(kicad_pcb
	(version 20241229)
	(generator "pcbnew")
	(generator_version "9.0")
	(general
		(thickness 1.292)
		(legacy_teardrops no)
	)
	(paper "A4")
	(title_block
		(title "LPDDR5 Testbed")
		(date "2023-12-19")
		(rev "1.0.0")
	)
	(layers
		(0 "F.Cu" signal)
		(4 "In1.Cu" power)
		(6 "In2.Cu" power)
		(8 "In3.Cu" signal)
		(10 "In4.Cu" signal)
		(2 "B.Cu" signal)
		(9 "F.Adhes" user "F.Adhesive")
		(11 "B.Adhes" user "B.Adhesive")
		(13 "F.Paste" user)
		(15 "B.Paste" user)
		(5 "F.SilkS" user "F.Silkscreen")
		(7 "B.SilkS" user "B.Silkscreen")
		(1 "F.Mask" user)
		(3 "B.Mask" user)
		(17 "Dwgs.User" user "User.Drawings")
		(19 "Cmts.User" user "User.Comments")
		(21 "Eco1.User" user "User.Eco1")
		(23 "Eco2.User" user "User.Eco2")
		(25 "Edge.Cuts" user)
		(27 "Margin" user)
		(31 "F.CrtYd" user "F.Courtyard")
		(29 "B.CrtYd" user "B.Courtyard")
		(35 "F.Fab" user)
		(33 "B.Fab" user)
	)
	(setup
		(stackup
			(layer "F.SilkS"
				(type "Top Silk Screen")
				(color "White")
			)
			(layer "F.Paste"
				(type "Top Solder Paste")
			)
			(layer "F.Mask"
				(type "Top Solder Mask")
				(color "Black")
				(thickness 0.01)
			)
			(layer "F.Cu"
				(type "copper")
				(thickness 0.035)
			)
			(layer "dielectric 1"
				(type "prepreg")
				(thickness 0.11)
				(material "PR2116")
				(epsilon_r 4.29)
				(loss_tangent 0.02)
			)
			(layer "In1.Cu"
				(type "copper")
				(thickness 0.018)
			)
			(layer "dielectric 2"
				(type "core")
				(thickness 0.4)
				(material "FR4")
				(epsilon_r 4.29)
				(loss_tangent 0.02)
			)
			(layer "In2.Cu"
				(type "copper")
				(thickness 0.018)
			)
			(layer "dielectric 3"
				(type "prepreg")
				(thickness 0.11)
				(material "PR2116")
				(epsilon_r 4.29)
				(loss_tangent 0.02)
			)
			(layer "In3.Cu"
				(type "copper")
				(thickness 0.018)
			)
			(layer "dielectric 4"
				(type "core")
				(thickness 0.4)
				(material "FR4")
				(epsilon_r 4.29)
				(loss_tangent 0.02)
			)
			(layer "In4.Cu"
				(type "copper")
				(thickness 0.018)
			)
			(layer "dielectric 5"
				(type "prepreg")
				(thickness 0.11)
				(material "PR2116")
				(epsilon_r 4.29)
				(loss_tangent 0.02)
			)
			(layer "B.Cu"
				(type "copper")
				(thickness 0.035)
			)
			(layer "B.Mask"
				(type "Bottom Solder Mask")
				(color "Black")
				(thickness 0.01)
			)
			(layer "B.Paste"
				(type "Bottom Solder Paste")
			)
			(layer "B.SilkS"
				(type "Bottom Silk Screen")
				(color "White")
			)
			(copper_finish "None")
			(dielectric_constraints yes)
		)
		(pad_to_mask_clearance 0.05)
		(allow_soldermask_bridges_in_footprints no)
		(tenting front back)
		(pcbplotparams
			(layerselection 0x00000000_00000000_55555555_5755f5ff)
			(plot_on_all_layers_selection 0x00000000_00000000_00000000_00000000)
			(disableapertmacros no)
			(usegerberextensions no)
			(usegerberattributes yes)
			(usegerberadvancedattributes yes)
			(creategerberjobfile yes)
			(dashed_line_dash_ratio 12.000000)
			(dashed_line_gap_ratio 3.000000)
			(svgprecision 6)
			(plotframeref no)
			(mode 1)
			(useauxorigin no)
			(hpglpennumber 1)
			(hpglpenspeed 20)
			(hpglpendiameter 15.000000)
			(pdf_front_fp_property_popups yes)
			(pdf_back_fp_property_popups yes)
			(pdf_metadata yes)
			(pdf_single_document no)
			(dxfpolygonmode yes)
			(dxfimperialunits yes)
			(dxfusepcbnewfont yes)
			(psnegative no)
			(psa4output no)
			(plot_black_and_white yes)
			(sketchpadsonfab no)
			(plotpadnumbers no)
			(hidednponfab no)
			(sketchdnponfab yes)
			(crossoutdnponfab yes)
			(subtractmaskfromsilk no)
			(outputformat 1)
			(mirror no)
			(drillshape 0)
			(scaleselection 1)
			(outputdirectory "./fab")
		)
	)
	(net 0 "")
	(net 1 "+1V1")
	(net 2 "unconnected-(U1-PadA14)")
	(net 3 "unconnected-(U1-PadA15)")
	(net 4 "+0V5")
	(net 5 "+5V")
	(net 6 "Net-(C13-Pad2)")
	(net 7 "/Power supply/VOUT1")
	(net 8 "/Power supply/VOUT2")
	(net 9 "/Power supply/VOUT3")
	(net 10 "/Power supply/VOUT4")
	(net 11 "/Power supply/VOUT")
	(net 12 "+0V9")
	(net 13 "+1V05")
	(net 14 "GND")
	(net 15 "/Power supply/3.3V_QWIIC")
	(net 16 "Net-(D2-Pad1)")
	(net 17 "Net-(D2-Pad2)")
	(net 18 "/SODIMM/HSCL")
	(net 19 "/SODIMM/HSDA")
	(net 20 "/Power supply/PWR_EN")
	(net 21 "unconnected-(U1-PadA1)")
	(net 22 "unconnected-(U1-PadA2)")
	(net 23 "unconnected-(U1-PadAA14)")
	(net 24 "unconnected-(U1-PadAA15)")
	(net 25 "unconnected-(U1-PadB15)")
	(net 26 "unconnected-(U1-PadAA1)")
	(net 27 "unconnected-(U1-PadAA2)")
	(net 28 "unconnected-(U1-PadB1)")
	(net 29 "unconnected-(U1-PadJ4)")
	(net 30 "unconnected-(U1-PadJ6)")
	(net 31 "unconnected-(U1-PadP1)")
	(net 32 "unconnected-(U1-PadP15)")
	(net 33 "Net-(J1-Pad130)")
	(net 34 "/SODIMM/~{RESET}")
	(net 35 "+1V8")
	(net 36 "unconnected-(U1-PadY1)")
	(net 37 "unconnected-(U1-PadY15)")
	(net 38 "/Power supply/I2C.SDA")
	(net 39 "/Power supply/I2C.SCL")
	(net 40 "/LPDDR5/~{RESET}")
	(net 41 "/Power supply/PWRGD")
	(net 42 "unconnected-(J1-Pad5)")
	(net 43 "/LPDDR5/LPDDR5_A.CS0")
	(net 44 "/LPDDR5/LPDDR5_A.CS1")
	(net 45 "/LPDDR5/LPDDR5_A.WCK0_P")
	(net 46 "/LPDDR5/LPDDR5_A.WCK0_N")
	(net 47 "/LPDDR5/LPDDR5_A.WCK1_N")
	(net 48 "/LPDDR5/LPDDR5_A.WCK1_P")
	(net 49 "/LPDDR5/LPDDR5_A.CK_P")
	(net 50 "/LPDDR5/LPDDR5_A.CK_N")
	(net 51 "unconnected-(POT1-Pad1)")
	(net 52 "Net-(POT1-Pad2)")
	(net 53 "Net-(POT1-Pad3)")
	(net 54 "/LPDDR5/LPDDR5_A.CA3")
	(net 55 "/LPDDR5/LPDDR5_A.CA6")
	(net 56 "/LPDDR5/LPDDR5_A.CA5")
	(net 57 "/LPDDR5/LPDDR5_A.CA0")
	(net 58 "/LPDDR5/LPDDR5_A.CA1")
	(net 59 "/LPDDR5/LPDDR5_A.CA2")
	(net 60 "/LPDDR5/LPDDR5_A.CA4")
	(net 61 "Net-(R29-Pad2)")
	(net 62 "unconnected-(J1-Pad95)")
	(net 63 "unconnected-(J1-Pad96)")
	(net 64 "unconnected-(J1-Pad99)")
	(net 65 "unconnected-(J1-Pad100)")
	(net 66 "unconnected-(J1-Pad102)")
	(net 67 "unconnected-(J1-Pad103)")
	(net 68 "unconnected-(J1-Pad108)")
	(net 69 "Net-(R32-Pad2)")
	(net 70 "/Power supply/FB1")
	(net 71 "/Power supply/FB2")
	(net 72 "/Power supply/FB3")
	(net 73 "/Power supply/FB4")
	(net 74 "unconnected-(J1-Pad120)")
	(net 75 "unconnected-(J1-Pad121)")
	(net 76 "unconnected-(J1-Pad122)")
	(net 77 "unconnected-(J1-Pad125)")
	(net 78 "unconnected-(J1-Pad126)")
	(net 79 "unconnected-(J1-Pad127)")
	(net 80 "unconnected-(J1-Pad128)")
	(net 81 "unconnected-(J1-Pad132)")
	(net 82 "unconnected-(J1-Pad134)")
	(net 83 "unconnected-(J1-Pad138)")
	(net 84 "unconnected-(J1-Pad140)")
	(net 85 "unconnected-(J1-Pad143)")
	(net 86 "unconnected-(J1-Pad144)")
	(net 87 "unconnected-(J1-Pad145)")
	(net 88 "unconnected-(J1-Pad146)")
	(net 89 "unconnected-(J1-Pad149)")
	(net 90 "unconnected-(J1-Pad150)")
	(net 91 "unconnected-(J1-Pad151)")
	(net 92 "Net-(R69-Pad2)")
	(net 93 "unconnected-(J1-Pad168)")
	(net 94 "unconnected-(J1-Pad169)")
	(net 95 "unconnected-(J1-Pad171)")
	(net 96 "unconnected-(J1-Pad172)")
	(net 97 "unconnected-(J1-Pad175)")
	(net 98 "unconnected-(J1-Pad176)")
	(net 99 "/LPDDR5/LPDDR5_B.CA3")
	(net 100 "/LPDDR5/LPDDR5_B.CA6")
	(net 101 "/LPDDR5/LPDDR5_B.CA5")
	(net 102 "/LPDDR5/LPDDR5_B.CA0")
	(net 103 "/LPDDR5/LPDDR5_B.CA1")
	(net 104 "/LPDDR5/LPDDR5_B.CA2")
	(net 105 "/LPDDR5/LPDDR5_B.CA4")
	(net 106 "/LPDDR5/LPDDR5_B.CS0")
	(net 107 "/LPDDR5/LPDDR5_B.CS1")
	(net 108 "/LPDDR5/LPDDR5_B.WCK0_P")
	(net 109 "/LPDDR5/LPDDR5_B.WCK0_N")
	(net 110 "/LPDDR5/LPDDR5_B.WCK1_N")
	(net 111 "/LPDDR5/LPDDR5_B.WCK1_P")
	(net 112 "/LPDDR5/LPDDR5_B.CK_P")
	(net 113 "/LPDDR5/LPDDR5_B.CK_N")
	(net 114 "unconnected-(U8-Pad11)")
	(net 115 "unconnected-(U8-Pad12)")
	(net 116 "unconnected-(J1-Pad2)")
	(net 117 "Net-(C12-Pad2)")
	(net 118 "/SODIMM/LPDDR5_IN_A.DMI1")
	(net 119 "/SODIMM/LPDDR5_IN_A.DMI0")
	(net 120 "/SODIMM/LPDDR5_IN_B.DMI0")
	(net 121 "/SODIMM/LPDDR5_IN_B.DMI1")
	(net 122 "/SODIMM/LPDDR5_IN_B.DQ0")
	(net 123 "/SODIMM/LPDDR5_IN_B.DQ1")
	(net 124 "/SODIMM/LPDDR5_IN_B.DQ2")
	(net 125 "/SODIMM/LPDDR5_IN_B.DQ3")
	(net 126 "/SODIMM/LPDDR5_IN_B.WCK0_P")
	(net 127 "/SODIMM/LPDDR5_IN_B.WCK0_N")
	(net 128 "/LPDDR5/LPDDR5_A.DQ8")
	(net 129 "/SODIMM/LPDDR5_IN_B.DQ4")
	(net 130 "/SODIMM/LPDDR5_IN_B.DQ5")
	(net 131 "/SODIMM/LPDDR5_IN_B.DQ6")
	(net 132 "/SODIMM/LPDDR5_IN_B.DQ7")
	(net 133 "/SODIMM/LPDDR5_IN_B.DQ15")
	(net 134 "/SODIMM/LPDDR5_IN_B.DQ14")
	(net 135 "/SODIMM/LPDDR5_IN_B.DQ13")
	(net 136 "/SODIMM/LPDDR5_IN_B.DQ12")
	(net 137 "/SODIMM/LPDDR5_IN_B.WCK1_P")
	(net 138 "/SODIMM/LPDDR5_IN_B.WCK1_N")
	(net 139 "/LPDDR5/LPDDR5_A.DQ10")
	(net 140 "/SODIMM/LPDDR5_IN_B.DQ11")
	(net 141 "/SODIMM/LPDDR5_IN_B.DQ10")
	(net 142 "/SODIMM/LPDDR5_IN_B.DQ9")
	(net 143 "/SODIMM/LPDDR5_IN_B.DQ8")
	(net 144 "/SODIMM/LPDDR5_IN_B.CS1")
	(net 145 "/SODIMM/LPDDR5_IN_B.CA0")
	(net 146 "/SODIMM/LPDDR5_IN_B.CA1")
	(net 147 "/SODIMM/LPDDR5_IN_B.CS0")
	(net 148 "/SODIMM/LPDDR5_IN_B.CA2")
	(net 149 "/SODIMM/LPDDR5_IN_B.CA3")
	(net 150 "/SODIMM/LPDDR5_IN_B.CA4")
	(net 151 "/SODIMM/LPDDR5_IN_B.CA5")
	(net 152 "/SODIMM/LPDDR5_IN_B.CA6")
	(net 153 "/SODIMM/LPDDR5_IN_B.CK_N")
	(net 154 "/SODIMM/LPDDR5_IN_B.CK_P")
	(net 155 "/SODIMM/LPDDR5_IN_A.CK_N")
	(net 156 "/SODIMM/LPDDR5_IN_A.CK_P")
	(net 157 "/SODIMM/LPDDR5_IN_A.CA6")
	(net 158 "/SODIMM/LPDDR5_IN_A.CA5")
	(net 159 "/SODIMM/LPDDR5_IN_A.CA4")
	(net 160 "/SODIMM/LPDDR5_IN_A.CA3")
	(net 161 "/SODIMM/LPDDR5_IN_A.CA2")
	(net 162 "/SODIMM/LPDDR5_IN_A.CS1")
	(net 163 "/SODIMM/LPDDR5_IN_A.CA1")
	(net 164 "/SODIMM/LPDDR5_IN_A.CA0")
	(net 165 "/SODIMM/LPDDR5_IN_A.CS0")
	(net 166 "/SODIMM/LPDDR5_IN_A.DQ0")
	(net 167 "/SODIMM/LPDDR5_IN_A.DQ2")
	(net 168 "/SODIMM/LPDDR5_IN_A.DQ1")
	(net 169 "/SODIMM/LPDDR5_IN_A.DQ3")
	(net 170 "/SODIMM/LPDDR5_IN_A.WCK0_P")
	(net 171 "/SODIMM/LPDDR5_IN_A.WCK0_N")
	(net 172 "/LPDDR5/LPDDR5_A.DQ9")
	(net 173 "/SODIMM/LPDDR5_IN_A.DQ7")
	(net 174 "/SODIMM/LPDDR5_IN_A.DQ6")
	(net 175 "/SODIMM/LPDDR5_IN_A.DQ4")
	(net 176 "/SODIMM/LPDDR5_IN_A.DQ5")
	(net 177 "/SODIMM/LPDDR5_IN_A.DQ15")
	(net 178 "/SODIMM/LPDDR5_IN_A.DQ12")
	(net 179 "/SODIMM/LPDDR5_IN_A.DQ13")
	(net 180 "/SODIMM/LPDDR5_IN_A.DQ14")
	(net 181 "/SODIMM/LPDDR5_IN_A.WCK1_P")
	(net 182 "/SODIMM/LPDDR5_IN_A.WCK1_N")
	(net 183 "/LPDDR5/LPDDR5_A.DQ11")
	(net 184 "/SODIMM/LPDDR5_IN_A.DQ11")
	(net 185 "/SODIMM/LPDDR5_IN_A.DQ10")
	(net 186 "/SODIMM/LPDDR5_IN_A.DQ9")
	(net 187 "/SODIMM/LPDDR5_IN_A.DQ8")
	(net 188 "/LPDDR5/LPDDR5_A.RDQS1_N")
	(net 189 "/LPDDR5/LPDDR5_A.RDQS1_P")
	(net 190 "/LPDDR5/LPDDR5_A.DMI1")
	(net 191 "/LPDDR5/LPDDR5_A.DQ15")
	(net 192 "/LPDDR5/LPDDR5_A.DQ14")
	(net 193 "/LPDDR5/LPDDR5_A.DQ12")
	(net 194 "/LPDDR5/LPDDR5_A.DQ13")
	(net 195 "/LPDDR5/LPDDR5_A.DQ7")
	(net 196 "/LPDDR5/LPDDR5_A.DQ6")
	(net 197 "/LPDDR5/LPDDR5_A.DQ5")
	(net 198 "/LPDDR5/LPDDR5_A.DQ4")
	(net 199 "/LPDDR5/LPDDR5_A.RDQS0_N")
	(net 200 "/LPDDR5/LPDDR5_A.RDQS0_P")
	(net 201 "/LPDDR5/LPDDR5_A.DMI0")
	(net 202 "/LPDDR5/LPDDR5_A.DQ3")
	(net 203 "/LPDDR5/LPDDR5_A.DQ2")
	(net 204 "/LPDDR5/LPDDR5_A.DQ1")
	(net 205 "/LPDDR5/LPDDR5_A.DQ0")
	(net 206 "/LPDDR5/LPDDR5_B.DQ8")
	(net 207 "/LPDDR5/LPDDR5_B.DQ9")
	(net 208 "/LPDDR5/LPDDR5_B.DQ10")
	(net 209 "/LPDDR5/LPDDR5_B.DQ11")
	(net 210 "/LPDDR5/LPDDR5_B.RDQS1_N")
	(net 211 "/LPDDR5/LPDDR5_B.RDQS1_P")
	(net 212 "/LPDDR5/LPDDR5_B.DMI0")
	(net 213 "/LPDDR5/LPDDR5_B.DQ12")
	(net 214 "/LPDDR5/LPDDR5_B.DQ13")
	(net 215 "/LPDDR5/LPDDR5_B.DQ14")
	(net 216 "/LPDDR5/LPDDR5_B.DQ15")
	(net 217 "/LPDDR5/LPDDR5_B.DQ7")
	(net 218 "/LPDDR5/LPDDR5_B.DQ6")
	(net 219 "/LPDDR5/LPDDR5_B.DQ5")
	(net 220 "/LPDDR5/LPDDR5_B.DQ4")
	(net 221 "/LPDDR5/LPDDR5_B.RDQS0_N")
	(net 222 "/LPDDR5/LPDDR5_B.RDQS0_P")
	(net 223 "/LPDDR5/LPDDR5_B.DMI1")
	(net 224 "/LPDDR5/LPDDR5_B.DQ3")
	(net 225 "/LPDDR5/LPDDR5_B.DQ2")
	(net 226 "/LPDDR5/LPDDR5_B.DQ1")
	(net 227 "/LPDDR5/LPDDR5_B.DQ0")
	(net 228 "/Power supply/DCDC_PWRGD")
	(footprint "antmicro-footprints:TP_SMD_0.75mm"
		(layer "F.Cu")
		(at 160.8 69.5)
		(property "Reference" "TP8"
			(at -2.6 1.1 0)
			(unlocked yes)
			(layer "F.SilkS")
			(effects
				(font
					(size 0.7 0.7)
					(thickness 0.15)
				)
				(justify left bottom)
			)
		)
		(property "Value" "TP_0.75mm_SMD"
			(at 0 1.2 0)
			(layer "F.Fab")
			(effects
				(font
					(size 0.7 0.7)
					(thickness 0.15)
				)
				(justify left bottom)
			)
		)
		(property "Author" "Antmicro"
			(at 0 0 0)
			(layer "F.Fab")
			(hide yes)
			(effects
				(font
					(size 1 1)
					(thickness 0.15)
				)
			)
		)
		(property "License" "Apache-2.0"
			(at 0 0 0)
			(layer "F.Fab")
			(hide yes)
			(effects
				(font
					(size 1 1)
					(thickness 0.15)
				)
			)
		)
		(property "MPN" ""
			(at 0 0 0)
			(layer "F.Fab")
			(hide yes)
			(effects
				(font
					(size 1 1)
					(thickness 0.15)
				)
			)
		)
		(property "Manufacturer" ""
			(at 0 0 0)
			(layer "F.Fab")
			(hide yes)
			(effects
				(font
					(size 1 1)
					(thickness 0.15)
				)
			)
		)
		(sheetname "Power supply")
		(sheetfile "power_supply.kicad_sch")
		(attr exclude_from_pos_files)
		(pad "1" smd circle
			(at 0 0)
			(size 0.75 0.75)
			(layers "F.Cu" "F.Mask")
			(net 11 "/Power supply/VOUT")
			(pinfunction "1")
			(pintype "passive")
		)
	)
	(footprint "antmicro-footprints:R_Array_4x0402_Panasonic_EXB28V"
		(layer "F.Cu")
		(at 155.7 93.85)
		(property "Reference" "R63"
			(at -1.301 -1.45 0)
			(unlocked yes)
			(layer "F.SilkS")
			(effects
				(font
					(size 0.7 0.7)
					(thickness 0.15)
				)
				(justify left bottom)
			)
		)
		(property "Value" "R_4x100R_0402_array"
			(at -1.5 2 0)
			(layer "F.Fab")
			(effects
				(font
					(size 0.7 0.7)
					(thickness 0.15)
				)
				(justify left bottom)
			)
		)
		(property "Author" "Antmicro"
			(at 0 0 0)
			(layer "F.Fab")
			(hide yes)
			(effects
				(font
					(size 1 1)
					(thickness 0.15)
				)
			)
		)
		(property "License" "Apache-2.0"
			(at 0 0 0)
			(layer "F.Fab")
			(hide yes)
			(effects
				(font
					(size 1 1)
					(thickness 0.15)
				)
			)
		)
		(property "MPN" "EXB-28V101JX"
			(at 0 0 0)
			(layer "F.Fab")
			(hide yes)
			(effects
				(font
					(size 1 1)
					(thickness 0.15)
				)
			)
		)
		(property "Manufacturer" "Panasonic"
			(at 0 0 0)
			(layer "F.Fab")
			(hide yes)
			(effects
				(font
					(size 1 1)
					(thickness 0.15)
				)
			)
		)
		(property "Val" "R_4x100R_0402"
			(at 0 0 0)
			(layer "F.Fab")
			(hide yes)
			(effects
				(font
					(size 1 1)
					(thickness 0.15)
				)
			)
		)
		(sheetname "Translators1")
		(sheetfile "translators.kicad_sch")
		(attr smd)
		(fp_line
			(start -1.25 -0.5)
			(end -1.25 0.498)
			(stroke
				(width 0.15)
				(type solid)
			)
			(layer "F.SilkS")
		)
		(fp_line
			(start 1.25 0.499)
			(end 1.25 -0.499)
			(stroke
				(width 0.15)
				(type solid)
			)
			(layer "F.SilkS")
		)
		(fp_rect
			(start -1.25 -0.8)
			(end 1.25 0.8)
			(stroke
				(width 0.05)
				(type solid)
			)
			(fill no)
			(layer "F.CrtYd")
		)
		(fp_line
			(start -1 -0.5)
			(end 0.998 -0.5)
			(stroke
				(width 0.15)
				(type solid)
			)
			(layer "F.Fab")
		)
		(fp_line
			(start -1 0.498)
			(end -1 -0.5)
			(stroke
				(width 0.15)
				(type solid)
			)
			(layer "F.Fab")
		)
		(fp_line
			(start 0.998 -0.5)
			(end 0.998 0.498)
			(stroke
				(width 0.15)
				(type solid)
			)
			(layer "F.Fab")
		)
		(fp_line
			(start 0.998 0.498)
			(end -1 0.498)
			(stroke
				(width 0.15)
				(type solid)
			)
			(layer "F.Fab")
		)
		(pad "1" smd roundrect
			(at -0.8875 0.45)
			(size 0.525 0.5)
			(layers "F.Cu" "F.Mask" "F.Paste")
			(roundrect_rratio 0.25)
			(net 133 "/SODIMM/LPDDR5_IN_B.DQ15")
			(pinfunction "R1.1")
			(pintype "passive")
		)
		(pad "2" smd roundrect
			(at -0.25 0.45)
			(size 0.25 0.5)
			(layers "F.Cu" "F.Mask" "F.Paste")
			(roundrect_rratio 0.25)
			(net 134 "/SODIMM/LPDDR5_IN_B.DQ14")
			(pinfunction "R2.1")
			(pintype "passive")
		)
		(pad "3" smd roundrect
			(at 0.25 0.45)
			(size 0.25 0.5)
			(layers "F.Cu" "F.Mask" "F.Paste")
			(roundrect_rratio 0.25)
			(net 136 "/SODIMM/LPDDR5_IN_B.DQ12")
			(pinfunction "R3.1")
			(pintype "passive")
		)
		(pad "4" smd roundrect
			(at 0.8875 0.45)
			(size 0.525 0.5)
			(layers "F.Cu" "F.Mask" "F.Paste")
			(roundrect_rratio 0.25)
			(net 135 "/SODIMM/LPDDR5_IN_B.DQ13")
			(pinfunction "R4.1")
			(pintype "passive")
		)
		(pad "5" smd roundrect
			(at 0.8875 -0.45)
			(size 0.525 0.5)
			(layers "F.Cu" "F.Mask" "F.Paste")
			(roundrect_rratio 0.25)
			(net 214 "/LPDDR5/LPDDR5_B.DQ13")
			(pinfunction "R4.2")
			(pintype "passive")
		)
		(pad "6" smd roundrect
			(at 0.25 -0.45)
			(size 0.25 0.5)
			(layers "F.Cu" "F.Mask" "F.Paste")
			(roundrect_rratio 0.25)
			(net 213 "/LPDDR5/LPDDR5_B.DQ12")
			(pinfunction "R3.2")
			(pintype "passive")
		)
		(pad "7" smd roundrect
			(at -0.25 -0.45)
			(size 0.25 0.5)
			(layers "F.Cu" "F.Mask" "F.Paste")
			(roundrect_rratio 0.25)
			(net 215 "/LPDDR5/LPDDR5_B.DQ14")
			(pinfunction "R2.2")
			(pintype "passive")
		)
		(pad "8" smd roundrect
			(at -0.8875 -0.45)
			(size 0.525 0.5)
			(layers "F.Cu" "F.Mask" "F.Paste")
			(roundrect_rratio 0.25)
			(net 216 "/LPDDR5/LPDDR5_B.DQ15")
			(pinfunction "R1.2")
			(pintype "passive")
		)
	)
	(footprint "antmicro-footprints:C_0402_1005Metric"
		(layer "F.Cu")
		(at 144.225 81 -90)
		(descr "Capacitor SMD 0402")
		(tags "capacitor SMD 0402")
		(property "Reference" "C56"
			(at 1 -0.325 90)
			(unlocked yes)
			(layer "F.SilkS")
			(effects
				(font
					(size 0.7 0.7)
					(thickness 0.15)
				)
				(justify right bottom)
			)
		)
		(property "Value" "C_4u7_0402"
			(at -1.022927 2.155213 90)
			(layer "F.Fab")
			(effects
				(font
					(size 0.7 0.7)
					(thickness 0.15)
				)
				(justify right bottom)
			)
		)
		(property "Author" "Antmicro"
			(at 63.225 225.225 0)
			(layer "F.Fab")
			(hide yes)
			(effects
				(font
					(size 1 1)
					(thickness 0.15)
				)
			)
		)
		(property "Dielectric" ""
			(at 63.225 225.225 0)
			(layer "F.Fab")
			(hide yes)
			(effects
				(font
					(size 1 1)
					(thickness 0.15)
				)
			)
		)
		(property "License" "Apache-2.0"
			(at 63.225 225.225 0)
			(layer "F.Fab")
			(hide yes)
			(effects
				(font
					(size 1 1)
					(thickness 0.15)
				)
			)
		)
		(property "MPN" "GRM155R61A475MEAAD"
			(at 63.225 225.225 0)
			(layer "F.Fab")
			(hide yes)
			(effects
				(font
					(size 1 1)
					(thickness 0.15)
				)
			)
		)
		(property "Manufacturer" "Murata"
			(at 63.225 225.225 0)
			(layer "F.Fab")
			(hide yes)
			(effects
				(font
					(size 1 1)
					(thickness 0.15)
				)
			)
		)
		(property "Val" "4u7"
			(at 63.225 225.225 0)
			(layer "F.Fab")
			(hide yes)
			(effects
				(font
					(size 1 1)
					(thickness 0.15)
				)
			)
		)
		(property "Voltage" ""
			(at 63.225 225.225 0)
			(layer "F.Fab")
			(hide yes)
			(effects
				(font
					(size 1 1)
					(thickness 0.15)
				)
			)
		)
		(sheetname "LPDDR5")
		(sheetfile "lpddr5.kicad_sch")
		(attr smd)
		(fp_rect
			(start -0.9659 -0.481258)
			(end 0.9649 0.458742)
			(stroke
				(width 0.05)
				(type solid)
			)
			(fill no)
			(layer "F.CrtYd")
		)
		(fp_line
			(start -0.499 0.248)
			(end -0.499 -0.25)
			(stroke
				(width 0.15)
				(type solid)
			)
			(layer "F.Fab")
		)
		(fp_line
			(start 0.499 0.248)
			(end -0.499 0.248)
			(stroke
				(width 0.15)
				(type solid)
			)
			(layer "F.Fab")
		)
		(fp_line
			(start -0.499 -0.25)
			(end 0.499 -0.25)
			(stroke
				(width 0.15)
				(type solid)
			)
			(layer "F.Fab")
		)
		(fp_line
			(start 0.499 -0.25)
			(end 0.499 0.248)
			(stroke
				(width 0.15)
				(type solid)
			)
			(layer "F.Fab")
		)
		(pad "1" smd roundrect
			(at -0.484 0 270)
			(size 0.59 0.64)
			(layers "F.Cu" "F.Mask" "F.Paste")
			(roundrect_rratio 0.25)
			(net 14 "GND")
			(pintype "passive")
		)
		(pad "2" smd roundrect
			(at 0.484 0 270)
			(size 0.59 0.64)
			(layers "F.Cu" "F.Mask" "F.Paste")
			(roundrect_rratio 0.25)
			(net 12 "+0V9")
			(pintype "passive")
		)
	)
	(footprint "antmicro-footprints:TP_SMD_0.75mm"
		(layer "F.Cu")
		(at 103.6 62.95)
		(property "Reference" "TP4"
			(at -3.125 0.225 0)
			(unlocked yes)
			(layer "F.SilkS")
			(effects
				(font
					(size 0.7 0.7)
					(thickness 0.15)
				)
				(justify left bottom)
			)
		)
		(property "Value" "TP_0.75mm_SMD"
			(at 0 1.2 0)
			(layer "F.Fab")
			(effects
				(font
					(size 0.7 0.7)
					(thickness 0.15)
				)
				(justify left bottom)
			)
		)
		(property "Author" "Antmicro"
			(at 0 0 0)
			(layer "F.Fab")
			(hide yes)
			(effects
				(font
					(size 1 1)
					(thickness 0.15)
				)
			)
		)
		(property "License" "Apache-2.0"
			(at 0 0 0)
			(layer "F.Fab")
			(hide yes)
			(effects
				(font
					(size 1 1)
					(thickness 0.15)
				)
			)
		)
		(property "MPN" ""
			(at 0 0 0)
			(layer "F.Fab")
			(hide yes)
			(effects
				(font
					(size 1 1)
					(thickness 0.15)
				)
			)
		)
		(property "Manufacturer" ""
			(at 0 0 0)
			(layer "F.Fab")
			(hide yes)
			(effects
				(font
					(size 1 1)
					(thickness 0.15)
				)
			)
		)
		(sheetname "Power supply")
		(sheetfile "power_supply.kicad_sch")
		(attr exclude_from_pos_files)
		(pad "1" smd circle
			(at 0 0)
			(size 0.75 0.75)
			(layers "F.Cu" "F.Mask")
			(net 7 "/Power supply/VOUT1")
			(pinfunction "1")
			(pintype "passive")
		)
	)
	(footprint "antmicro-footprints:C_0402_1005Metric"
		(layer "F.Cu")
		(at 125.575 80.95 -90)
		(descr "Capacitor SMD 0402")
		(tags "capacitor SMD 0402")
		(property "Reference" "C59"
			(at 1.05 -0.325 90)
			(unlocked yes)
			(layer "F.SilkS")
			(effects
				(font
					(size 0.7 0.7)
					(thickness 0.15)
				)
				(justify right bottom)
			)
		)
		(property "Value" "C_4u7_0402"
			(at -1.022927 2.155213 90)
			(layer "F.Fab")
			(effects
				(font
					(size 0.7 0.7)
					(thickness 0.15)
				)
				(justify right bottom)
			)
		)
		(property "Author" "Antmicro"
			(at 44.625 206.525 0)
			(layer "F.Fab")
			(hide yes)
			(effects
				(font
					(size 1 1)
					(thickness 0.15)
				)
			)
		)
		(property "Dielectric" ""
			(at 44.625 206.525 0)
			(layer "F.Fab")
			(hide yes)
			(effects
				(font
					(size 1 1)
					(thickness 0.15)
				)
			)
		)
		(property "License" "Apache-2.0"
			(at 44.625 206.525 0)
			(layer "F.Fab")
			(hide yes)
			(effects
				(font
					(size 1 1)
					(thickness 0.15)
				)
			)
		)
		(property "MPN" "GRM155R61A475MEAAD"
			(at 44.625 206.525 0)
			(layer "F.Fab")
			(hide yes)
			(effects
				(font
					(size 1 1)
					(thickness 0.15)
				)
			)
		)
		(property "Manufacturer" "Murata"
			(at 44.625 206.525 0)
			(layer "F.Fab")
			(hide yes)
			(effects
				(font
					(size 1 1)
					(thickness 0.15)
				)
			)
		)
		(property "Val" "4u7"
			(at 44.625 206.525 0)
			(layer "F.Fab")
			(hide yes)
			(effects
				(font
					(size 1 1)
					(thickness 0.15)
				)
			)
		)
		(property "Voltage" ""
			(at 44.625 206.525 0)
			(layer "F.Fab")
			(hide yes)
			(effects
				(font
					(size 1 1)
					(thickness 0.15)
				)
			)
		)
		(sheetname "LPDDR5")
		(sheetfile "lpddr5.kicad_sch")
		(attr smd)
		(fp_rect
			(start -0.9659 -0.481258)
			(end 0.9649 0.458742)
			(stroke
				(width 0.05)
				(type solid)
			)
			(fill no)
			(layer "F.CrtYd")
		)
		(fp_line
			(start -0.499 0.248)
			(end -0.499 -0.25)
			(stroke
				(width 0.15)
				(type solid)
			)
			(layer "F.Fab")
		)
		(fp_line
			(start 0.499 0.248)
			(end -0.499 0.248)
			(stroke
				(width 0.15)
				(type solid)
			)
			(layer "F.Fab")
		)
		(fp_line
			(start -0.499 -0.25)
			(end 0.499 -0.25)
			(stroke
				(width 0.15)
				(type solid)
			)
			(layer "F.Fab")
		)
		(fp_line
			(start 0.499 -0.25)
			(end 0.499 0.248)
			(stroke
				(width 0.15)
				(type solid)
			)
			(layer "F.Fab")
		)
		(pad "1" smd roundrect
			(at -0.484 0 270)
			(size 0.59 0.64)
			(layers "F.Cu" "F.Mask" "F.Paste")
			(roundrect_rratio 0.25)
			(net 14 "GND")
			(pintype "passive")
		)
		(pad "2" smd roundrect
			(at 0.484 0 270)
			(size 0.59 0.64)
			(layers "F.Cu" "F.Mask" "F.Paste")
			(roundrect_rratio 0.25)
			(net 12 "+0V9")
			(pintype "passive")
		)
	)
	(footprint "antmicro-footprints:R_Array_4x0402_Panasonic_EXB28V"
		(layer "F.Cu")
		(at 130.3 93.8)
		(property "Reference" "R8"
			(at -0.7 -1.4 0)
			(unlocked yes)
			(layer "F.SilkS")
			(effects
				(font
					(size 0.7 0.7)
					(thickness 0.15)
				)
				(justify left bottom)
			)
		)
		(property "Value" "R_4x100R_0402_array"
			(at -1.5 2 0)
			(layer "F.Fab")
			(effects
				(font
					(size 0.7 0.7)
					(thickness 0.15)
				)
				(justify left bottom)
			)
		)
		(property "Author" "Antmicro"
			(at 0 0 0)
			(layer "F.Fab")
			(hide yes)
			(effects
				(font
					(size 1 1)
					(thickness 0.15)
				)
			)
		)
		(property "License" "Apache-2.0"
			(at 0 0 0)
			(layer "F.Fab")
			(hide yes)
			(effects
				(font
					(size 1 1)
					(thickness 0.15)
				)
			)
		)
		(property "MPN" "EXB-28V101JX"
			(at 0 0 0)
			(layer "F.Fab")
			(hide yes)
			(effects
				(font
					(size 1 1)
					(thickness 0.15)
				)
			)
		)
		(property "Manufacturer" "Panasonic"
			(at 0 0 0)
			(layer "F.Fab")
			(hide yes)
			(effects
				(font
					(size 1 1)
					(thickness 0.15)
				)
			)
		)
		(property "Val" "R_4x100R_0402"
			(at 0 0 0)
			(layer "F.Fab")
			(hide yes)
			(effects
				(font
					(size 1 1)
					(thickness 0.15)
				)
			)
		)
		(sheetname "Translators")
		(sheetfile "translators.kicad_sch")
		(attr smd)
		(fp_line
			(start -1.25 -0.5)
			(end -1.25 0.498)
			(stroke
				(width 0.15)
				(type solid)
			)
			(layer "F.SilkS")
		)
		(fp_line
			(start 1.25 0.499)
			(end 1.25 -0.499)
			(stroke
				(width 0.15)
				(type solid)
			)
			(layer "F.SilkS")
		)
		(fp_rect
			(start -1.25 -0.8)
			(end 1.25 0.8)
			(stroke
				(width 0.05)
				(type solid)
			)
			(fill no)
			(layer "F.CrtYd")
		)
		(fp_line
			(start -1 -0.5)
			(end 0.998 -0.5)
			(stroke
				(width 0.15)
				(type solid)
			)
			(layer "F.Fab")
		)
		(fp_line
			(start -1 0.498)
			(end -1 -0.5)
			(stroke
				(width 0.15)
				(type solid)
			)
			(layer "F.Fab")
		)
		(fp_line
			(start 0.998 -0.5)
			(end 0.998 0.498)
			(stroke
				(width 0.15)
				(type solid)
			)
			(layer "F.Fab")
		)
		(fp_line
			(start 0.998 0.498)
			(end -1 0.498)
			(stroke
				(width 0.15)
				(type solid)
			)
			(layer "F.Fab")
		)
		(pad "1" smd roundrect
			(at -0.8875 0.45)
			(size 0.525 0.5)
			(layers "F.Cu" "F.Mask" "F.Paste")
			(roundrect_rratio 0.25)
			(net 161 "/SODIMM/LPDDR5_IN_A.CA2")
			(pinfunction "R1.1")
			(pintype "passive")
		)
		(pad "2" smd roundrect
			(at -0.25 0.45)
			(size 0.25 0.5)
			(layers "F.Cu" "F.Mask" "F.Paste")
			(roundrect_rratio 0.25)
			(net 160 "/SODIMM/LPDDR5_IN_A.CA3")
			(pinfunction "R2.1")
			(pintype "passive")
		)
		(pad "3" smd roundrect
			(at 0.25 0.45)
			(size 0.25 0.5)
			(layers "F.Cu" "F.Mask" "F.Paste")
			(roundrect_rratio 0.25)
			(net 159 "/SODIMM/LPDDR5_IN_A.CA4")
			(pinfunction "R3.1")
			(pintype "passive")
		)
		(pad "4" smd roundrect
			(at 0.8875 0.45)
			(size 0.525 0.5)
			(layers "F.Cu" "F.Mask" "F.Paste")
			(roundrect_rratio 0.25)
			(net 158 "/SODIMM/LPDDR5_IN_A.CA5")
			(pinfunction "R4.1")
			(pintype "passive")
		)
		(pad "5" smd roundrect
			(at 0.8875 -0.45)
			(size 0.525 0.5)
			(layers "F.Cu" "F.Mask" "F.Paste")
			(roundrect_rratio 0.25)
			(net 56 "/LPDDR5/LPDDR5_A.CA5")
			(pinfunction "R4.2")
			(pintype "passive")
		)
		(pad "6" smd roundrect
			(at 0.25 -0.45)
			(size 0.25 0.5)
			(layers "F.Cu" "F.Mask" "F.Paste")
			(roundrect_rratio 0.25)
			(net 60 "/LPDDR5/LPDDR5_A.CA4")
			(pinfunction "R3.2")
			(pintype "passive")
		)
		(pad "7" smd roundrect
			(at -0.25 -0.45)
			(size 0.25 0.5)
			(layers "F.Cu" "F.Mask" "F.Paste")
			(roundrect_rratio 0.25)
			(net 54 "/LPDDR5/LPDDR5_A.CA3")
			(pinfunction "R2.2")
			(pintype "passive")
		)
		(pad "8" smd roundrect
			(at -0.8875 -0.45)
			(size 0.525 0.5)
			(layers "F.Cu" "F.Mask" "F.Paste")
			(roundrect_rratio 0.25)
			(net 59 "/LPDDR5/LPDDR5_A.CA2")
			(pinfunction "R1.2")
			(pintype "passive")
		)
	)
	(footprint "antmicro-footprints:R_0402_1005Metric"
		(layer "F.Cu")
		(at 117.625 93.8 90)
		(descr "Resistor SMD 0402")
		(tags "resistor SMD 0402")
		(property "Reference" "R93"
			(at -3.1 0.375 90)
			(unlocked yes)
			(layer "F.SilkS")
			(effects
				(font
					(size 0.7 0.7)
					(thickness 0.15)
				)
				(justify left bottom)
			)
		)
		(property "Value" "R_100R_0402"
			(at -1.011843 1.772047 90)
			(layer "F.Fab")
			(effects
				(font
					(size 0.7 0.7)
					(thickness 0.15)
				)
				(justify left bottom)
			)
		)
		(property "Author" "Antmicro"
			(at 211.425 -23.825 0)
			(layer "F.Fab")
			(hide yes)
			(effects
				(font
					(size 1 1)
					(thickness 0.15)
				)
			)
		)
		(property "License" "Apache-2.0"
			(at 211.425 -23.825 0)
			(layer "F.Fab")
			(hide yes)
			(effects
				(font
					(size 1 1)
					(thickness 0.15)
				)
			)
		)
		(property "MPN" "CR0402-FX-1000GLF"
			(at 211.425 -23.825 0)
			(layer "F.Fab")
			(hide yes)
			(effects
				(font
					(size 1 1)
					(thickness 0.15)
				)
			)
		)
		(property "Manufacturer" "Bourns"
			(at 211.425 -23.825 0)
			(layer "F.Fab")
			(hide yes)
			(effects
				(font
					(size 1 1)
					(thickness 0.15)
				)
			)
		)
		(property "Tolerance" "1%"
			(at 211.425 -23.825 0)
			(layer "F.Fab")
			(hide yes)
			(effects
				(font
					(size 1 1)
					(thickness 0.15)
				)
			)
		)
		(property "Val" "100R"
			(at 211.425 -23.825 0)
			(layer "F.Fab")
			(hide yes)
			(effects
				(font
					(size 1 1)
					(thickness 0.15)
				)
			)
		)
		(sheetname "Translators")
		(sheetfile "translators.kicad_sch")
		(attr smd)
		(fp_rect
			(start -0.93 -0.47)
			(end 0.93 0.47)
			(stroke
				(width 0.05)
				(type solid)
			)
			(fill no)
			(layer "F.CrtYd")
		)
		(fp_rect
			(start -0.5 -0.25)
			(end 0.5 0.25)
			(stroke
				(width 0.15)
				(type solid)
			)
			(fill no)
			(layer "F.Fab")
		)
		(pad "1" smd roundrect
			(at -0.485 0 90)
			(size 0.59 0.64)
			(layers "F.Cu" "F.Mask" "F.Paste")
			(roundrect_rratio 0.25)
			(net 119 "/SODIMM/LPDDR5_IN_A.DMI0")
			(pintype "passive")
		)
		(pad "2" smd roundrect
			(at 0.485 0 90)
			(size 0.59 0.64)
			(layers "F.Cu" "F.Mask" "F.Paste")
			(roundrect_rratio 0.25)
			(net 201 "/LPDDR5/LPDDR5_A.DMI0")
			(pintype "passive")
		)
	)
	(footprint "antmicro-footprints:C_0603_1608Metric"
		(layer "F.Cu")
		(at 105.425 62.575 180)
		(descr "Capacitor SMD 0603")
		(tags "capacitor 0603")
		(property "Reference" "C16"
			(at -1.075 -1.325 0)
			(unlocked yes)
			(layer "F.SilkS")
			(effects
				(font
					(size 0.7 0.7)
					(thickness 0.15)
				)
				(justify right bottom)
			)
		)
		(property "Value" "C_22u_0603"
			(at -1.42757 1.770288 0)
			(layer "F.Fab")
			(effects
				(font
					(size 0.7 0.7)
					(thickness 0.15)
				)
				(justify right bottom)
			)
		)
		(property "Author" "Antmicro"
			(at 210.85 125.15 0)
			(layer "F.Fab")
			(hide yes)
			(effects
				(font
					(size 1 1)
					(thickness 0.15)
				)
			)
		)
		(property "Dielectric" ""
			(at 210.85 125.15 0)
			(layer "F.Fab")
			(hide yes)
			(effects
				(font
					(size 1 1)
					(thickness 0.15)
				)
			)
		)
		(property "License" "Apache-2.0"
			(at 210.85 125.15 0)
			(layer "F.Fab")
			(hide yes)
			(effects
				(font
					(size 1 1)
					(thickness 0.15)
				)
			)
		)
		(property "MPN" "GRM188R60J226MEA0D"
			(at 210.85 125.15 0)
			(layer "F.Fab")
			(hide yes)
			(effects
				(font
					(size 1 1)
					(thickness 0.15)
				)
			)
		)
		(property "Manufacturer" "Murata"
			(at 210.85 125.15 0)
			(layer "F.Fab")
			(hide yes)
			(effects
				(font
					(size 1 1)
					(thickness 0.15)
				)
			)
		)
		(property "Val" "22u"
			(at 210.85 125.15 0)
			(layer "F.Fab")
			(hide yes)
			(effects
				(font
					(size 1 1)
					(thickness 0.15)
				)
			)
		)
		(property "Voltage" ""
			(at 210.85 125.15 0)
			(layer "F.Fab")
			(hide yes)
			(effects
				(font
					(size 1 1)
					(thickness 0.15)
				)
			)
		)
		(sheetname "Power supply")
		(sheetfile "power_supply.kicad_sch")
		(attr smd)
		(fp_line
			(start -0.3 0.3)
			(end 0.3 0.3)
			(stroke
				(width 0.15)
				(type solid)
			)
			(layer "F.SilkS")
		)
		(fp_line
			(start -0.3 -0.3)
			(end 0.3 -0.3)
			(stroke
				(width 0.15)
				(type solid)
			)
			(layer "F.SilkS")
		)
		(fp_rect
			(start -1.24 -0.7)
			(end 1.24 0.7)
			(stroke
				(width 0.05)
				(type solid)
			)
			(fill no)
			(layer "F.CrtYd")
		)
		(fp_rect
			(start -0.8 -0.4)
			(end 0.8 0.4)
			(stroke
				(width 0.15)
				(type solid)
			)
			(fill no)
			(layer "F.Fab")
		)
		(pad "1" smd roundrect
			(at -0.7 0 180)
			(size 0.6 0.8)
			(layers "F.Cu" "F.Mask" "F.Paste")
			(roundrect_rratio 0.2)
			(net 14 "GND")
			(pintype "passive")
		)
		(pad "2" smd roundrect
			(at 0.7 0 180)
			(size 0.6 0.8)
			(layers "F.Cu" "F.Mask" "F.Paste")
			(roundrect_rratio 0.2)
			(net 7 "/Power supply/VOUT1")
			(pintype "passive")
		)
	)
	(footprint "antmicro-footprints:C_0805_2012Metric"
		(layer "F.Cu")
		(at 106.4875 73.225)
		(descr "Capacitor SMD 0805")
		(tags "capacitor SMD 0805")
		(property "Reference" "C10"
			(at 2.4125 2.275 0)
			(unlocked yes)
			(layer "F.SilkS")
			(effects
				(font
					(size 0.7 0.7)
					(thickness 0.15)
				)
				(justify left bottom)
			)
		)
		(property "Value" "C_22u_25V_0805"
			(at -2.055717 1.963152 0)
			(layer "F.Fab")
			(effects
				(font
					(size 0.7 0.7)
					(thickness 0.15)
				)
				(justify left bottom)
			)
		)
		(property "Author" "Antmicro"
			(at 0 0 0)
			(layer "F.Fab")
			(hide yes)
			(effects
				(font
					(size 1 1)
					(thickness 0.15)
				)
			)
		)
		(property "Dielectric" ""
			(at 0 0 0)
			(layer "F.Fab")
			(hide yes)
			(effects
				(font
					(size 1 1)
					(thickness 0.15)
				)
			)
		)
		(property "License" "Apache-2.0"
			(at 0 0 0)
			(layer "F.Fab")
			(hide yes)
			(effects
				(font
					(size 1 1)
					(thickness 0.15)
				)
			)
		)
		(property "MPN" "CL21A226MAYNNNE"
			(at 0 0 0)
			(layer "F.Fab")
			(hide yes)
			(effects
				(font
					(size 1 1)
					(thickness 0.15)
				)
			)
		)
		(property "Manufacturer" "Samsung Electro-Mechanics"
			(at 0 0 0)
			(layer "F.Fab")
			(hide yes)
			(effects
				(font
					(size 1 1)
					(thickness 0.15)
				)
			)
		)
		(property "Val" "22u_25V"
			(at 0 0 0)
			(layer "F.Fab")
			(hide yes)
			(effects
				(font
					(size 1 1)
					(thickness 0.15)
				)
			)
		)
		(property "Voltage" ""
			(at 0 0 0)
			(layer "F.Fab")
			(hide yes)
			(effects
				(font
					(size 1 1)
					(thickness 0.15)
				)
			)
		)
		(sheetname "Power supply")
		(sheetfile "power_supply.kicad_sch")
		(attr smd)
		(fp_line
			(start -0.3 -0.8)
			(end 0.3 -0.8)
			(stroke
				(width 0.15)
				(type solid)
			)
			(layer "F.SilkS")
		)
		(fp_line
			(start -0.3 0.8)
			(end 0.3 0.8)
			(stroke
				(width 0.15)
				(type solid)
			)
			(layer "F.SilkS")
		)
		(fp_rect
			(start -1.9 -0.93)
			(end 1.9 0.93)
			(stroke
				(width 0.05)
				(type solid)
			)
			(fill no)
			(layer "F.CrtYd")
		)
		(fp_rect
			(start -0.95 -0.675)
			(end 0.95 0.675)
			(stroke
				(width 0.15)
				(type solid)
			)
			(fill no)
			(layer "F.Fab")
		)
		(pad "1" smd rect
			(at -1.05 0)
			(size 1.2 1.2)
			(layers "F.Cu" "F.Mask" "F.Paste")
			(net 14 "GND")
			(pintype "passive")
		)
		(pad "2" smd rect
			(at 1.05 0)
			(size 1.2 1.2)
			(layers "F.Cu" "F.Mask" "F.Paste")
			(net 5 "+5V")
			(pintype "passive")
		)
	)
	(footprint "antmicro-footprints:R_Array_4x0402_Panasonic_EXB28V"
		(layer "F.Cu")
		(at 141.6 93.8 180)
		(property "Reference" "R76"
			(at -1 1.4 0)
			(unlocked yes)
			(layer "F.SilkS")
			(effects
				(font
					(size 0.7 0.7)
					(thickness 0.15)
				)
				(justify right bottom)
			)
		)
		(property "Value" "R_4x100R_0402_array"
			(at -1.5 2 0)
			(layer "F.Fab")
			(effects
				(font
					(size 0.7 0.7)
					(thickness 0.15)
				)
				(justify right bottom)
			)
		)
		(property "Author" "Antmicro"
			(at 283.2 187.6 0)
			(layer "F.Fab")
			(hide yes)
			(effects
				(font
					(size 1 1)
					(thickness 0.15)
				)
			)
		)
		(property "License" "Apache-2.0"
			(at 283.2 187.6 0)
			(layer "F.Fab")
			(hide yes)
			(effects
				(font
					(size 1 1)
					(thickness 0.15)
				)
			)
		)
		(property "MPN" "EXB-28V101JX"
			(at 283.2 187.6 0)
			(layer "F.Fab")
			(hide yes)
			(effects
				(font
					(size 1 1)
					(thickness 0.15)
				)
			)
		)
		(property "Manufacturer" "Panasonic"
			(at 283.2 187.6 0)
			(layer "F.Fab")
			(hide yes)
			(effects
				(font
					(size 1 1)
					(thickness 0.15)
				)
			)
		)
		(property "Val" "R_4x100R_0402"
			(at 283.2 187.6 0)
			(layer "F.Fab")
			(hide yes)
			(effects
				(font
					(size 1 1)
					(thickness 0.15)
				)
			)
		)
		(sheetname "Translators1")
		(sheetfile "translators.kicad_sch")
		(attr smd)
		(fp_line
			(start 1.25 0.499)
			(end 1.25 -0.499)
			(stroke
				(width 0.15)
				(type solid)
			)
			(layer "F.SilkS")
		)
		(fp_line
			(start -1.25 -0.5)
			(end -1.25 0.498)
			(stroke
				(width 0.15)
				(type solid)
			)
			(layer "F.SilkS")
		)
		(fp_rect
			(start -1.25 -0.8)
			(end 1.25 0.8)
			(stroke
				(width 0.05)
				(type solid)
			)
			(fill no)
			(layer "F.CrtYd")
		)
		(fp_line
			(start 0.998 0.498)
			(end -1 0.498)
			(stroke
				(width 0.15)
				(type solid)
			)
			(layer "F.Fab")
		)
		(fp_line
			(start 0.998 -0.5)
			(end 0.998 0.498)
			(stroke
				(width 0.15)
				(type solid)
			)
			(layer "F.Fab")
		)
		(fp_line
			(start -1 0.498)
			(end -1 -0.5)
			(stroke
				(width 0.15)
				(type solid)
			)
			(layer "F.Fab")
		)
		(fp_line
			(start -1 -0.5)
			(end 0.998 -0.5)
			(stroke
				(width 0.15)
				(type solid)
			)
			(layer "F.Fab")
		)
		(pad "1" smd roundrect
			(at -0.8875 0.45 180)
			(size 0.525 0.5)
			(layers "F.Cu" "F.Mask" "F.Paste")
			(roundrect_rratio 0.25)
			(net 104 "/LPDDR5/LPDDR5_B.CA2")
			(pinfunction "R1.1")
			(pintype "passive")
		)
		(pad "2" smd roundrect
			(at -0.25 0.45 180)
			(size 0.25 0.5)
			(layers "F.Cu" "F.Mask" "F.Paste")
			(roundrect_rratio 0.25)
			(net 99 "/LPDDR5/LPDDR5_B.CA3")
			(pinfunction "R2.1")
			(pintype "passive")
		)
		(pad "3" smd roundrect
			(at 0.25 0.45 180)
			(size 0.25 0.5)
			(layers "F.Cu" "F.Mask" "F.Paste")
			(roundrect_rratio 0.25)
			(net 105 "/LPDDR5/LPDDR5_B.CA4")
			(pinfunction "R3.1")
			(pintype "passive")
		)
		(pad "4" smd roundrect
			(at 0.8875 0.45 180)
			(size 0.525 0.5)
			(layers "F.Cu" "F.Mask" "F.Paste")
			(roundrect_rratio 0.25)
			(net 101 "/LPDDR5/LPDDR5_B.CA5")
			(pinfunction "R4.1")
			(pintype "passive")
		)
		(pad "5" smd roundrect
			(at 0.8875 -0.45 180)
			(size 0.525 0.5)
			(layers "F.Cu" "F.Mask" "F.Paste")
			(roundrect_rratio 0.25)
			(net 14 "GND")
			(pinfunction "R4.2")
			(pintype "passive")
		)
		(pad "6" smd roundrect
			(at 0.25 -0.45 180)
			(size 0.25 0.5)
			(layers "F.Cu" "F.Mask" "F.Paste")
			(roundrect_rratio 0.25)
			(net 14 "GND")
			(pinfunction "R3.2")
			(pintype "passive")
		)
		(pad "7" smd roundrect
			(at -0.25 -0.45 180)
			(size 0.25 0.5)
			(layers "F.Cu" "F.Mask" "F.Paste")
			(roundrect_rratio 0.25)
			(net 14 "GND")
			(pinfunction "R2.2")
			(pintype "passive")
		)
		(pad "8" smd roundrect
			(at -0.8875 -0.45 180)
			(size 0.525 0.5)
			(layers "F.Cu" "F.Mask" "F.Paste")
			(roundrect_rratio 0.25)
			(net 14 "GND")
			(pinfunction "R1.2")
			(pintype "passive")
		)
	)
	(footprint "antmicro-footprints:R_0402_1005Metric"
		(layer "F.Cu")
		(at 161.55 63.85 -90)
		(descr "Resistor SMD 0402")
		(tags "resistor SMD 0402")
		(property "Reference" "R51"
			(at -1.15 0.65 90)
			(unlocked yes)
			(layer "F.SilkS")
			(effects
				(font
					(size 0.7 0.7)
					(thickness 0.15)
				)
				(justify right bottom)
			)
		)
		(property "Value" "R_3k9_0402"
			(at -1.011843 1.772047 90)
			(layer "F.Fab")
			(effects
				(font
					(size 0.7 0.7)
					(thickness 0.15)
				)
				(justify right bottom)
			)
		)
		(property "Author" "Antmicro"
			(at 97.7 225.4 0)
			(layer "F.Fab")
			(hide yes)
			(effects
				(font
					(size 1 1)
					(thickness 0.15)
				)
			)
		)
		(property "License" "Apache-2.0"
			(at 97.7 225.4 0)
			(layer "F.Fab")
			(hide yes)
			(effects
				(font
					(size 1 1)
					(thickness 0.15)
				)
			)
		)
		(property "MPN" "CR0402-FX-3901GLF"
			(at 97.7 225.4 0)
			(layer "F.Fab")
			(hide yes)
			(effects
				(font
					(size 1 1)
					(thickness 0.15)
				)
			)
		)
		(property "Manufacturer" "Bourns"
			(at 97.7 225.4 0)
			(layer "F.Fab")
			(hide yes)
			(effects
				(font
					(size 1 1)
					(thickness 0.15)
				)
			)
		)
		(property "Tolerance" "1%"
			(at 97.7 225.4 0)
			(layer "F.Fab")
			(hide yes)
			(effects
				(font
					(size 1 1)
					(thickness 0.15)
				)
			)
		)
		(property "Val" "3k9"
			(at 97.7 225.4 0)
			(layer "F.Fab")
			(hide yes)
			(effects
				(font
					(size 1 1)
					(thickness 0.15)
				)
			)
		)
		(sheetname "Power supply")
		(sheetfile "power_supply.kicad_sch")
		(attr smd)
		(fp_rect
			(start -0.93 -0.47)
			(end 0.93 0.47)
			(stroke
				(width 0.05)
				(type solid)
			)
			(fill no)
			(layer "F.CrtYd")
		)
		(fp_rect
			(start -0.5 -0.25)
			(end 0.5 0.25)
			(stroke
				(width 0.15)
				(type solid)
			)
			(fill no)
			(layer "F.Fab")
		)
		(pad "1" smd roundrect
			(at -0.485 0 270)
			(size 0.59 0.64)
			(layers "F.Cu" "F.Mask" "F.Paste")
			(roundrect_rratio 0.25)
			(net 53 "Net-(POT1-Pad3)")
			(pintype "passive")
		)
		(pad "2" smd roundrect
			(at 0.485 0 270)
			(size 0.59 0.64)
			(layers "F.Cu" "F.Mask" "F.Paste")
			(roundrect_rratio 0.25)
			(net 11 "/Power supply/VOUT")
			(pintype "passive")
		)
	)
	(footprint "antmicro-footprints:BGA-315_12.4x15mm_Layout15x21_P0.8x0.7mm"
		(layer "F.Cu")
		(at 134.775 80 90)
		(property "Reference" "U1"
			(at 6.8 7.025 0)
			(unlocked yes)
			(layer "F.SilkS")
			(effects
				(font
					(size 0.7 0.7)
					(thickness 0.15)
				)
				(justify left bottom)
			)
		)
		(property "Value" "MT62F1G32D4DR-031"
			(at 0 8.9 90)
			(layer "F.Fab")
			(effects
				(font
					(size 0.7 0.7)
					(thickness 0.15)
				)
				(justify left bottom)
			)
		)
		(property "Author" "Antmicro"
			(at 214.775 -54.775 0)
			(layer "F.Fab")
			(hide yes)
			(effects
				(font
					(size 1 1)
					(thickness 0.15)
				)
			)
		)
		(property "License" "Apache-2.0"
			(at 214.775 -54.775 0)
			(layer "F.Fab")
			(hide yes)
			(effects
				(font
					(size 1 1)
					(thickness 0.15)
				)
			)
		)
		(property "MPN" "MT62F1G32D4DR-031 WT:B"
			(at 214.775 -54.775 0)
			(layer "F.Fab")
			(hide yes)
			(effects
				(font
					(size 1 1)
					(thickness 0.15)
				)
			)
		)
		(property "Manufacturer" "Micron Technology"
			(at 214.775 -54.775 0)
			(layer "F.Fab")
			(hide yes)
			(effects
				(font
					(size 1 1)
					(thickness 0.15)
				)
			)
		)
		(sheetname "LPDDR5")
		(sheetfile "lpddr5.kicad_sch")
		(attr smd)
		(fp_line
			(start 6.32 -7.62)
			(end 6.32 -3.87)
			(stroke
				(width 0.12)
				(type solid)
			)
			(layer "F.SilkS")
		)
		(fp_line
			(start 3.22 -7.62)
			(end 6.32 -7.62)
			(stroke
				(width 0.12)
				(type solid)
			)
			(layer "F.SilkS")
		)
		(fp_line
			(start -2.9 -7.62)
			(end -5.8 -7.62)
			(stroke
				(width 0.12)
				(type solid)
			)
			(layer "F.SilkS")
		)
		(fp_line
			(start -5.8 -7.62)
			(end -6.32 -7.1)
			(stroke
				(width 0.12)
				(type solid)
			)
			(layer "F.SilkS")
		)
		(fp_line
			(start -6.32 -7.1)
			(end -6.32 -3.87)
			(stroke
				(width 0.12)
				(type solid)
			)
			(layer "F.SilkS")
		)
		(fp_line
			(start 6.32 7.62)
			(end 6.32 3.87)
			(stroke
				(width 0.12)
				(type solid)
			)
			(layer "F.SilkS")
		)
		(fp_line
			(start 3.22 7.62)
			(end 6.32 7.62)
			(stroke
				(width 0.12)
				(type solid)
			)
			(layer "F.SilkS")
		)
		(fp_line
			(start -3.22 7.62)
			(end -6.32 7.62)
			(stroke
				(width 0.12)
				(type solid)
			)
			(layer "F.SilkS")
		)
		(fp_line
			(start -6.32 7.62)
			(end -6.32 3.87)
			(stroke
				(width 0.12)
				(type solid)
			)
			(layer "F.SilkS")
		)
		(fp_circle
			(center -6.3 -7.6)
			(end -6.3 -7.5)
			(stroke
				(width 0.2)
				(type solid)
			)
			(fill no)
			(layer "F.SilkS")
		)
		(fp_line
			(start 6.45 -7.75)
			(end 6.45 7.75)
			(stroke
				(width 0.05)
				(type solid)
			)
			(layer "F.CrtYd")
		)
		(fp_line
			(start -6.45 -7.75)
			(end 6.45 -7.75)
			(stroke
				(width 0.05)
				(type solid)
			)
			(layer "F.CrtYd")
		)
		(fp_line
			(start 6.45 7.75)
			(end -6.45 7.75)
			(stroke
				(width 0.05)
				(type solid)
			)
			(layer "F.CrtYd")
		)
		(fp_line
			(start -6.45 7.75)
			(end -6.45 -7.75)
			(stroke
				(width 0.05)
				(type solid)
			)
			(layer "F.CrtYd")
		)
		(fp_line
			(start 6.2 -7.5)
			(end -5.7 -7.5)
			(stroke
				(width 0.1)
				(type solid)
			)
			(layer "F.Fab")
		)
		(fp_line
			(start -5.7 -7.5)
			(end -6.2 -7)
			(stroke
				(width 0.1)
				(type solid)
			)
			(layer "F.Fab")
		)
		(fp_line
			(start -6.2 -7)
			(end -6.2 7)
			(stroke
				(width 0.1)
				(type solid)
			)
			(layer "F.Fab")
		)
		(fp_line
			(start 6.2 7.5)
			(end 6.2 -7.5)
			(stroke
				(width 0.1)
				(type solid)
			)
			(layer "F.Fab")
		)
		(fp_line
			(start -6.2 7.5)
			(end 6.2 7.5)
			(stroke
				(width 0.1)
				(type solid)
			)
			(layer "F.Fab")
		)
		(pad "A1" smd circle
			(at -5.6 -7 90)
			(size 0.41 0.41)
			(layers "F.Cu" "F.Mask" "F.Paste")
			(net 21 "unconnected-(U1-PadA1)")
			(pinfunction "NC")
			(pintype "no_connect")
		)
		(pad "A2" smd circle
			(at -4.8 -7 90)
			(size 0.41 0.41)
			(layers "F.Cu" "F.Mask" "F.Paste")
			(net 22 "unconnected-(U1-PadA2)")
			(pinfunction "NC")
			(pintype "no_connect")
		)
		(pad "A3" smd circle
			(at -4 -7 90)
			(size 0.41 0.41)
			(layers "F.Cu" "F.Mask" "F.Paste")
			(net 4 "+0V5")
			(pinfunction "VDDQ")
			(pintype "passive")
		)
		(pad "A4" smd circle
			(at -3.2 -7 90)
			(size 0.41 0.41)
			(layers "F.Cu" "F.Mask" "F.Paste")
			(net 201 "/LPDDR5/LPDDR5_A.DMI0")
			(pinfunction "DMI0_A")
			(pintype "passive")
		)
		(pad "A5" smd circle
			(at -2.4 -7 90)
			(size 0.41 0.41)
			(layers "F.Cu" "F.Mask" "F.Paste")
			(net 14 "GND")
			(pinfunction "VSS")
			(pintype "passive")
		)
		(pad "A6" smd circle
			(at -1.6 -7 90)
			(size 0.41 0.41)
			(layers "F.Cu" "F.Mask" "F.Paste")
			(net 12 "+0V9")
			(pinfunction "VDD2L")
			(pintype "passive")
		)
		(pad "A7" smd circle
			(at -0.8 -7 90)
			(size 0.41 0.41)
			(layers "F.Cu" "F.Mask" "F.Paste")
			(net 13 "+1V05")
			(pinfunction "VDD2H")
			(pintype "passive")
		)
		(pad "A8" smd circle
			(at 0 -7 90)
			(size 0.41 0.41)
			(layers "F.Cu" "F.Mask" "F.Paste")
			(net 13 "+1V05")
			(pinfunction "VDD2H")
			(pintype "passive")
		)
		(pad "A9" smd circle
			(at 0.8 -7 90)
			(size 0.41 0.41)
			(layers "F.Cu" "F.Mask" "F.Paste")
			(net 13 "+1V05")
			(pinfunction "VDD2H")
			(pintype "passive")
		)
		(pad "A10" smd circle
			(at 1.6 -7 90)
			(size 0.41 0.41)
			(layers "F.Cu" "F.Mask" "F.Paste")
			(net 12 "+0V9")
			(pinfunction "VDD2L")
			(pintype "passive")
		)
		(pad "A11" smd circle
			(at 2.4 -7 90)
			(size 0.41 0.41)
			(layers "F.Cu" "F.Mask" "F.Paste")
			(net 14 "GND")
			(pinfunction "VSS")
			(pintype "passive")
		)
		(pad "A12" smd circle
			(at 3.2 -7 90)
			(size 0.41 0.41)
			(layers "F.Cu" "F.Mask" "F.Paste")
			(net 190 "/LPDDR5/LPDDR5_A.DMI1")
			(pinfunction "DMI1_A")
			(pintype "passive")
		)
		(pad "A13" smd circle
			(at 4 -7 90)
			(size 0.41 0.41)
			(layers "F.Cu" "F.Mask" "F.Paste")
			(net 4 "+0V5")
			(pinfunction "VDDQ")
			(pintype "passive")
		)
		(pad "A14" smd circle
			(at 4.8 -7 90)
			(size 0.41 0.41)
			(layers "F.Cu" "F.Mask" "F.Paste")
			(net 2 "unconnected-(U1-PadA14)")
			(pinfunction "NC")
			(pintype "no_connect")
		)
		(pad "A15" smd circle
			(at 5.6 -7 90)
			(size 0.41 0.41)
			(layers "F.Cu" "F.Mask" "F.Paste")
			(net 3 "unconnected-(U1-PadA15)")
			(pinfunction "NC")
			(pintype "no_connect")
		)
		(pad "AA1" smd circle
			(at -5.6 7 90)
			(size 0.41 0.41)
			(layers "F.Cu" "F.Mask" "F.Paste")
			(net 26 "unconnected-(U1-PadAA1)")
			(pinfunction "NC")
			(pintype "no_connect")
		)
		(pad "AA2" smd circle
			(at -4.8 7 90)
			(size 0.41 0.41)
			(layers "F.Cu" "F.Mask" "F.Paste")
			(net 27 "unconnected-(U1-PadAA2)")
			(pinfunction "NC")
			(pintype "no_connect")
		)
		(pad "AA3" smd circle
			(at -4 7 90)
			(size 0.41 0.41)
			(layers "F.Cu" "F.Mask" "F.Paste")
			(net 4 "+0V5")
			(pinfunction "VDDQ")
			(pintype "passive")
		)
		(pad "AA4" smd circle
			(at -3.2 7 90)
			(size 0.41 0.41)
			(layers "F.Cu" "F.Mask" "F.Paste")
			(net 223 "/LPDDR5/LPDDR5_B.DMI1")
			(pinfunction "DMI1_B")
			(pintype "passive")
		)
		(pad "AA5" smd circle
			(at -2.4 7 90)
			(size 0.41 0.41)
			(layers "F.Cu" "F.Mask" "F.Paste")
			(net 14 "GND")
			(pinfunction "VSS")
			(pintype "passive")
		)
		(pad "AA6" smd circle
			(at -1.6 7 90)
			(size 0.41 0.41)
			(layers "F.Cu" "F.Mask" "F.Paste")
			(net 12 "+0V9")
			(pinfunction "VDD2L")
			(pintype "passive")
		)
		(pad "AA7" smd circle
			(at -0.8 7 90)
			(size 0.41 0.41)
			(layers "F.Cu" "F.Mask" "F.Paste")
			(net 13 "+1V05")
			(pinfunction "VDD2H")
			(pintype "passive")
		)
		(pad "AA8" smd circle
			(at 0 7 90)
			(size 0.41 0.41)
			(layers "F.Cu" "F.Mask" "F.Paste")
			(net 13 "+1V05")
			(pinfunction "VDD2H")
			(pintype "passive")
		)
		(pad "AA9" smd circle
			(at 0.8 7 90)
			(size 0.41 0.41)
			(layers "F.Cu" "F.Mask" "F.Paste")
			(net 13 "+1V05")
			(pinfunction "VDD2H")
			(pintype "passive")
		)
		(pad "AA10" smd circle
			(at 1.6 7 90)
			(size 0.41 0.41)
			(layers "F.Cu" "F.Mask" "F.Paste")
			(net 12 "+0V9")
			(pinfunction "VDD2L")
			(pintype "passive")
		)
		(pad "AA11" smd circle
			(at 2.4 7 90)
			(size 0.41 0.41)
			(layers "F.Cu" "F.Mask" "F.Paste")
			(net 14 "GND")
			(pinfunction "VSS")
			(pintype "passive")
		)
		(pad "AA12" smd circle
			(at 3.2 7 90)
			(size 0.41 0.41)
			(layers "F.Cu" "F.Mask" "F.Paste")
			(net 212 "/LPDDR5/LPDDR5_B.DMI0")
			(pinfunction "DMI0_B")
			(pintype "passive")
		)
		(pad "AA13" smd circle
			(at 4 7 90)
			(size 0.41 0.41)
			(layers "F.Cu" "F.Mask" "F.Paste")
			(net 4 "+0V5")
			(pinfunction "VDDQ")
			(pintype "passive")
		)
		(pad "AA14" smd circle
			(at 4.8 7 90)
			(size 0.41 0.41)
			(layers "F.Cu" "F.Mask" "F.Paste")
			(net 23 "unconnected-(U1-PadAA14)")
			(pinfunction "NC")
			(pintype "no_connect")
		)
		(pad "AA15" smd circle
			(at 5.6 7 90)
			(size 0.41 0.41)
			(layers "F.Cu" "F.Mask" "F.Paste")
			(net 24 "unconnected-(U1-PadAA15)")
			(pinfunction "NC")
			(pintype "no_connect")
		)
		(pad "B1" smd circle
			(at -5.6 -6.3 90)
			(size 0.41 0.41)
			(layers "F.Cu" "F.Mask" "F.Paste")
			(net 28 "unconnected-(U1-PadB1)")
			(pinfunction "NC")
			(pintype "no_connect")
		)
		(pad "B2" smd circle
			(at -4.8 -6.3 90)
			(size 0.41 0.41)
			(layers "F.Cu" "F.Mask" "F.Paste")
			(net 4 "+0V5")
			(pinfunction "VDDQ")
			(pintype "passive")
		)
		(pad "B3" smd circle
			(at -4 -6.3 90)
			(size 0.41 0.41)
			(layers "F.Cu" "F.Mask" "F.Paste")
			(net 200 "/LPDDR5/LPDDR5_A.RDQS0_P")
			(pinfunction "RDQS0_t_A")
			(pintype "passive")
		)
		(pad "B4" smd circle
			(at -3.2 -6.3 90)
			(size 0.41 0.41)
			(layers "F.Cu" "F.Mask" "F.Paste")
			(net 14 "GND")
			(pinfunction "VSS")
			(pintype "passive")
		)
		(pad "B5" smd circle
			(at -2.4 -6.3 90)
			(size 0.41 0.41)
			(layers "F.Cu" "F.Mask" "F.Paste")
			(net 198 "/LPDDR5/LPDDR5_A.DQ4")
			(pinfunction "DQ4_A")
			(pintype "passive")
		)
		(pad "B6" smd circle
			(at -1.6 -6.3 90)
			(size 0.41 0.41)
			(layers "F.Cu" "F.Mask" "F.Paste")
			(net 12 "+0V9")
			(pinfunction "VDD2L")
			(pintype "passive")
		)
		(pad "B7" smd circle
			(at -0.8 -6.3 90)
			(size 0.41 0.41)
			(layers "F.Cu" "F.Mask" "F.Paste")
			(net 13 "+1V05")
			(pinfunction "VDD2H")
			(pintype "passive")
		)
		(pad "B8" smd circle
			(at 0 -6.3 90)
			(size 0.41 0.41)
			(layers "F.Cu" "F.Mask" "F.Paste")
			(net 14 "GND")
			(pinfunction "VSS")
			(pintype "passive")
		)
		(pad "B9" smd circle
			(at 0.8 -6.3 90)
			(size 0.41 0.41)
			(layers "F.Cu" "F.Mask" "F.Paste")
			(net 13 "+1V05")
			(pinfunction "VDD2H")
			(pintype "passive")
		)
		(pad "B10" smd circle
			(at 1.6 -6.3 90)
			(size 0.41 0.41)
			(layers "F.Cu" "F.Mask" "F.Paste")
			(net 12 "+0V9")
			(pinfunction "VDD2L")
			(pintype "passive")
		)
		(pad "B11" smd circle
			(at 2.4 -6.3 90)
			(size 0.41 0.41)
			(layers "F.Cu" "F.Mask" "F.Paste")
			(net 193 "/LPDDR5/LPDDR5_A.DQ12")
			(pinfunction "DQ12_A")
			(pintype "passive")
		)
		(pad "B12" smd circle
			(at 3.2 -6.3 90)
			(size 0.41 0.41)
			(layers "F.Cu" "F.Mask" "F.Paste")
			(net 14 "GND")
			(pinfunction "VSS")
			(pintype "passive")
		)
		(pad "B13" smd circle
			(at 4 -6.3 90)
			(size 0.41 0.41)
			(layers "F.Cu" "F.Mask" "F.Paste")
			(net 189 "/LPDDR5/LPDDR5_A.RDQS1_P")
			(pinfunction "RDQS1_t_A")
			(pintype "passive")
		)
		(pad "B14" smd circle
			(at 4.8 -6.3 90)
			(size 0.41 0.41)
			(layers "F.Cu" "F.Mask" "F.Paste")
			(net 4 "+0V5")
			(pinfunction "VDDQ")
			(pintype "passive")
		)
		(pad "B15" smd circle
			(at 5.6 -6.3 90)
			(size 0.41 0.41)
			(layers "F.Cu" "F.Mask" "F.Paste")
			(net 25 "unconnected-(U1-PadB15)")
			(pinfunction "NC")
			(pintype "no_connect")
		)
		(pad "C1" smd circle
			(at -5.6 -5.6 90)
			(size 0.41 0.41)
			(layers "F.Cu" "F.Mask" "F.Paste")
			(net 35 "+1V8")
			(pinfunction "VDD1")
			(pintype "passive")
		)
		(pad "C2" smd circle
			(at -4.8 -5.6 90)
			(size 0.41 0.41)
			(layers "F.Cu" "F.Mask" "F.Paste")
			(net 204 "/LPDDR5/LPDDR5_A.DQ1")
			(pinfunction "DQ1_A")
			(pintype "passive")
		)
		(pad "C3" smd circle
			(at -4 -5.6 90)
			(size 0.41 0.41)
			(layers "F.Cu" "F.Mask" "F.Paste")
			(net 4 "+0V5")
			(pinfunction "VDDQ")
			(pintype "passive")
		)
		(pad "C4" smd circle
			(at -3.2 -5.6 90)
			(size 0.41 0.41)
			(layers "F.Cu" "F.Mask" "F.Paste")
			(net 199 "/LPDDR5/LPDDR5_A.RDQS0_N")
			(pinfunction "RDQS0_c_A")
			(pintype "passive")
		)
		(pad "C5" smd circle
			(at -2.4 -5.6 90)
			(size 0.41 0.41)
			(layers "F.Cu" "F.Mask" "F.Paste")
			(net 14 "GND")
			(pinfunction "VSS")
			(pintype "passive")
		)
		(pad "C6" smd circle
			(at -1.6 -5.6 90)
			(size 0.41 0.41)
			(layers "F.Cu" "F.Mask" "F.Paste")
			(net 197 "/LPDDR5/LPDDR5_A.DQ5")
			(pinfunction "DQ5_A")
			(pintype "passive")
		)
		(pad "C7" smd circle
			(at -0.8 -5.6 90)
			(size 0.41 0.41)
			(layers "F.Cu" "F.Mask" "F.Paste")
			(net 13 "+1V05")
			(pinfunction "VDD2H")
			(pintype "passive")
		)
		(pad "C8" smd circle
			(at 0 -5.6 90)
			(size 0.41 0.41)
			(layers "F.Cu" "F.Mask" "F.Paste")
			(net 14 "GND")
			(pinfunction "VSS")
			(pintype "passive")
		)
		(pad "C9" smd circle
			(at 0.8 -5.6 90)
			(size 0.41 0.41)
			(layers "F.Cu" "F.Mask" "F.Paste")
			(net 13 "+1V05")
			(pinfunction "VDD2H")
			(pintype "passive")
		)
		(pad "C10" smd circle
			(at 1.6 -5.6 90)
			(size 0.41 0.41)
			(layers "F.Cu" "F.Mask" "F.Paste")
			(net 194 "/LPDDR5/LPDDR5_A.DQ13")
			(pinfunction "DQ13_A")
			(pintype "passive")
		)
		(pad "C11" smd circle
			(at 2.4 -5.6 90)
			(size 0.41 0.41)
			(layers "F.Cu" "F.Mask" "F.Paste")
			(net 14 "GND")
			(pinfunction "VSS")
			(pintype "passive")
		)
		(pad "C12" smd circle
			(at 3.2 -5.6 90)
			(size 0.41 0.41)
			(layers "F.Cu" "F.Mask" "F.Paste")
			(net 188 "/LPDDR5/LPDDR5_A.RDQS1_N")
			(pinfunction "RDQS1_c_A")
			(pintype "passive")
		)
		(pad "C13" smd circle
			(at 4 -5.6 90)
			(size 0.41 0.41)
			(layers "F.Cu" "F.Mask" "F.Paste")
			(net 4 "+0V5")
			(pinfunction "VDDQ")
			(pintype "passive")
		)
		(pad "C14" smd circle
			(at 4.8 -5.6 90)
			(size 0.41 0.41)
			(layers "F.Cu" "F.Mask" "F.Paste")
			(net 172 "/LPDDR5/LPDDR5_A.DQ9")
			(pinfunction "DQ9_A")
			(pintype "passive")
		)
		(pad "C15" smd circle
			(at 5.6 -5.6 90)
			(size 0.41 0.41)
			(layers "F.Cu" "F.Mask" "F.Paste")
			(net 35 "+1V8")
			(pinfunction "VDD1")
			(pintype "passive")
		)
		(pad "D1" smd circle
			(at -5.6 -4.9 90)
			(size 0.41 0.41)
			(layers "F.Cu" "F.Mask" "F.Paste")
			(net 205 "/LPDDR5/LPDDR5_A.DQ0")
			(pinfunction "DQ0_A")
			(pintype "passive")
		)
		(pad "D2" smd circle
			(at -4.8 -4.9 90)
			(size 0.41 0.41)
			(layers "F.Cu" "F.Mask" "F.Paste")
			(net 14 "GND")
			(pinfunction "VSS")
			(pintype "passive")
		)
		(pad "D3" smd circle
			(at -4 -4.9 90)
			(size 0.41 0.41)
			(layers "F.Cu" "F.Mask" "F.Paste")
			(net 202 "/LPDDR5/LPDDR5_A.DQ3")
			(pinfunction "DQ3_A")
			(pintype "passive")
		)
		(pad "D4" smd circle
			(at -3.2 -4.9 90)
			(size 0.41 0.41)
			(layers "F.Cu" "F.Mask" "F.Paste")
			(net 4 "+0V5")
			(pinfunction "VDDQ")
			(pintype "passive")
		)
		(pad "D5" smd circle
			(at -2.4 -4.9 90)
			(size 0.41 0.41)
			(layers "F.Cu" "F.Mask" "F.Paste")
			(net 46 "/LPDDR5/LPDDR5_A.WCK0_N")
			(pinfunction "WCK0_c_A")
			(pintype "passive")
		)
		(pad "D6" smd circle
			(at -1.6 -4.9 90)
			(size 0.41 0.41)
			(layers "F.Cu" "F.Mask" "F.Paste")
			(net 14 "GND")
			(pinfunction "VSS")
			(pintype "passive")
		)
		(pad "D7" smd circle
			(at -0.8 -4.9 90)
			(size 0.41 0.41)
			(layers "F.Cu" "F.Mask" "F.Paste")
			(net 14 "GND")
			(pinfunction "VSS")
			(pintype "passive")
		)
		(pad "D8" smd circle
			(at 0 -4.9 90)
			(size 0.41 0.41)
			(layers "F.Cu" "F.Mask" "F.Paste")
			(net 13 "+1V05")
			(pinfunction "VDD2H")
			(pintype "passive")
		)
		(pad "D9" smd circle
			(at 0.8 -4.9 90)
			(size 0.41 0.41)
			(layers "F.Cu" "F.Mask" "F.Paste")
			(net 14 "GND")
			(pinfunction "VSS")
			(pintype "passive")
		)
		(pad "D10" smd circle
			(at 1.6 -4.9 90)
			(size 0.41 0.41)
			(layers "F.Cu" "F.Mask" "F.Paste")
			(net 14 "GND")
			(pinfunction "VSS")
			(pintype "passive")
		)
		(pad "D11" smd circle
			(at 2.4 -4.9 90)
			(size 0.41 0.41)
			(layers "F.Cu" "F.Mask" "F.Paste")
			(net 47 "/LPDDR5/LPDDR5_A.WCK1_N")
			(pinfunction "WCK1_c_A")
			(pintype "passive")
		)
		(pad "D12" smd circle
			(at 3.2 -4.9 90)
			(size 0.41 0.41)
			(layers "F.Cu" "F.Mask" "F.Paste")
			(net 4 "+0V5")
			(pinfunction "VDDQ")
			(pintype "passive")
		)
		(pad "D13" smd circle
			(at 4 -4.9 90)
			(size 0.41 0.41)
			(layers "F.Cu" "F.Mask" "F.Paste")
			(net 183 "/LPDDR5/LPDDR5_A.DQ11")
			(pinfunction "DQ11_A")
			(pintype "passive")
		)
		(pad "D14" smd circle
			(at 4.8 -4.9 90)
			(size 0.41 0.41)
			(layers "F.Cu" "F.Mask" "F.Paste")
			(net 14 "GND")
			(pinfunction "VSS")
			(pintype "passive")
		)
		(pad "D15" smd circle
			(at 5.6 -4.9 90)
			(size 0.41 0.41)
			(layers "F.Cu" "F.Mask" "F.Paste")
			(net 128 "/LPDDR5/LPDDR5_A.DQ8")
			(pinfunction "DQ8_A")
			(pintype "passive")
		)
		(pad "E1" smd circle
			(at -5.6 -4.2 90)
			(size 0.41 0.41)
			(layers "F.Cu" "F.Mask" "F.Paste")
			(net 14 "GND")
			(pinfunction "VSS")
			(pintype "passive")
		)
		(pad "E2" smd circle
			(at -4.8 -4.2 90)
			(size 0.41 0.41)
			(layers "F.Cu" "F.Mask" "F.Paste")
			(net 203 "/LPDDR5/LPDDR5_A.DQ2")
			(pinfunction "DQ2_A")
			(pintype "passive")
		)
		(pad "E3" smd circle
			(at -4 -4.2 90)
			(size 0.41 0.41)
			(layers "F.Cu" "F.Mask" "F.Paste")
			(net 14 "GND")
			(pinfunction "VSS")
			(pintype "passive")
		)
		(pad "E4" smd circle
			(at -3.2 -4.2 90)
			(size 0.41 0.41)
			(layers "F.Cu" "F.Mask" "F.Paste")
			(net 45 "/LPDDR5/LPDDR5_A.WCK0_P")
			(pinfunction "WCK0_t_A")
			(pintype "passive")
		)
		(pad "E5" smd circle
			(at -2.4 -4.2 90)
			(size 0.41 0.41)
			(layers "F.Cu" "F.Mask" "F.Paste")
			(net 4 "+0V5")
			(pinfunction "VDDQ")
			(pintype "passive")
		)
		(pad "E6" smd circle
			(at -1.6 -4.2 90)
			(size 0.41 0.41)
			(layers "F.Cu" "F.Mask" "F.Paste")
			(net 196 "/LPDDR5/LPDDR5_A.DQ6")
			(pinfunction "DQ6_A")
			(pintype "passive")
		)
		(pad "E7" smd circle
			(at -0.8 -4.2 90)
			(size 0.41 0.41)
			(layers "F.Cu" "F.Mask" "F.Paste")
			(net 13 "+1V05")
			(pinfunction "VDD2H")
			(pintype "passive")
		)
		(pad "E8" smd circle
			(at 0 -4.2 90)
			(size 0.41 0.41)
			(layers "F.Cu" "F.Mask" "F.Paste")
			(net 14 "GND")
			(pinfunction "VSS")
			(pintype "passive")
		)
		(pad "E9" smd circle
			(at 0.8 -4.2 90)
			(size 0.41 0.41)
			(layers "F.Cu" "F.Mask" "F.Paste")
			(net 13 "+1V05")
			(pinfunction "VDD2H")
			(pintype "passive")
		)
		(pad "E10" smd circle
			(at 1.6 -4.2 90)
			(size 0.41 0.41)
			(layers "F.Cu" "F.Mask" "F.Paste")
			(net 192 "/LPDDR5/LPDDR5_A.DQ14")
			(pinfunction "DQ14_A")
			(pintype "passive")
		)
		(pad "E11" smd circle
			(at 2.4 -4.2 90)
			(size 0.41 0.41)
			(layers "F.Cu" "F.Mask" "F.Paste")
			(net 4 "+0V5")
			(pinfunction "VDDQ")
			(pintype "passive")
		)
		(pad "E12" smd circle
			(at 3.2 -4.2 90)
			(size 0.41 0.41)
			(layers "F.Cu" "F.Mask" "F.Paste")
			(net 48 "/LPDDR5/LPDDR5_A.WCK1_P")
			(pinfunction "WCK1_t_A")
			(pintype "passive")
		)
		(pad "E13" smd circle
			(at 4 -4.2 90)
			(size 0.41 0.41)
			(layers "F.Cu" "F.Mask" "F.Paste")
			(net 14 "GND")
			(pinfunction "VSS")
			(pintype "passive")
		)
		(pad "E14" smd circle
			(at 4.8 -4.2 90)
			(size 0.41 0.41)
			(layers "F.Cu" "F.Mask" "F.Paste")
			(net 139 "/LPDDR5/LPDDR5_A.DQ10")
			(pinfunction "DQ10_A")
			(pintype "passive")
		)
		(pad "E15" smd circle
			(at 5.6 -4.2 90)
			(size 0.41 0.41)
			(layers "F.Cu" "F.Mask" "F.Paste")
			(net 14 "GND")
			(pinfunction "VSS")
			(pintype "passive")
		)
		(pad "F1" smd circle
			(at -5.6 -3.5 90)
			(size 0.41 0.41)
			(layers "F.Cu" "F.Mask" "F.Paste")
			(net 4 "+0V5")
			(pinfunction "VDDQ")
			(pintype "passive")
		)
		(pad "F2" smd circle
			(at -4.8 -3.5 90)
			(size 0.41 0.41)
			(layers "F.Cu" "F.Mask" "F.Paste")
			(net 14 "GND")
			(pinfunction "VSS")
			(pintype "passive")
		)
		(pad "F3" smd circle
			(at -4 -3.5 90)
			(size 0.41 0.41)
			(layers "F.Cu" "F.Mask" "F.Paste")
			(net 4 "+0V5")
			(pinfunction "VDDQ")
			(pintype "passive")
		)
		(pad "F4" smd circle
			(at -3.2 -3.5 90)
			(size 0.41 0.41)
			(layers "F.Cu" "F.Mask" "F.Paste")
			(net 4 "+0V5")
			(pinfunction "VDDQ")
			(pintype "passive")
		)
		(pad "F5" smd circle
			(at -2.4 -3.5 90)
			(size 0.41 0.41)
			(layers "F.Cu" "F.Mask" "F.Paste")
			(net 195 "/LPDDR5/LPDDR5_A.DQ7")
			(pinfunction "DQ7_A")
			(pintype "passive")
		)
		(pad "F6" smd circle
			(at -1.6 -3.5 90)
			(size 0.41 0.41)
			(layers "F.Cu" "F.Mask" "F.Paste")
			(net 13 "+1V05")
			(pinfunction "VDD2H")
			(pintype "passive")
		)
		(pad "F7" smd circle
			(at -0.8 -3.5 90)
			(size 0.41 0.41)
			(layers "F.Cu" "F.Mask" "F.Paste")
			(net 13 "+1V05")
			(pinfunction "VDD2H")
			(pintype "passive")
		)
		(pad "F8" smd circle
			(at 0 -3.5 90)
			(size 0.41 0.41)
			(layers "F.Cu" "F.Mask" "F.Paste")
			(net 14 "GND")
			(pinfunction "VSS")
			(pintype "passive")
		)
		(pad "F9" smd circle
			(at 0.8 -3.5 90)
			(size 0.41 0.41)
			(layers "F.Cu" "F.Mask" "F.Paste")
			(net 13 "+1V05")
			(pinfunction "VDD2H")
			(pintype "passive")
		)
		(pad "F10" smd circle
			(at 1.6 -3.5 90)
			(size 0.41 0.41)
			(layers "F.Cu" "F.Mask" "F.Paste")
			(net 13 "+1V05")
			(pinfunction "VDD2H")
			(pintype "passive")
		)
		(pad "F11" smd circle
			(at 2.4 -3.5 90)
			(size 0.41 0.41)
			(layers "F.Cu" "F.Mask" "F.Paste")
			(net 191 "/LPDDR5/LPDDR5_A.DQ15")
			(pinfunction "DQ15_A")
			(pintype "passive")
		)
		(pad "F12" smd circle
			(at 3.2 -3.5 90)
			(size 0.41 0.41)
			(layers "F.Cu" "F.Mask" "F.Paste")
			(net 4 "+0V5")
			(pinfunction "VDDQ")
			(pintype "passive")
		)
		(pad "F13" smd circle
			(at 4 -3.5 90)
			(size 0.41 0.41)
			(layers "F.Cu" "F.Mask" "F.Paste")
			(net 4 "+0V5")
			(pinfunction "VDDQ")
			(pintype "passive")
		)
		(pad "F14" smd circle
			(at 4.8 -3.5 90)
			(size 0.41 0.41)
			(layers "F.Cu" "F.Mask" "F.Paste")
			(net 14 "GND")
			(pinfunction "VSS")
			(pintype "passive")
		)
		(pad "F15" smd circle
			(at 5.6 -3.5 90)
			(size 0.41 0.41)
			(layers "F.Cu" "F.Mask" "F.Paste")
			(net 4 "+0V5")
			(pinfunction "VDDQ")
			(pintype "passive")
		)
		(pad "G1" smd circle
			(at -5.6 -2.8 90)
			(size 0.41 0.41)
			(layers "F.Cu" "F.Mask" "F.Paste")
			(net 4 "+0V5")
			(pinfunction "VDDQ")
			(pintype "passive")
		)
		(pad "G2" smd circle
			(at -4.8 -2.8 90)
			(size 0.41 0.41)
			(layers "F.Cu" "F.Mask" "F.Paste")
			(net 4 "+0V5")
			(pinfunction "VDDQ")
			(pintype "passive")
		)
		(pad "G3" smd circle
			(at -4 -2.8 90)
			(size 0.41 0.41)
			(layers "F.Cu" "F.Mask" "F.Paste")
			(net 14 "GND")
			(pinfunction "VSS")
			(pintype "passive")
		)
		(pad "G4" smd circle
			(at -3.2 -2.8 90)
			(size 0.41 0.41)
			(layers "F.Cu" "F.Mask" "F.Paste")
			(net 57 "/LPDDR5/LPDDR5_A.CA0")
			(pinfunction "CA0_A")
			(pintype "passive")
		)
		(pad "G5" smd circle
			(at -2.4 -2.8 90)
			(size 0.41 0.41)
			(layers "F.Cu" "F.Mask" "F.Paste")
			(net 14 "GND")
			(pinfunction "VSS")
			(pintype "passive")
		)
		(pad "G6" smd circle
			(at -1.6 -2.8 90)
			(size 0.41 0.41)
			(layers "F.Cu" "F.Mask" "F.Paste")
			(net 44 "/LPDDR5/LPDDR5_A.CS1")
			(pinfunction "CS1_A")
			(pintype "passive")
		)
		(pad "G7" smd circle
			(at -0.8 -2.8 90)
			(size 0.41 0.41)
			(layers "F.Cu" "F.Mask" "F.Paste")
			(net 14 "GND")
			(pinfunction "VSS")
			(pintype "passive")
		)
		(pad "G8" smd circle
			(at 0 -2.8 90)
			(size 0.41 0.41)
			(layers "F.Cu" "F.Mask" "F.Paste")
			(net 59 "/LPDDR5/LPDDR5_A.CA2")
			(pinfunction "CA2_A")
			(pintype "passive")
		)
		(pad "G9" smd circle
			(at 0.8 -2.8 90)
			(size 0.41 0.41)
			(layers "F.Cu" "F.Mask" "F.Paste")
			(net 14 "GND")
			(pinfunction "VSS")
			(pintype "passive")
		)
		(pad "G10" smd circle
			(at 1.6 -2.8 90)
			(size 0.41 0.41)
			(layers "F.Cu" "F.Mask" "F.Paste")
			(net 60 "/LPDDR5/LPDDR5_A.CA4")
			(pinfunction "CA4_A")
			(pintype "passive")
		)
		(pad "G11" smd circle
			(at 2.4 -2.8 90)
			(size 0.41 0.41)
			(layers "F.Cu" "F.Mask" "F.Paste")
			(net 14 "GND")
			(pinfunction "VSS")
			(pintype "passive")
		)
		(pad "G12" smd circle
			(at 3.2 -2.8 90)
			(size 0.41 0.41)
			(layers "F.Cu" "F.Mask" "F.Paste")
			(net 55 "/LPDDR5/LPDDR5_A.CA6")
			(pinfunction "CA6_A")
			(pintype "passive")
		)
		(pad "G13" smd circle
			(at 4 -2.8 90)
			(size 0.41 0.41)
			(layers "F.Cu" "F.Mask" "F.Paste")
			(net 14 "GND")
			(pinfunction "VSS")
			(pintype "passive")
		)
		(pad "G14" smd circle
			(at 4.8 -2.8 90)
			(size 0.41 0.41)
			(layers "F.Cu" "F.Mask" "F.Paste")
			(net 4 "+0V5")
			(pinfunction "VDDQ")
			(pintype "passive")
		)
		(pad "G15" smd circle
			(at 5.6 -2.8 90)
			(size 0.41 0.41)
			(layers "F.Cu" "F.Mask" "F.Paste")
			(net 4 "+0V5")
			(pinfunction "VDDQ")
			(pintype "passive")
		)
		(pad "H1" smd circle
			(at -5.6 -2.1 90)
			(size 0.41 0.41)
			(layers "F.Cu" "F.Mask" "F.Paste")
			(net 40 "/LPDDR5/~{RESET}")
			(pinfunction "RESET_n")
			(pintype "passive")
		)
		(pad "H2" smd circle
			(at -4.8 -2.1 90)
			(size 0.41 0.41)
			(layers "F.Cu" "F.Mask" "F.Paste")
			(net 12 "+0V9")
			(pinfunction "VDD2L")
			(pintype "passive")
		)
		(pad "H3" smd circle
			(at -4 -2.1 90)
			(size 0.41 0.41)
			(layers "F.Cu" "F.Mask" "F.Paste")
			(net 14 "GND")
			(pinfunction "VSS")
			(pintype "passive")
		)
		(pad "H4" smd circle
			(at -3.2 -2.1 90)
			(size 0.41 0.41)
			(layers "F.Cu" "F.Mask" "F.Paste")
			(net 14 "GND")
			(pinfunction "VSS")
			(pintype "passive")
		)
		(pad "H5" smd circle
			(at -2.4 -2.1 90)
			(size 0.41 0.41)
			(layers "F.Cu" "F.Mask" "F.Paste")
			(net 58 "/LPDDR5/LPDDR5_A.CA1")
			(pinfunction "CA1_A")
			(pintype "passive")
		)
		(pad "H6" smd circle
			(at -1.6 -2.1 90)
			(size 0.41 0.41)
			(layers "F.Cu" "F.Mask" "F.Paste")
			(net 14 "GND")
			(pinfunction "VSS")
			(pintype "passive")
		)
		(pad "H7" smd circle
			(at -0.8 -2.1 90)
			(size 0.41 0.41)
			(layers "F.Cu" "F.Mask" "F.Paste")
			(net 43 "/LPDDR5/LPDDR5_A.CS0")
			(pinfunction "CS0_A")
			(pintype "passive")
		)
		(pad "H8" smd circle
			(at 0 -2.1 90)
			(size 0.41 0.41)
			(layers "F.Cu" "F.Mask" "F.Paste")
			(net 14 "GND")
			(pinfunction "VSS")
			(pintype "passive")
		)
		(pad "H9" smd circle
			(at 0.8 -2.1 90)
			(size 0.41 0.41)
			(layers "F.Cu" "F.Mask" "F.Paste")
			(net 49 "/LPDDR5/LPDDR5_A.CK_P")
			(pinfunction "CK_t_A")
			(pintype "passive")
		)
		(pad "H10" smd circle
			(at 1.6 -2.1 90)
			(size 0.41 0.41)
			(layers "F.Cu" "F.Mask" "F.Paste")
			(net 14 "GND")
			(pinfunction "VSS")
			(pintype "passive")
		)
		(pad "H11" smd circle
			(at 2.4 -2.1 90)
			(size 0.41 0.41)
			(layers "F.Cu" "F.Mask" "F.Paste")
			(net 54 "/LPDDR5/LPDDR5_A.CA3")
			(pinfunction "CA3_A")
			(pintype "passive")
		)
		(pad "H12" smd circle
			(at 3.2 -2.1 90)
			(size 0.41 0.41)
			(layers "F.Cu" "F.Mask" "F.Paste")
			(net 14 "GND")
			(pinfunction "VSS")
			(pintype "passive")
		)
		(pad "H13" smd circle
			(at 4 -2.1 90)
			(size 0.41 0.41)
			(layers "F.Cu" "F.Mask" "F.Paste")
			(net 56 "/LPDDR5/LPDDR5_A.CA5")
			(pinfunction "CA5_A")
			(pintype "passive")
		)
		(pad "H14" smd circle
			(at 4.8 -2.1 90)
			(size 0.41 0.41)
			(layers "F.Cu" "F.Mask" "F.Paste")
			(net 12 "+0V9")
			(pinfunction "VDD2L")
			(pintype "passive")
		)
		(pad "H15" smd circle
			(at 5.6 -2.1 90)
			(size 0.41 0.41)
			(layers "F.Cu" "F.Mask" "F.Paste")
			(net 92 "Net-(R69-Pad2)")
			(pinfunction "ZQ_A")
			(pintype "passive")
		)
		(pad "J1" smd circle
			(at -5.6 -1.4 90)
			(size 0.41 0.41)
			(layers "F.Cu" "F.Mask" "F.Paste")
			(net 14 "GND")
			(pinfunction "VSS")
			(pintype "passive")
		)
		(pad "J2" smd circle
			(at -4.8 -1.4 90)
			(size 0.41 0.41)
			(layers "F.Cu" "F.Mask" "F.Paste")
			(net 12 "+0V9")
			(pinfunction "VDD2L")
			(pintype "passive")
		)
		(pad "J3" smd circle
			(at -4 -1.4 90)
			(size 0.41 0.41)
			(layers "F.Cu" "F.Mask" "F.Paste")
			(net 14 "GND")
			(pinfunction "VSS")
			(pintype "passive")
		)
		(pad "J4" smd circle
			(at -3.2 -1.4 90)
			(size 0.41 0.41)
			(layers "F.Cu" "F.Mask" "F.Paste")
			(net 29 "unconnected-(U1-PadJ4)")
			(pinfunction "RFU")
			(pintype "no_connect")
		)
		(pad "J5" smd circle
			(at -2.4 -1.4 90)
			(size 0.41 0.41)
			(layers "F.Cu" "F.Mask" "F.Paste")
			(net 13 "+1V05")
			(pinfunction "VDD2H")
			(pintype "passive")
		)
		(pad "J6" smd circle
			(at -1.6 -1.4 90)
			(size 0.41 0.41)
			(layers "F.Cu" "F.Mask" "F.Paste")
			(net 30 "unconnected-(U1-PadJ6)")
			(pinfunction "RFU")
			(pintype "no_connect")
		)
		(pad "J7" smd circle
			(at -0.8 -1.4 90)
			(size 0.41 0.41)
			(layers "F.Cu" "F.Mask" "F.Paste")
			(net 14 "GND")
			(pinfunction "VSS")
			(pintype "passive")
		)
		(pad "J8" smd circle
			(at 0 -1.4 90)
			(size 0.41 0.41)
			(layers "F.Cu" "F.Mask" "F.Paste")
			(net 14 "GND")
			(pinfunction "VSS")
			(pintype "passive")
		)
		(pad "J9" smd circle
			(at 0.8 -1.4 90)
			(size 0.41 0.41)
			(layers "F.Cu" "F.Mask" "F.Paste")
			(net 50 "/LPDDR5/LPDDR5_A.CK_N")
			(pinfunction "CK_c_A")
			(pintype "passive")
		)
		(pad "J10" smd circle
			(at 1.6 -1.4 90)
			(size 0.41 0.41)
			(layers "F.Cu" "F.Mask" "F.Paste")
			(net 14 "GND")
			(pinfunction "VSS")
			(pintype "passive")
		)
		(pad "J11" smd circle
			(at 2.4 -1.4 90)
			(size 0.41 0.41)
			(layers "F.Cu" "F.Mask" "F.Paste")
			(net 13 "+1V05")
			(pinfunction "VDD2H")
			(pintype "passive")
		)
		(pad "J12" smd circle
			(at 3.2 -1.4 90)
			(size 0.41 0.41)
			(layers "F.Cu" "F.Mask" "F.Paste")
			(net 14 "GND")
			(pinfunction "VSS")
			(pintype "passive")
		)
		(pad "J13" smd circle
			(at 4 -1.4 90)
			(size 0.41 0.41)
			(layers "F.Cu" "F.Mask" "F.Paste")
			(net 14 "GND")
			(pinfunction "VSS")
			(pintype "passive")
		)
		(pad "J14" smd circle
			(at 4.8 -1.4 90)
			(size 0.41 0.41)
			(layers "F.Cu" "F.Mask" "F.Paste")
			(net 12 "+0V9")
			(pinfunction "VDD2L")
			(pintype "passive")
		)
		(pad "J15" smd circle
			(at 5.6 -1.4 90)
			(size 0.41 0.41)
			(layers "F.Cu" "F.Mask" "F.Paste")
			(net 14 "GND")
			(pinfunction "VSS")
			(pintype "passive")
		)
		(pad "K1" smd circle
			(at -5.6 -0.7 90)
			(size 0.41 0.41)
			(layers "F.Cu" "F.Mask" "F.Paste")
			(net 13 "+1V05")
			(pinfunction "VDD2H")
			(pintype "passive")
		)
		(pad "K2" smd circle
			(at -4.8 -0.7 90)
			(size 0.41 0.41)
			(layers "F.Cu" "F.Mask" "F.Paste")
			(net 13 "+1V05")
			(pinfunction "VDD2H")
			(pintype "passive")
		)
		(pad "K3" smd circle
			(at -4 -0.7 90)
			(size 0.41 0.41)
			(layers "F.Cu" "F.Mask" "F.Paste")
			(net 13 "+1V05")
			(pinfunction "VDD2H")
			(pintype "passive")
		)
		(pad "K4" smd circle
			(at -3.2 -0.7 90)
			(size 0.41 0.41)
			(layers "F.Cu" "F.Mask" "F.Paste")
			(net 13 "+1V05")
			(pinfunction "VDD2H")
			(pintype "passive")
		)
		(pad "K5" smd circle
			(at -2.4 -0.7 90)
			(size 0.41 0.41)
			(layers "F.Cu" "F.Mask" "F.Paste")
			(net 13 "+1V05")
			(pinfunction "VDD2H")
			(pintype "passive")
		)
		(pad "K6" smd circle
			(at -1.6 -0.7 90)
			(size 0.41 0.41)
			(layers "F.Cu" "F.Mask" "F.Paste")
			(net 13 "+1V05")
			(pinfunction "VDD2H")
			(pintype "passive")
		)
		(pad "K7" smd circle
			(at -0.8 -0.7 90)
			(size 0.41 0.41)
			(layers "F.Cu" "F.Mask" "F.Paste")
			(net 14 "GND")
			(pinfunction "VSS")
			(pintype "passive")
		)
		(pad "K8" smd circle
			(at 0 -0.7 90)
			(size 0.41 0.41)
			(layers "F.Cu" "F.Mask" "F.Paste")
			(net 14 "GND")
			(pinfunction "VSS")
			(pintype "passive")
		)
		(pad "K9" smd circle
			(at 0.8 -0.7 90)
			(size 0.41 0.41)
			(layers "F.Cu" "F.Mask" "F.Paste")
			(net 14 "GND")
			(pinfunction "VSS")
			(pintype "passive")
		)
		(pad "K10" smd circle
			(at 1.6 -0.7 90)
			(size 0.41 0.41)
			(layers "F.Cu" "F.Mask" "F.Paste")
			(net 13 "+1V05")
			(pinfunction "VDD2H")
			(pintype "passive")
		)
		(pad "K11" smd circle
			(at 2.4 -0.7 90)
			(size 0.41 0.41)
			(layers "F.Cu" "F.Mask" "F.Paste")
			(net 13 "+1V05")
			(pinfunction "VDD2H")
			(pintype "passive")
		)
		(pad "K12" smd circle
			(at 3.2 -0.7 90)
			(size 0.41 0.41)
			(layers "F.Cu" "F.Mask" "F.Paste")
			(net 13 "+1V05")
			(pinfunction "VDD2H")
			(pintype "passive")
		)
		(pad "K13" smd circle
			(at 4 -0.7 90)
			(size 0.41 0.41)
			(layers "F.Cu" "F.Mask" "F.Paste")
			(net 13 "+1V05")
			(pinfunction "VDD2H")
			(pintype "passive")
		)
		(pad "K14" smd circle
			(at 4.8 -0.7 90)
			(size 0.41 0.41)
			(layers "F.Cu" "F.Mask" "F.Paste")
			(net 13 "+1V05")
			(pinfunction "VDD2H")
			(pintype "passive")
		)
		(pad "K15" smd circle
			(at 5.6 -0.7 90)
			(size 0.41 0.41)
			(layers "F.Cu" "F.Mask" "F.Paste")
			(net 13 "+1V05")
			(pinfunction "VDD2H")
			(pintype "passive")
		)
		(pad "L1" smd circle
			(at -5.6 0 90)
			(size 0.41 0.41)
			(layers "F.Cu" "F.Mask" "F.Paste")
			(net 14 "GND")
			(pinfunction "VSS")
			(pintype "passive")
		)
		(pad "L2" smd circle
			(at -4.8 0 90)
			(size 0.41 0.41)
			(layers "F.Cu" "F.Mask" "F.Paste")
			(net 14 "GND")
			(pinfunction "VSS")
			(pintype "passive")
		)
		(pad "L3" smd circle
			(at -4 0 90)
			(size 0.41 0.41)
			(layers "F.Cu" "F.Mask" "F.Paste")
			(net 14 "GND")
			(pinfunction "VSS")
			(pintype "passive")
		)
		(pad "L4" smd circle
			(at -3.2 0 90)
			(size 0.41 0.41)
			(layers "F.Cu" "F.Mask" "F.Paste")
			(net 14 "GND")
			(pinfunction "VSS")
			(pintype "passive")
		)
		(pad "L5" smd circle
			(at -2.4 0 90)
			(size 0.41 0.41)
			(layers "F.Cu" "F.Mask" "F.Paste")
			(net 14 "GND")
			(pinfunction "VSS")
			(pintype "passive")
		)
		(pad "L6" smd circle
			(at -1.6 0 90)
			(size 0.41 0.41)
			(layers "F.Cu" "F.Mask" "F.Paste")
			(net 13 "+1V05")
			(pinfunction "VDD2H")
			(pintype "passive")
		)
		(pad "L7" smd circle
			(at -0.8 0 90)
			(size 0.41 0.41)
			(layers "F.Cu" "F.Mask" "F.Paste")
			(net 13 "+1V05")
			(pinfunction "VDD2H")
			(pintype "passive")
		)
		(pad "L8" smd circle
			(at 0 0 90)
			(size 0.41 0.41)
			(layers "F.Cu" "F.Mask" "F.Paste")
			(net 13 "+1V05")
			(pinfunction "VDD2H")
			(pintype "passive")
		)
		(pad "L9" smd circle
			(at 0.8 0 90)
			(size 0.41 0.41)
			(layers "F.Cu" "F.Mask" "F.Paste")
			(net 13 "+1V05")
			(pinfunction "VDD2H")
			(pintype "passive")
		)
		(pad "L10" smd circle
			(at 1.6 0 90)
			(size 0.41 0.41)
			(layers "F.Cu" "F.Mask" "F.Paste")
			(net 13 "+1V05")
			(pinfunction "VDD2H")
			(pintype "passive")
		)
		(pad "L11" smd circle
			(at 2.4 0 90)
			(size 0.41 0.41)
			(layers "F.Cu" "F.Mask" "F.Paste")
			(net 14 "GND")
			(pinfunction "VSS")
			(pintype "passive")
		)
		(pad "L12" smd circle
			(at 3.2 0 90)
			(size 0.41 0.41)
			(layers "F.Cu" "F.Mask" "F.Paste")
			(net 14 "GND")
			(pinfunction "VSS")
			(pintype "passive")
		)
		(pad "L13" smd circle
			(at 4 0 90)
			(size 0.41 0.41)
			(layers "F.Cu" "F.Mask" "F.Paste")
			(net 14 "GND")
			(pinfunction "VSS")
			(pintype "passive")
		)
		(pad "L14" smd circle
			(at 4.8 0 90)
			(size 0.41 0.41)
			(layers "F.Cu" "F.Mask" "F.Paste")
			(net 14 "GND")
			(pinfunction "VSS")
			(pintype "passive")
		)
		(pad "L15" smd circle
			(at 5.6 0 90)
			(size 0.41 0.41)
			(layers "F.Cu" "F.Mask" "F.Paste")
			(net 14 "GND")
			(pinfunction "VSS")
			(pintype "passive")
		)
		(pad "M1" smd circle
			(at -5.6 0.7 90)
			(size 0.41 0.41)
			(layers "F.Cu" "F.Mask" "F.Paste")
			(net 13 "+1V05")
			(pinfunction "VDD2H")
			(pintype "passive")
		)
		(pad "M2" smd circle
			(at -4.8 0.7 90)
			(size 0.41 0.41)
			(layers "F.Cu" "F.Mask" "F.Paste")
			(net 13 "+1V05")
			(pinfunction "VDD2H")
			(pintype "passive")
		)
		(pad "M3" smd circle
			(at -4 0.7 90)
			(size 0.41 0.41)
			(layers "F.Cu" "F.Mask" "F.Paste")
			(net 13 "+1V05")
			(pinfunction "VDD2H")
			(pintype "passive")
		)
		(pad "M4" smd circle
			(at -3.2 0.7 90)
			(size 0.41 0.41)
			(layers "F.Cu" "F.Mask" "F.Paste")
			(net 13 "+1V05")
			(pinfunction "VDD2H")
			(pintype "passive")
		)
		(pad "M5" smd circle
			(at -2.4 0.7 90)
			(size 0.41 0.41)
			(layers "F.Cu" "F.Mask" "F.Paste")
			(net 13 "+1V05")
			(pinfunction "VDD2H")
			(pintype "passive")
		)
		(pad "M6" smd circle
			(at -1.6 0.7 90)
			(size 0.41 0.41)
			(layers "F.Cu" "F.Mask" "F.Paste")
			(net 13 "+1V05")
			(pinfunction "VDD2H")
			(pintype "passive")
		)
		(pad "M7" smd circle
			(at -0.8 0.7 90)
			(size 0.41 0.41)
			(layers "F.Cu" "F.Mask" "F.Paste")
			(net 14 "GND")
			(pinfunction "VSS")
			(pintype "passive")
		)
		(pad "M8" smd circle
			(at 0 0.7 90)
			(size 0.41 0.41)
			(layers "F.Cu" "F.Mask" "F.Paste")
			(net 14 "GND")
			(pinfunction "VSS")
			(pintype "passive")
		)
		(pad "M9" smd circle
			(at 0.8 0.7 90)
			(size 0.41 0.41)
			(layers "F.Cu" "F.Mask" "F.Paste")
			(net 14 "GND")
			(pinfunction "VSS")
			(pintype "passive")
		)
		(pad "M10" smd circle
			(at 1.6 0.7 90)
			(size 0.41 0.41)
			(layers "F.Cu" "F.Mask" "F.Paste")
			(net 13 "+1V05")
			(pinfunction "VDD2H")
			(pintype "passive")
		)
		(pad "M11" smd circle
			(at 2.4 0.7 90)
			(size 0.41 0.41)
			(layers "F.Cu" "F.Mask" "F.Paste")
			(net 13 "+1V05")
			(pinfunction "VDD2H")
			(pintype "passive")
		)
		(pad "M12" smd circle
			(at 3.2 0.7 90)
			(size 0.41 0.41)
			(layers "F.Cu" "F.Mask" "F.Paste")
			(net 13 "+1V05")
			(pinfunction "VDD2H")
			(pintype "passive")
		)
		(pad "M13" smd circle
			(at 4 0.7 90)
			(size 0.41 0.41)
			(layers "F.Cu" "F.Mask" "F.Paste")
			(net 13 "+1V05")
			(pinfunction "VDD2H")
			(pintype "passive")
		)
		(pad "M14" smd circle
			(at 4.8 0.7 90)
			(size 0.41 0.41)
			(layers "F.Cu" "F.Mask" "F.Paste")
			(net 13 "+1V05")
			(pinfunction "VDD2H")
			(pintype "passive")
		)
		(pad "M15" smd circle
			(at 5.6 0.7 90)
			(size 0.41 0.41)
			(layers "F.Cu" "F.Mask" "F.Paste")
			(net 13 "+1V05")
			(pinfunction "VDD2H")
			(pintype "passive")
		)
		(pad "N1" smd circle
			(at -5.6 1.4 90)
			(size 0.41 0.41)
			(layers "F.Cu" "F.Mask" "F.Paste")
			(net 14 "GND")
			(pinfunction "VSS")
			(pintype "passive")
		)
		(pad "N2" smd circle
			(at -4.8 1.4 90)
			(size 0.41 0.41)
			(layers "F.Cu" "F.Mask" "F.Paste")
			(net 12 "+0V9")
			(pinfunction "VDD2L")
			(pintype "passive")
		)
		(pad "N3" smd circle
			(at -4 1.4 90)
			(size 0.41 0.41)
			(layers "F.Cu" "F.Mask" "F.Paste")
			(net 14 "GND")
			(pinfunction "VSS")
			(pintype "passive")
		)
		(pad "N4" smd circle
			(at -3.2 1.4 90)
			(size 0.41 0.41)
			(layers "F.Cu" "F.Mask" "F.Paste")
			(net 14 "GND")
			(pinfunction "VSS")
			(pintype "passive")
		)
		(pad "N5" smd circle
			(at -2.4 1.4 90)
			(size 0.41 0.41)
			(layers "F.Cu" "F.Mask" "F.Paste")
			(net 13 "+1V05")
			(pinfunction "VDD2H")
			(pintype "passive")
		)
		(pad "N6" smd circle
			(at -1.6 1.4 90)
			(size 0.41 0.41)
			(layers "F.Cu" "F.Mask" "F.Paste")
			(net 14 "GND")
			(pinfunction "VSS")
			(pintype "passive")
		)
		(pad "N7" smd circle
			(at -0.8 1.4 90)
			(size 0.41 0.41)
			(layers "F.Cu" "F.Mask" "F.Paste")
			(net 113 "/LPDDR5/LPDDR5_B.CK_N")
			(pinfunction "CK_c_B")
			(pintype "passive")
		)
		(pad "N8" smd circle
			(at 0 1.4 90)
			(size 0.41 0.41)
			(layers "F.Cu" "F.Mask" "F.Paste")
			(net 14 "GND")
			(pinfunction "VSS")
			(pintype "passive")
		)
		(pad "N9" smd circle
			(at 0.8 1.4 90)
			(size 0.41 0.41)
			(layers "F.Cu" "F.Mask" "F.Paste")
			(net 14 "GND")
			(pinfunction "VSS")
			(pintype "passive")
		)
		(pad "N10" smd circle
			(at 1.6 1.4 90)
			(size 0.41 0.41)
			(layers "F.Cu" "F.Mask" "F.Paste")
			(net 14 "GND")
			(pinfunction "VSS")
			(pintype "passive")
		)
		(pad "N11" smd circle
			(at 2.4 1.4 90)
			(size 0.41 0.41)
			(layers "F.Cu" "F.Mask" "F.Paste")
			(net 13 "+1V05")
			(pinfunction "VDD2H")
			(pintype "passive")
		)
		(pad "N12" smd circle
			(at 3.2 1.4 90)
			(size 0.41 0.41)
			(layers "F.Cu" "F.Mask" "F.Paste")
			(net 14 "GND")
			(pinfunction "VSS")
			(pintype "passive")
		)
		(pad "N13" smd circle
			(at 4 1.4 90)
			(size 0.41 0.41)
			(layers "F.Cu" "F.Mask" "F.Paste")
			(net 14 "GND")
			(pinfunction "VSS")
			(pintype "passive")
		)
		(pad "N14" smd circle
			(at 4.8 1.4 90)
			(size 0.41 0.41)
			(layers "F.Cu" "F.Mask" "F.Paste")
			(net 12 "+0V9")
			(pinfunction "VDD2L")
			(pintype "passive")
		)
		(pad "N15" smd circle
			(at 5.6 1.4 90)
			(size 0.41 0.41)
			(layers "F.Cu" "F.Mask" "F.Paste")
			(net 14 "GND")
			(pinfunction "VSS")
			(pintype "passive")
		)
		(pad "P1" smd circle
			(at -5.6 2.1 90)
			(size 0.41 0.41)
			(layers "F.Cu" "F.Mask" "F.Paste")
			(net 31 "unconnected-(U1-PadP1)")
			(pinfunction "RFU")
			(pintype "no_connect")
		)
		(pad "P2" smd circle
			(at -4.8 2.1 90)
			(size 0.41 0.41)
			(layers "F.Cu" "F.Mask" "F.Paste")
			(net 12 "+0V9")
			(pinfunction "VDD2L")
			(pintype "passive")
		)
		(pad "P3" smd circle
			(at -4 2.1 90)
			(size 0.41 0.41)
			(layers "F.Cu" "F.Mask" "F.Paste")
			(net 101 "/LPDDR5/LPDDR5_B.CA5")
			(pinfunction "CA5_B")
			(pintype "passive")
		)
		(pad "P4" smd circle
			(at -3.2 2.1 90)
			(size 0.41 0.41)
			(layers "F.Cu" "F.Mask" "F.Paste")
			(net 14 "GND")
			(pinfunction "VSS")
			(pintype "passive")
		)
		(pad "P5" smd circle
			(at -2.4 2.1 90)
			(size 0.41 0.41)
			(layers "F.Cu" "F.Mask" "F.Paste")
			(net 99 "/LPDDR5/LPDDR5_B.CA3")
			(pinfunction "CA3_B")
			(pintype "passive")
		)
		(pad "P6" smd circle
			(at -1.6 2.1 90)
			(size 0.41 0.41)
			(layers "F.Cu" "F.Mask" "F.Paste")
			(net 14 "GND")
			(pinfunction "VSS")
			(pintype "passive")
		)
		(pad "P7" smd circle
			(at -0.8 2.1 90)
			(size 0.41 0.41)
			(layers "F.Cu" "F.Mask" "F.Paste")
			(net 112 "/LPDDR5/LPDDR5_B.CK_P")
			(pinfunction "CK_t_B")
			(pintype "passive")
		)
		(pad "P8" smd circle
			(at 0 2.1 90)
			(size 0.41 0.41)
			(layers "F.Cu" "F.Mask" "F.Paste")
			(net 14 "GND")
			(pinfunction "VSS")
			(pintype "passive")
		)
		(pad "P9" smd circle
			(at 0.8 2.1 90)
			(size 0.41 0.41)
			(layers "F.Cu" "F.Mask" "F.Paste")
			(net 106 "/LPDDR5/LPDDR5_B.CS0")
			(pinfunction "CS0_B")
			(pintype "passive")
		)
		(pad "P10" smd circle
			(at 1.6 2.1 90)
			(size 0.41 0.41)
			(layers "F.Cu" "F.Mask" "F.Paste")
			(net 14 "GND")
			(pinfunction "VSS")
			(pintype "passive")
		)
		(pad "P11" smd circle
			(at 2.4 2.1 90)
			(size 0.41 0.41)
			(layers "F.Cu" "F.Mask" "F.Paste")
			(net 103 "/LPDDR5/LPDDR5_B.CA1")
			(pinfunction "CA1_B")
			(pintype "passive")
		)
		(pad "P12" smd circle
			(at 3.2 2.1 90)
			(size 0.41 0.41)
			(layers "F.Cu" "F.Mask" "F.Paste")
			(net 14 "GND")
			(pinfunction "VSS")
			(pintype "passive")
		)
		(pad "P13" smd circle
			(at 4 2.1 90)
			(size 0.41 0.41)
			(layers "F.Cu" "F.Mask" "F.Paste")
			(net 14 "GND")
			(pinfunction "VSS")
			(pintype "passive")
		)
		(pad "P14" smd circle
			(at 4.8 2.1 90)
			(size 0.41 0.41)
			(layers "F.Cu" "F.Mask" "F.Paste")
			(net 12 "+0V9")
			(pinfunction "VDD2L")
			(pintype "passive")
		)
		(pad "P15" smd circle
			(at 5.6 2.1 90)
			(size 0.41 0.41)
			(layers "F.Cu" "F.Mask" "F.Paste")
			(net 32 "unconnected-(U1-PadP15)")
			(pinfunction "RFU")
			(pintype "no_connect")
		)
		(pad "R1" smd circle
			(at -5.6 2.8 90)
			(size 0.41 0.41)
			(layers "F.Cu" "F.Mask" "F.Paste")
			(net 4 "+0V5")
			(pinfunction "VDDQ")
			(pintype "passive")
		)
		(pad "R2" smd circle
			(at -4.8 2.8 90)
			(size 0.41 0.41)
			(layers "F.Cu" "F.Mask" "F.Paste")
			(net 4 "+0V5")
			(pinfunction "VDDQ")
			(pintype "passive")
		)
		(pad "R3" smd circle
			(at -4 2.8 90)
			(size 0.41 0.41)
			(layers "F.Cu" "F.Mask" "F.Paste")
			(net 14 "GND")
			(pinfunction "VSS")
			(pintype "passive")
		)
		(pad "R4" smd circle
			(at -3.2 2.8 90)
			(size 0.41 0.41)
			(layers "F.Cu" "F.Mask" "F.Paste")
			(net 100 "/LPDDR5/LPDDR5_B.CA6")
			(pinfunction "CA6_B")
			(pintype "passive")
		)
		(pad "R5" smd circle
			(at -2.4 2.8 90)
			(size 0.41 0.41)
			(layers "F.Cu" "F.Mask" "F.Paste")
			(net 14 "GND")
			(pinfunction "VSS")
			(pintype "passive")
		)
		(pad "R6" smd circle
			(at -1.6 2.8 90)
			(size 0.41 0.41)
			(layers "F.Cu" "F.Mask" "F.Paste")
			(net 105 "/LPDDR5/LPDDR5_B.CA4")
			(pinfunction "CA4_B")
			(pintype "passive")
		)
		(pad "R7" smd circle
			(at -0.8 2.8 90)
			(size 0.41 0.41)
			(layers "F.Cu" "F.Mask" "F.Paste")
			(net 14 "GND")
			(pinfunction "VSS")
			(pintype "passive")
		)
		(pad "R8" smd circle
			(at 0 2.8 90)
			(size 0.41 0.41)
			(layers "F.Cu" "F.Mask" "F.Paste")
			(net 104 "/LPDDR5/LPDDR5_B.CA2")
			(pinfunction "CA2_B")
			(pintype "passive")
		)
		(pad "R9" smd circle
			(at 0.8 2.8 90)
			(size 0.41 0.41)
			(layers "F.Cu" "F.Mask" "F.Paste")
			(net 14 "GND")
			(pinfunction "VSS")
			(pintype "passive")
		)
		(pad "R10" smd circle
			(at 1.6 2.8 90)
			(size 0.41 0.41)
			(layers "F.Cu" "F.Mask" "F.Paste")
			(net 107 "/LPDDR5/LPDDR5_B.CS1")
			(pinfunction "CS1_B")
			(pintype "passive")
		)
		(pad "R11" smd circle
			(at 2.4 2.8 90)
			(size 0.41 0.41)
			(layers "F.Cu" "F.Mask" "F.Paste")
			(net 14 "GND")
			(pinfunction "VSS")
			(pintype "passive")
		)
		(pad "R12" smd circle
			(at 3.2 2.8 90)
			(size 0.41 0.41)
			(layers "F.Cu" "F.Mask" "F.Paste")
			(net 102 "/LPDDR5/LPDDR5_B.CA0")
			(pinfunction "CA0_B")
			(pintype "passive")
		)
		(pad "R13" smd circle
			(at 4 2.8 90)
			(size 0.41 0.41)
			(layers "F.Cu" "F.Mask" "F.Paste")
			(net 14 "GND")
			(pinfunction "VSS")
			(pintype "passive")
		)
		(pad "R14" smd circle
			(at 4.8 2.8 90)
			(size 0.41 0.41)
			(layers "F.Cu" "F.Mask" "F.Paste")
			(net 4 "+0V5")
			(pinfunction "VDDQ")
			(pintype "passive")
		)
		(pad "R15" smd circle
			(at 5.6 2.8 90)
			(size 0.41 0.41)
			(layers "F.Cu" "F.Mask" "F.Paste")
			(net 4 "+0V5")
			(pinfunction "VDDQ")
			(pintype "passive")
		)
		(pad "T1" smd circle
			(at -5.6 3.5 90)
			(size 0.41 0.41)
			(layers "F.Cu" "F.Mask" "F.Paste")
			(net 4 "+0V5")
			(pinfunction "VDDQ")
			(pintype "passive")
		)
		(pad "T2" smd circle
			(at -4.8 3.5 90)
			(size 0.41 0.41)
			(layers "F.Cu" "F.Mask" "F.Paste")
			(net 14 "GND")
			(pinfunction "VSS")
			(pintype "passive")
		)
		(pad "T3" smd circle
			(at -4 3.5 90)
			(size 0.41 0.41)
			(layers "F.Cu" "F.Mask" "F.Paste")
			(net 4 "+0V5")
			(pinfunction "VDDQ")
			(pintype "passive")
		)
		(pad "T4" smd circle
			(at -3.2 3.5 90)
			(size 0.41 0.41)
			(layers "F.Cu" "F.Mask" "F.Paste")
			(net 4 "+0V5")
			(pinfunction "VDDQ")
			(pintype "passive")
		)
		(pad "T5" smd circle
			(at -2.4 3.5 90)
			(size 0.41 0.41)
			(layers "F.Cu" "F.Mask" "F.Paste")
			(net 216 "/LPDDR5/LPDDR5_B.DQ15")
			(pinfunction "DQ15_B")
			(pintype "passive")
		)
		(pad "T6" smd circle
			(at -1.6 3.5 90)
			(size 0.41 0.41)
			(layers "F.Cu" "F.Mask" "F.Paste")
			(net 13 "+1V05")
			(pinfunction "VDD2H")
			(pintype "passive")
		)
		(pad "T7" smd circle
			(at -0.8 3.5 90)
			(size 0.41 0.41)
			(layers "F.Cu" "F.Mask" "F.Paste")
			(net 13 "+1V05")
			(pinfunction "VDD2H")
			(pintype "passive")
		)
		(pad "T8" smd circle
			(at 0 3.5 90)
			(size 0.41 0.41)
			(layers "F.Cu" "F.Mask" "F.Paste")
			(net 14 "GND")
			(pinfunction "VSS")
			(pintype "passive")
		)
		(pad "T9" smd circle
			(at 0.8 3.5 90)
			(size 0.41 0.41)
			(layers "F.Cu" "F.Mask" "F.Paste")
			(net 13 "+1V05")
			(pinfunction "VDD2H")
			(pintype "passive")
		)
		(pad "T10" smd circle
			(at 1.6 3.5 90)
			(size 0.41 0.41)
			(layers "F.Cu" "F.Mask" "F.Paste")
			(net 13 "+1V05")
			(pinfunction "VDD2H")
			(pintype "passive")
		)
		(pad "T11" smd circle
			(at 2.4 3.5 90)
			(size 0.41 0.41)
			(layers "F.Cu" "F.Mask" "F.Paste")
			(net 217 "/LPDDR5/LPDDR5_B.DQ7")
			(pinfunction "DQ7_B")
			(pintype "passive")
		)
		(pad "T12" smd circle
			(at 3.2 3.5 90)
			(size 0.41 0.41)
			(layers "F.Cu" "F.Mask" "F.Paste")
			(net 4 "+0V5")
			(pinfunction "VDDQ")
			(pintype "passive")
		)
		(pad "T13" smd circle
			(at 4 3.5 90)
			(size 0.41 0.41)
			(layers "F.Cu" "F.Mask" "F.Paste")
			(net 4 "+0V5")
			(pinfunction "VDDQ")
			(pintype "passive")
		)
		(pad "T14" smd circle
			(at 4.8 3.5 90)
			(size 0.41 0.41)
			(layers "F.Cu" "F.Mask" "F.Paste")
			(net 14 "GND")
			(pinfunction "VSS")
			(pintype "passive")
		)
		(pad "T15" smd circle
			(at 5.6 3.5 90)
			(size 0.41 0.41)
			(layers "F.Cu" "F.Mask" "F.Paste")
			(net 4 "+0V5")
			(pinfunction "VDDQ")
			(pintype "passive")
		)
		(pad "U1" smd circle
			(at -5.6 4.2 90)
			(size 0.41 0.41)
			(layers "F.Cu" "F.Mask" "F.Paste")
			(net 14 "GND")
			(pinfunction "VSS")
			(pintype "passive")
		)
		(pad "U2" smd circle
			(at -4.8 4.2 90)
			(size 0.41 0.41)
			(layers "F.Cu" "F.Mask" "F.Paste")
			(net 208 "/LPDDR5/LPDDR5_B.DQ10")
			(pinfunction "DQ10_B")
			(pintype "passive")
		)
		(pad "U3" smd circle
			(at -4 4.2 90)
			(size 0.41 0.41)
			(layers "F.Cu" "F.Mask" "F.Paste")
			(net 14 "GND")
			(pinfunction "VSS")
			(pintype "passive")
		)
		(pad "U4" smd circle
			(at -3.2 4.2 90)
			(size 0.41 0.41)
			(layers "F.Cu" "F.Mask" "F.Paste")
			(net 111 "/LPDDR5/LPDDR5_B.WCK1_P")
			(pinfunction "WCK1_t_B")
			(pintype "passive")
		)
		(pad "U5" smd circle
			(at -2.4 4.2 90)
			(size 0.41 0.41)
			(layers "F.Cu" "F.Mask" "F.Paste")
			(net 4 "+0V5")
			(pinfunction "VDDQ")
			(pintype "passive")
		)
		(pad "U6" smd circle
			(at -1.6 4.2 90)
			(size 0.41 0.41)
			(layers "F.Cu" "F.Mask" "F.Paste")
			(net 215 "/LPDDR5/LPDDR5_B.DQ14")
			(pinfunction "DQ14_B")
			(pintype "passive")
		)
		(pad "U7" smd circle
			(at -0.8 4.2 90)
			(size 0.41 0.41)
			(layers "F.Cu" "F.Mask" "F.Paste")
			(net 13 "+1V05")
			(pinfunction "VDD2H")
			(pintype "passive")
		)
		(pad "U8" smd circle
			(at 0 4.2 90)
			(size 0.41 0.41)
			(layers "F.Cu" "F.Mask" "F.Paste")
			(net 14 "GND")
			(pinfunction "VSS")
			(pintype "passive")
		)
		(pad "U9" smd circle
			(at 0.8 4.2 90)
			(size 0.41 0.41)
			(layers "F.Cu" "F.Mask" "F.Paste")
			(net 13 "+1V05")
			(pinfunction "VDD2H")
			(pintype "passive")
		)
		(pad "U10" smd circle
			(at 1.6 4.2 90)
			(size 0.41 0.41)
			(layers "F.Cu" "F.Mask" "F.Paste")
			(net 218 "/LPDDR5/LPDDR5_B.DQ6")
			(pinfunction "DQ6_B")
			(pintype "passive")
		)
		(pad "U11" smd circle
			(at 2.4 4.2 90)
			(size 0.41 0.41)
			(layers "F.Cu" "F.Mask" "F.Paste")
			(net 4 "+0V5")
			(pinfunction "VDDQ")
			(pintype "passive")
		)
		(pad "U12" smd circle
			(at 3.2 4.2 90)
			(size 0.41 0.41)
			(layers "F.Cu" "F.Mask" "F.Paste")
			(net 108 "/LPDDR5/LPDDR5_B.WCK0_P")
			(pinfunction "WCK0_t_B")
			(pintype "passive")
		)
		(pad "U13" smd circle
			(at 4 4.2 90)
			(size 0.41 0.41)
			(layers "F.Cu" "F.Mask" "F.Paste")
			(net 14 "GND")
			(pinfunction "VSS")
			(pintype "passive")
		)
		(pad "U14" smd circle
			(at 4.8 4.2 90)
			(size 0.41 0.41)
			(layers "F.Cu" "F.Mask" "F.Paste")
			(net 225 "/LPDDR5/LPDDR5_B.DQ2")
			(pinfunction "DQ2_B")
			(pintype "passive")
		)
		(pad "U15" smd circle
			(at 5.6 4.2 90)
			(size 0.41 0.41)
			(layers "F.Cu" "F.Mask" "F.Paste")
			(net 14 "GND")
			(pinfunction "VSS")
			(pintype "passive")
		)
		(pad "V1" smd circle
			(at -5.6 4.9 90)
			(size 0.41 0.41)
			(layers "F.Cu" "F.Mask" "F.Paste")
			(net 206 "/LPDDR5/LPDDR5_B.DQ8")
			(pinfunction "DQ8_B")
			(pintype "passive")
		)
		(pad "V2" smd circle
			(at -4.8 4.9 90)
			(size 0.41 0.41)
			(layers "F.Cu" "F.Mask" "F.Paste")
			(net 14 "GND")
			(pinfunction "VSS")
			(pintype "passive")
		)
		(pad "V3" smd circle
			(at -4 4.9 90)
			(size 0.41 0.41)
			(layers "F.Cu" "F.Mask" "F.Paste")
			(net 209 "/LPDDR5/LPDDR5_B.DQ11")
			(pinfunction "DQ11_B")
			(pintype "passive")
		)
		(pad "V4" smd circle
			(at -3.2 4.9 90)
			(size 0.41 0.41)
			(layers "F.Cu" "F.Mask" "F.Paste")
			(net 4 "+0V5")
			(pinfunction "VDDQ")
			(pintype "passive")
		)
		(pad "V5" smd circle
			(at -2.4 4.9 90)
			(size 0.41 0.41)
			(layers "F.Cu" "F.Mask" "F.Paste")
			(net 110 "/LPDDR5/LPDDR5_B.WCK1_N")
			(pinfunction "WCK1_c_B")
			(pintype "passive")
		)
		(pad "V6" smd circle
			(at -1.6 4.9 90)
			(size 0.41 0.41)
			(layers "F.Cu" "F.Mask" "F.Paste")
			(net 14 "GND")
			(pinfunction "VSS")
			(pintype "passive")
		)
		(pad "V7" smd circle
			(at -0.8 4.9 90)
			(size 0.41 0.41)
			(layers "F.Cu" "F.Mask" "F.Paste")
			(net 14 "GND")
			(pinfunction "VSS")
			(pintype "passive")
		)
		(pad "V8" smd circle
			(at 0 4.9 90)
			(size 0.41 0.41)
			(layers "F.Cu" "F.Mask" "F.Paste")
			(net 13 "+1V05")
			(pinfunction "VDD2H")
			(pintype "passive")
		)
		(pad "V9" smd circle
			(at 0.8 4.9 90)
			(size 0.41 0.41)
			(layers "F.Cu" "F.Mask" "F.Paste")
			(net 14 "GND")
			(pinfunction "VSS")
			(pintype "passive")
		)
		(pad "V10" smd circle
			(at 1.6 4.9 90)
			(size 0.41 0.41)
			(layers "F.Cu" "F.Mask" "F.Paste")
			(net 14 "GND")
			(pinfunction "VSS")
			(pintype "passive")
		)
		(pad "V11" smd circle
			(at 2.4 4.9 90)
			(size 0.41 0.41)
			(layers "F.Cu" "F.Mask" "F.Paste")
			(net 109 "/LPDDR5/LPDDR5_B.WCK0_N")
			(pinfunction "WCK0_c_B")
			(pintype "passive")
		)
		(pad "V12" smd circle
			(at 3.2 4.9 90)
			(size 0.41 0.41)
			(layers "F.Cu" "F.Mask" "F.Paste")
			(net 4 "+0V5")
			(pinfunction "VDDQ")
			(pintype "passive")
		)
		(pad "V13" smd circle
			(at 4 4.9 90)
			(size 0.41 0.41)
			(layers "F.Cu" "F.Mask" "F.Paste")
			(net 224 "/LPDDR5/LPDDR5_B.DQ3")
			(pinfunction "DQ3_B")
			(pintype "passive")
		)
		(pad "V14" smd circle
			(at 4.8 4.9 90)
			(size 0.41 0.41)
			(layers "F.Cu" "F.Mask" "F.Paste")
			(net 14 "GND")
			(pinfunction "VSS")
			(pintype "passive")
		)
		(pad "V15" smd circle
			(at 5.6 4.9 90)
			(size 0.41 0.41)
			(layers "F.Cu" "F.Mask" "F.Paste")
			(net 227 "/LPDDR5/LPDDR5_B.DQ0")
			(pinfunction "DQ0_B")
			(pintype "passive")
		)
		(pad "W1" smd circle
			(at -5.6 5.6 90)
			(size 0.41 0.41)
			(layers "F.Cu" "F.Mask" "F.Paste")
			(net 35 "+1V8")
			(pinfunction "VDD1")
			(pintype "passive")
		)
		(pad "W2" smd circle
			(at -4.8 5.6 90)
			(size 0.41 0.41)
			(layers "F.Cu" "F.Mask" "F.Paste")
			(net 207 "/LPDDR5/LPDDR5_B.DQ9")
			(pinfunction "DQ9_B")
			(pintype "passive")
		)
		(pad "W3" smd circle
			(at -4 5.6 90)
			(size 0.41 0.41)
			(layers "F.Cu" "F.Mask" "F.Paste")
			(net 4 "+0V5")
			(pinfunction "VDDQ")
			(pintype "passive")
		)
		(pad "W4" smd circle
			(at -3.2 5.6 90)
			(size 0.41 0.41)
			(layers "F.Cu" "F.Mask" "F.Paste")
			(net 210 "/LPDDR5/LPDDR5_B.RDQS1_N")
			(pinfunction "RDQS1_c_B")
			(pintype "passive")
		)
		(pad "W5" smd circle
			(at -2.4 5.6 90)
			(size 0.41 0.41)
			(layers "F.Cu" "F.Mask" "F.Paste")
			(net 14 "GND")
			(pinfunction "VSS")
			(pintype "passive")
		)
		(pad "W6" smd circle
			(at -1.6 5.6 90)
			(size 0.41 0.41)
			(layers "F.Cu" "F.Mask" "F.Paste")
			(net 214 "/LPDDR5/LPDDR5_B.DQ13")
			(pinfunction "DQ13_B")
			(pintype "passive")
		)
		(pad "W7" smd circle
			(at -0.8 5.6 90)
			(size 0.41 0.41)
			(layers "F.Cu" "F.Mask" "F.Paste")
			(net 13 "+1V05")
			(pinfunction "VDD2H")
			(pintype "passive")
		)
		(pad "W8" smd circle
			(at 0 5.6 90)
			(size 0.41 0.41)
			(layers "F.Cu" "F.Mask" "F.Paste")
			(net 14 "GND")
			(pinfunction "VSS")
			(pintype "passive")
		)
		(pad "W9" smd circle
			(at 0.8 5.6 90)
			(size 0.41 0.41)
			(layers "F.Cu" "F.Mask" "F.Paste")
			(net 13 "+1V05")
			(pinfunction "VDD2H")
			(pintype "passive")
		)
		(pad "W10" smd circle
			(at 1.6 5.6 90)
			(size 0.41 0.41)
			(layers "F.Cu" "F.Mask" "F.Paste")
			(net 219 "/LPDDR5/LPDDR5_B.DQ5")
			(pinfunction "DQ5_B")
			(pintype "passive")
		)
		(pad "W11" smd circle
			(at 2.4 5.6 90)
			(size 0.41 0.41)
			(layers "F.Cu" "F.Mask" "F.Paste")
			(net 14 "GND")
			(pinfunction "VSS")
			(pintype "passive")
		)
		(pad "W12" smd circle
			(at 3.2 5.6 90)
			(size 0.41 0.41)
			(layers "F.Cu" "F.Mask" "F.Paste")
			(net 221 "/LPDDR5/LPDDR5_B.RDQS0_N")
			(pinfunction "RDQS0_c_B")
			(pintype "passive")
		)
		(pad "W13" smd circle
			(at 4 5.6 90)
			(size 0.41 0.41)
			(layers "F.Cu" "F.Mask" "F.Paste")
			(net 4 "+0V5")
			(pinfunction "VDDQ")
			(pintype "passive")
		)
		(pad "W14" smd circle
			(at 4.8 5.6 90)
			(size 0.41 0.41)
			(layers "F.Cu" "F.Mask" "F.Paste")
			(net 226 "/LPDDR5/LPDDR5_B.DQ1")
			(pinfunction "DQ1_B")
			(pintype "passive")
		)
		(pad "W15" smd circle
			(at 5.6 5.6 90)
			(size 0.41 0.41)
			(layers "F.Cu" "F.Mask" "F.Paste")
			(net 35 "+1V8")
			(pinfunction "VDD1")
			(pintype "passive")
		)
		(pad "Y1" smd circle
			(at -5.6 6.3 90)
			(size 0.41 0.41)
			(layers "F.Cu" "F.Mask" "F.Paste")
			(net 36 "unconnected-(U1-PadY1)")
			(pinfunction "NC")
			(pintype "no_connect")
		)
		(pad "Y2" smd circle
			(at -4.8 6.3 90)
			(size 0.41 0.41)
			(layers "F.Cu" "F.Mask" "F.Paste")
			(net 4 "+0V5")
			(pinfunction "VDDQ")
			(pintype "passive")
		)
		(pad "Y3" smd circle
			(at -4 6.3 90)
			(size 0.41 0.41)
			(layers "F.Cu" "F.Mask" "F.Paste")
			(net 211 "/LPDDR5/LPDDR5_B.RDQS1_P")
			(pinfunction "RDQS1_t_B")
			(pintype "passive")
		)
		(pad "Y4" smd circle
			(at -3.2 6.3 90)
			(size 0.41 0.41)
			(layers "F.Cu" "F.Mask" "F.Paste")
			(net 14 "GND")
			(pinfunction "VSS")
			(pintype "passive")
		)
		(pad "Y5" smd circle
			(at -2.4 6.3 90)
			(size 0.41 0.41)
			(layers "F.Cu" "F.Mask" "F.Paste")
			(net 213 "/LPDDR5/LPDDR5_B.DQ12")
			(pinfunction "DQ12_B")
			(pintype "passive")
		)
		(pad "Y6" smd circle
			(at -1.6 6.3 90)
			(size 0.41 0.41)
			(layers "F.Cu" "F.Mask" "F.Paste")
			(net 12 "+0V9")
			(pinfunction "VDD2L")
			(pintype "passive")
		)
		(pad "Y7" smd circle
			(at -0.8 6.3 90)
			(size 0.41 0.41)
			(layers "F.Cu" "F.Mask" "F.Paste")
			(net 13 "+1V05")
			(pinfunction "VDD2H")
			(pintype "passive")
		)
		(pad "Y8" smd circle
			(at 0 6.3 90)
			(size 0.41 0.41)
			(layers "F.Cu" "F.Mask" "F.Paste")
			(net 14 "GND")
			(pinfunction "VSS")
			(pintype "passive")
		)
		(pad "Y9" smd circle
			(at 0.8 6.3 90)
			(size 0.41 0.41)
			(layers "F.Cu" "F.Mask" "F.Paste")
			(net 13 "+1V05")
			(pinfunction "VDD2H")
			(pintype "passive")
		)
		(pad "Y10" smd circle
			(at 1.6 6.3 90)
			(size 0.41 0.41)
			(layers "F.Cu" "F.Mask" "F.Paste")
			(net 12 "+0V9")
			(pinfunction "VDD2L")
			(pintype "passive")
		)
		(pad "Y11" smd circle
			(at 2.4 6.3 90)
			(size 0.41 0.41)
			(layers "F.Cu" "F.Mask" "F.Paste")
			(net 220 "/LPDDR5/LPDDR5_B.DQ4")
			(pinfunction "DQ4_B")
			(pintype "passive")
		)
		(pad "Y12" smd circle
			(at 3.2 6.3 90)
			(size 0.41 0.41)
			(layers "F.Cu" "F.Mask" "F.Paste")
			(net 14 "GND")
			(pinfunction "VSS")
			(pintype "passive")
		)
		(pad "Y13" smd circle
			(at 4 6.3 90)
			(size 0.41 0.41)
			(layers "F.Cu" "F.Mask" "F.Paste")
			(net 222 "/LPDDR5/LPDDR5_B.RDQS0_P")
			(pinfunction "RDQS0_t_B")
			(pintype "passive")
		)
		(pad "Y14" smd circle
			(at 4.8 6.3 90)
			(size 0.41 0.41)
			(layers "F.Cu" "F.Mask" "F.Paste")
			(net 4 "+0V5")
			(pinfunction "VDDQ")
			(pintype "passive")
		)
		(pad "Y15" smd circle
			(at 5.6 6.3 90)
			(size 0.41 0.41)
			(layers "F.Cu" "F.Mask" "F.Paste")
			(net 37 "unconnected-(U1-PadY15)")
			(pinfunction "NC")
			(pintype "no_connect")
		)
	)
	(footprint "antmicro-footprints:R_0402_1005Metric"
		(layer "F.Cu")
		(at 136.65 93.85 90)
		(descr "Resistor SMD 0402")
		(tags "resistor SMD 0402")
		(property "Reference" "R70"
			(at -1.122484 -0.772697 90)
			(unlocked yes)
			(layer "F.SilkS")
			(effects
				(font
					(size 0.7 0.7)
					(thickness 0.15)
				)
				(justify left bottom)
			)
		)
		(property "Value" "R_100R_0402"
			(at -1.011843 1.772047 90)
			(layer "F.Fab")
			(effects
				(font
					(size 0.7 0.7)
					(thickness 0.15)
				)
				(justify left bottom)
			)
		)
		(property "Author" "Antmicro"
			(at 230.5 -42.8 0)
			(layer "F.Fab")
			(hide yes)
			(effects
				(font
					(size 1 1)
					(thickness 0.15)
				)
			)
		)
		(property "License" "Apache-2.0"
			(at 230.5 -42.8 0)
			(layer "F.Fab")
			(hide yes)
			(effects
				(font
					(size 1 1)
					(thickness 0.15)
				)
			)
		)
		(property "MPN" "CR0402-FX-1000GLF"
			(at 230.5 -42.8 0)
			(layer "F.Fab")
			(hide yes)
			(effects
				(font
					(size 1 1)
					(thickness 0.15)
				)
			)
		)
		(property "Manufacturer" "Bourns"
			(at 230.5 -42.8 0)
			(layer "F.Fab")
			(hide yes)
			(effects
				(font
					(size 1 1)
					(thickness 0.15)
				)
			)
		)
		(property "Tolerance" "1%"
			(at 230.5 -42.8 0)
			(layer "F.Fab")
			(hide yes)
			(effects
				(font
					(size 1 1)
					(thickness 0.15)
				)
			)
		)
		(property "Val" "100R"
			(at 230.5 -42.8 0)
			(layer "F.Fab")
			(hide yes)
			(effects
				(font
					(size 1 1)
					(thickness 0.15)
				)
			)
		)
		(sheetname "Translators1")
		(sheetfile "translators.kicad_sch")
		(attr smd)
		(fp_rect
			(start -0.93 -0.47)
			(end 0.93 0.47)
			(stroke
				(width 0.05)
				(type solid)
			)
			(fill no)
			(layer "F.CrtYd")
		)
		(fp_rect
			(start -0.5 -0.25)
			(end 0.5 0.25)
			(stroke
				(width 0.15)
				(type solid)
			)
			(fill no)
			(layer "F.Fab")
		)
		(pad "1" smd roundrect
			(at -0.485 0 90)
			(size 0.59 0.64)
			(layers "F.Cu" "F.Mask" "F.Paste")
			(roundrect_rratio 0.25)
			(net 154 "/SODIMM/LPDDR5_IN_B.CK_P")
			(pintype "passive")
		)
		(pad "2" smd roundrect
			(at 0.485 0 90)
			(size 0.59 0.64)
			(layers "F.Cu" "F.Mask" "F.Paste")
			(roundrect_rratio 0.25)
			(net 112 "/LPDDR5/LPDDR5_B.CK_P")
			(pintype "passive")
		)
	)
	(footprint "antmicro-footprints:C_0402_1005Metric"
		(layer "F.Cu")
		(at 164.475 71.65 180)
		(descr "Capacitor SMD 0402")
		(tags "capacitor SMD 0402")
		(property "Reference" "C21"
			(at -1.125 -2.65 0)
			(unlocked yes)
			(layer "F.SilkS")
			(effects
				(font
					(size 0.7 0.7)
					(thickness 0.15)
				)
				(justify right bottom)
			)
		)
		(property "Value" "C_4u7_0402"
			(at -1.022927 2.155213 0)
			(layer "F.Fab")
			(effects
				(font
					(size 0.7 0.7)
					(thickness 0.15)
				)
				(justify right bottom)
			)
		)
		(property "Author" "Antmicro"
			(at 328.95 143.3 0)
			(layer "F.Fab")
			(hide yes)
			(effects
				(font
					(size 1 1)
					(thickness 0.15)
				)
			)
		)
		(property "Dielectric" ""
			(at 328.95 143.3 0)
			(layer "F.Fab")
			(hide yes)
			(effects
				(font
					(size 1 1)
					(thickness 0.15)
				)
			)
		)
		(property "License" "Apache-2.0"
			(at 328.95 143.3 0)
			(layer "F.Fab")
			(hide yes)
			(effects
				(font
					(size 1 1)
					(thickness 0.15)
				)
			)
		)
		(property "MPN" "GRM155R61A475MEAAD"
			(at 328.95 143.3 0)
			(layer "F.Fab")
			(hide yes)
			(effects
				(font
					(size 1 1)
					(thickness 0.15)
				)
			)
		)
		(property "Manufacturer" "Murata"
			(at 328.95 143.3 0)
			(layer "F.Fab")
			(hide yes)
			(effects
				(font
					(size 1 1)
					(thickness 0.15)
				)
			)
		)
		(property "Val" "4u7"
			(at 328.95 143.3 0)
			(layer "F.Fab")
			(hide yes)
			(effects
				(font
					(size 1 1)
					(thickness 0.15)
				)
			)
		)
		(property "Voltage" ""
			(at 328.95 143.3 0)
			(layer "F.Fab")
			(hide yes)
			(effects
				(font
					(size 1 1)
					(thickness 0.15)
				)
			)
		)
		(sheetname "Power supply")
		(sheetfile "power_supply.kicad_sch")
		(attr smd)
		(fp_rect
			(start -0.9659 -0.481258)
			(end 0.9649 0.458742)
			(stroke
				(width 0.05)
				(type solid)
			)
			(fill no)
			(layer "F.CrtYd")
		)
		(fp_line
			(start 0.499 0.248)
			(end -0.499 0.248)
			(stroke
				(width 0.15)
				(type solid)
			)
			(layer "F.Fab")
		)
		(fp_line
			(start 0.499 -0.25)
			(end 0.499 0.248)
			(stroke
				(width 0.15)
				(type solid)
			)
			(layer "F.Fab")
		)
		(fp_line
			(start -0.499 0.248)
			(end -0.499 -0.25)
			(stroke
				(width 0.15)
				(type solid)
			)
			(layer "F.Fab")
		)
		(fp_line
			(start -0.499 -0.25)
			(end 0.499 -0.25)
			(stroke
				(width 0.15)
				(type solid)
			)
			(layer "F.Fab")
		)
		(pad "1" smd roundrect
			(at -0.484 0 180)
			(size 0.59 0.64)
			(layers "F.Cu" "F.Mask" "F.Paste")
			(roundrect_rratio 0.25)
			(net 14 "GND")
			(pintype "passive")
		)
		(pad "2" smd roundrect
			(at 0.484 0 180)
			(size 0.59 0.64)
			(layers "F.Cu" "F.Mask" "F.Paste")
			(roundrect_rratio 0.25)
			(net 11 "/Power supply/VOUT")
			(pintype "passive")
		)
	)
	(footprint "antmicro-footprints:C_0603_1608Metric"
		(layer "F.Cu")
		(at 111.875 69.825 -90)
		(descr "Capacitor SMD 0603")
		(tags "capacitor 0603")
		(property "Reference" "C18"
			(at -2.025 -2.125 90)
			(unlocked yes)
			(layer "F.SilkS")
			(effects
				(font
					(size 0.7 0.7)
					(thickness 0.15)
				)
				(justify right bottom)
			)
		)
		(property "Value" "C_22u_0603"
			(at -1.42757 1.770288 90)
			(layer "F.Fab")
			(effects
				(font
					(size 0.7 0.7)
					(thickness 0.15)
				)
				(justify right bottom)
			)
		)
		(property "Author" "Antmicro"
			(at 42.05 181.7 0)
			(layer "F.Fab")
			(hide yes)
			(effects
				(font
					(size 1 1)
					(thickness 0.15)
				)
			)
		)
		(property "Dielectric" ""
			(at 42.05 181.7 0)
			(layer "F.Fab")
			(hide yes)
			(effects
				(font
					(size 1 1)
					(thickness 0.15)
				)
			)
		)
		(property "License" "Apache-2.0"
			(at 42.05 181.7 0)
			(layer "F.Fab")
			(hide yes)
			(effects
				(font
					(size 1 1)
					(thickness 0.15)
				)
			)
		)
		(property "MPN" "GRM188R60J226MEA0D"
			(at 42.05 181.7 0)
			(layer "F.Fab")
			(hide yes)
			(effects
				(font
					(size 1 1)
					(thickness 0.15)
				)
			)
		)
		(property "Manufacturer" "Murata"
			(at 42.05 181.7 0)
			(layer "F.Fab")
			(hide yes)
			(effects
				(font
					(size 1 1)
					(thickness 0.15)
				)
			)
		)
		(property "Val" "22u"
			(at 42.05 181.7 0)
			(layer "F.Fab")
			(hide yes)
			(effects
				(font
					(size 1 1)
					(thickness 0.15)
				)
			)
		)
		(property "Voltage" ""
			(at 42.05 181.7 0)
			(layer "F.Fab")
			(hide yes)
			(effects
				(font
					(size 1 1)
					(thickness 0.15)
				)
			)
		)
		(sheetname "Power supply")
		(sheetfile "power_supply.kicad_sch")
		(attr smd)
		(fp_line
			(start -0.3 0.3)
			(end 0.3 0.3)
			(stroke
				(width 0.15)
				(type solid)
			)
			(layer "F.SilkS")
		)
		(fp_line
			(start -0.3 -0.3)
			(end 0.3 -0.3)
			(stroke
				(width 0.15)
				(type solid)
			)
			(layer "F.SilkS")
		)
		(fp_rect
			(start -1.24 -0.7)
			(end 1.24 0.7)
			(stroke
				(width 0.05)
				(type solid)
			)
			(fill no)
			(layer "F.CrtYd")
		)
		(fp_rect
			(start -0.8 -0.4)
			(end 0.8 0.4)
			(stroke
				(width 0.15)
				(type solid)
			)
			(fill no)
			(layer "F.Fab")
		)
		(pad "1" smd roundrect
			(at -0.7 0 270)
			(size 0.6 0.8)
			(layers "F.Cu" "F.Mask" "F.Paste")
			(roundrect_rratio 0.2)
			(net 14 "GND")
			(pintype "passive")
		)
		(pad "2" smd roundrect
			(at 0.7 0 270)
			(size 0.6 0.8)
			(layers "F.Cu" "F.Mask" "F.Paste")
			(roundrect_rratio 0.2)
			(net 9 "/Power supply/VOUT3")
			(pintype "passive")
		)
	)
	(footprint "lpddr5-testbed-footprints:Edge_Conn_Bus_DDR5_SODIMM"
		(locked yes)
		(layer "F.Cu")
		(at 99.975 100)
		(descr "SODIMM DDR5 Edge Connector")
		(tags "SODIMM DDR5 Edge Connector")
		(property "Reference" "J1"
			(at 0 -4.2 0)
			(unlocked yes)
			(layer "F.SilkS")
			(effects
				(font
					(size 0.7 0.7)
					(thickness 0.15)
				)
				(justify left bottom)
			)
		)
		(property "Value" "Edge_Conn_Bus_DDR5_SODIMM_1xDetectPin"
			(at 0 1 0)
			(layer "F.Fab")
			(effects
				(font
					(size 0.7 0.7)
					(thickness 0.15)
				)
				(justify left bottom)
			)
		)
		(property "Author" "Antmicro"
			(at 0 0 0)
			(layer "F.Fab")
			(hide yes)
			(effects
				(font
					(size 1 1)
					(thickness 0.15)
				)
			)
		)
		(property "License" "Apache-2.0"
			(at 0 0 0)
			(layer "F.Fab")
			(hide yes)
			(effects
				(font
					(size 1 1)
					(thickness 0.15)
				)
			)
		)
		(property "MPN" ""
			(at 0 0 0)
			(layer "F.Fab")
			(hide yes)
			(effects
				(font
					(size 1 1)
					(thickness 0.15)
				)
			)
		)
		(property "Manufacturer" ""
			(at 0 0 0)
			(layer "F.Fab")
			(hide yes)
			(effects
				(font
					(size 1 1)
					(thickness 0.15)
				)
			)
		)
		(sheetname "SODIMM")
		(sheetfile "sodim.kicad_sch")
		(attr exclude_from_pos_files)
		(fp_line
			(start 1.1 -3.6)
			(end 1.3 -2.9)
			(stroke
				(width 0.12)
				(type solid)
			)
			(layer "F.SilkS")
		)
		(fp_line
			(start 1.3 -3.6)
			(end 1.3 -3.1)
			(stroke
				(width 0.12)
				(type solid)
			)
			(layer "F.SilkS")
		)
		(fp_line
			(start 1.3 -3.1)
			(end 1.2 -3.5)
			(stroke
				(width 0.12)
				(type solid)
			)
			(layer "F.SilkS")
		)
		(fp_line
			(start 1.3 -3.1)
			(end 1.4 -3.5)
			(stroke
				(width 0.12)
				(type solid)
			)
			(layer "F.SilkS")
		)
		(fp_line
			(start 1.3 -2.9)
			(end 1.5 -3.6)
			(stroke
				(width 0.12)
				(type solid)
			)
			(layer "F.SilkS")
		)
		(fp_line
			(start 1.5 -3.6)
			(end 1.1 -3.6)
			(stroke
				(width 0.12)
				(type solid)
			)
			(layer "F.SilkS")
		)
		(fp_line
			(start 0 -29.25)
			(end 0 -22)
			(stroke
				(width 0.15)
				(type solid)
			)
			(layer "Edge.Cuts")
		)
		(fp_line
			(start 0 -0.75)
			(end 0 -18)
			(stroke
				(width 0.15)
				(type solid)
			)
			(layer "Edge.Cuts")
		)
		(fp_line
			(start 0 -0.75)
			(end 0.75 0)
			(stroke
				(width 0.15)
				(type solid)
			)
			(layer "Edge.Cuts")
		)
		(fp_line
			(start 0.75 0)
			(end 32.875 0)
			(stroke
				(width 0.15)
				(type solid)
			)
			(layer "Edge.Cuts")
		)
		(fp_line
			(start 1.099854 -22.000147)
			(end 0 -22)
			(stroke
				(width 0.15)
				(type solid)
			)
			(layer "Edge.Cuts")
		)
		(fp_line
			(start 1.1 -18)
			(end 0 -18)
			(stroke
				(width 0.15)
				(type solid)
			)
			(layer "Edge.Cuts")
		)
		(fp_line
			(start 1.749854 -21.351147)
			(end 1.749 -18.65)
			(stroke
				(width 0.15)
				(type solid)
			)
			(layer "Edge.Cuts")
		)
		(fp_line
			(start 33.05 -0.175)
			(end 32.875 0)
			(stroke
				(width 0.15)
				(type solid)
			)
			(layer "Edge.Cuts")
		)
		(fp_line
			(start 33.05 -0.175)
			(end 33.05 -3.5)
			(stroke
				(width 0.15)
				(type solid)
			)
			(layer "Edge.Cuts")
		)
		(fp_line
			(start 34.05 -0.175)
			(end 34.05 -3.5)
			(stroke
				(width 0.15)
				(type solid)
			)
			(layer "Edge.Cuts")
		)
		(fp_line
			(start 34.05 -0.175)
			(end 34.225 0)
			(stroke
				(width 0.15)
				(type solid)
			)
			(layer "Edge.Cuts")
		)
		(fp_line
			(start 34.225 0)
			(end 68.85 0)
			(stroke
				(width 0.15)
				(type solid)
			)
			(layer "Edge.Cuts")
		)
		(fp_line
			(start 67.849 -18.65)
			(end 67.85 -21.35)
			(stroke
				(width 0.15)
				(type solid)
			)
			(layer "Edge.Cuts")
		)
		(fp_line
			(start 68.499 -18.001)
			(end 69.6 -18)
			(stroke
				(width 0.15)
				(type solid)
			)
			(layer "Edge.Cuts")
		)
		(fp_line
			(start 69.6 -21.999)
			(end 68.499 -22)
			(stroke
				(width 0.15)
				(type solid)
			)
			(layer "Edge.Cuts")
		)
		(fp_line
			(start 69.6 -21.999)
			(end 69.6 -29.25)
			(stroke
				(width 0.15)
				(type solid)
			)
			(layer "Edge.Cuts")
		)
		(fp_line
			(start 69.6 -0.75)
			(end 68.85 0)
			(stroke
				(width 0.15)
				(type solid)
			)
			(layer "Edge.Cuts")
		)
		(fp_line
			(start 69.6 -0.75)
			(end 69.6 -18)
			(stroke
				(width 0.15)
				(type solid)
			)
			(layer "Edge.Cuts")
		)
		(fp_arc
			(start 1.099854 -22.000147)
			(mid 1.558994 -21.809993)
			(end 1.749854 -21.351147)
			(stroke
				(width 0.15)
				(type solid)
			)
			(layer "Edge.Cuts")
		)
		(fp_arc
			(start 1.749 -18.65)
			(mid 1.558853 -18.190854)
			(end 1.1 -18)
			(stroke
				(width 0.15)
				(type solid)
			)
			(layer "Edge.Cuts")
		)
		(fp_arc
			(start 33.05 -3.5)
			(mid 33.55 -4)
			(end 34.05 -3.5)
			(stroke
				(width 0.15)
				(type solid)
			)
			(layer "Edge.Cuts")
		)
		(fp_arc
			(start 67.85 -21.35)
			(mid 68.040144 -21.809149)
			(end 68.499 -22)
			(stroke
				(width 0.15)
				(type solid)
			)
			(layer "Edge.Cuts")
		)
		(fp_arc
			(start 68.499 -18.001)
			(mid 68.039851 -18.191144)
			(end 67.849 -18.65)
			(stroke
				(width 0.15)
				(type solid)
			)
			(layer "Edge.Cuts")
		)
		(fp_rect
			(start 0 -4.1)
			(end 69.6 0)
			(stroke
				(width 0.05)
				(type solid)
			)
			(fill no)
			(layer "F.CrtYd")
		)
		(pad "" np_thru_hole circle
			(at 1.1 -6)
			(size 1.5 1.5)
			(drill 1.5)
			(layers "*.Mask")
		)
		(pad "" np_thru_hole circle
			(at 68.51 -6)
			(size 1.6 1.6)
			(drill 1.6)
			(layers "*.Mask")
		)
		(pad "1" smd rect
			(at 1.425 -1.375)
			(size 0.35 2.35)
			(layers "F.Cu" "F.Mask")
			(net 5 "+5V")
			(pinfunction "VIN_BULK")
			(pintype "passive")
		)
		(pad "2" smd rect
			(at 1.675 -1.375 180)
			(size 0.35 2.35)
			(layers "B.Cu" "B.Mask")
			(net 116 "unconnected-(J1-Pad2)")
			(pinfunction "HSA")
			(pintype "passive+no_connect")
		)
		(pad "3" smd rect
			(at 1.925 -1.375)
			(size 0.35 2.35)
			(layers "F.Cu" "F.Mask")
			(net 5 "+5V")
			(pinfunction "VIN_BULK")
			(pintype "passive")
		)
		(pad "4" smd rect
			(at 2.175 -1.375 180)
			(size 0.35 2.35)
			(layers "B.Cu" "B.Mask")
			(net 18 "/SODIMM/HSCL")
			(pinfunction "HSCL")
			(pintype "passive")
		)
		(pad "5" smd rect
			(at 2.425 -1.375)
			(size 0.35 2.35)
			(layers "F.Cu" "F.Mask")
			(net 42 "unconnected-(J1-Pad5)")
			(pinfunction "RFU")
			(pintype "passive+no_connect")
		)
		(pad "6" smd rect
			(at 2.675 -1.375 180)
			(size 0.35 2.35)
			(layers "B.Cu" "B.Mask")
			(net 19 "/SODIMM/HSDA")
			(pinfunction "HSDA")
			(pintype "passive")
		)
		(pad "7" smd rect
			(at 2.925 -1.375)
			(size 0.35 2.35)
			(layers "F.Cu" "F.Mask")
			(net 41 "/Power supply/PWRGD")
			(pinfunction "PWR_GOOD")
			(pintype "passive")
		)
		(pad "8" smd rect
			(at 3.175 -1.375 180)
			(size 0.35 2.35)
			(layers "B.Cu" "B.Mask")
			(net 20 "/Power supply/PWR_EN")
			(pinfunction "PWR_EN")
			(pintype "passive")
		)
		(pad "9" smd rect
			(at 3.425 -1.375)
			(size 0.35 2.35)
			(layers "F.Cu" "F.Mask")
			(net 14 "GND")
			(pinfunction "VSS")
			(pintype "passive")
		)
		(pad "10" smd rect
			(at 3.675 -1.375 180)
			(size 0.35 2.35)
			(layers "B.Cu" "B.Mask")
			(net 14 "GND")
			(pinfunction "VSS")
			(pintype "passive")
		)
		(pad "11" smd rect
			(at 3.925 -1.375)
			(size 0.35 2.35)
			(layers "F.Cu" "F.Mask")
			(net 187 "/SODIMM/LPDDR5_IN_A.DQ8")
			(pinfunction "DQ0_A")
			(pintype "passive")
		)
		(pad "12" smd rect
			(at 4.175 -1.375 180)
			(size 0.35 2.35)
			(layers "B.Cu" "B.Mask")
			(net 185 "/SODIMM/LPDDR5_IN_A.DQ10")
			(pinfunction "DQ1_A")
			(pintype "passive")
		)
		(pad "13" smd rect
			(at 4.425 -1.375)
			(size 0.35 2.35)
			(layers "F.Cu" "F.Mask")
			(net 14 "GND")
			(pinfunction "VSS")
			(pintype "passive")
		)
		(pad "14" smd rect
			(at 4.675 -1.375 180)
			(size 0.35 2.35)
			(layers "B.Cu" "B.Mask")
			(net 14 "GND")
			(pinfunction "VSS")
			(pintype "passive")
		)
		(pad "15" smd rect
			(at 4.925 -1.375)
			(size 0.35 2.35)
			(layers "F.Cu" "F.Mask")
			(net 186 "/SODIMM/LPDDR5_IN_A.DQ9")
			(pinfunction "DQ2_A")
			(pintype "passive")
		)
		(pad "16" smd rect
			(at 5.175 -1.375 180)
			(size 0.35 2.35)
			(layers "B.Cu" "B.Mask")
			(net 184 "/SODIMM/LPDDR5_IN_A.DQ11")
			(pinfunction "DQ3_A")
			(pintype "passive")
		)
		(pad "17" smd rect
			(at 5.425 -1.375)
			(size 0.35 2.35)
			(layers "F.Cu" "F.Mask")
			(net 14 "GND")
			(pinfunction "VSS")
			(pintype "passive")
		)
		(pad "18" smd rect
			(at 5.675 -1.375 180)
			(size 0.35 2.35)
			(layers "B.Cu" "B.Mask")
			(net 14 "GND")
			(pinfunction "VSS")
			(pintype "passive")
		)
		(pad "19" smd rect
			(at 5.925 -1.375)
			(size 0.35 2.35)
			(layers "F.Cu" "F.Mask")
			(net 118 "/SODIMM/LPDDR5_IN_A.DMI1")
			(pinfunction "DM0_A_n")
			(pintype "passive")
		)
		(pad "20" smd rect
			(at 6.175 -1.375 180)
			(size 0.35 2.35)
			(layers "B.Cu" "B.Mask")
			(net 182 "/SODIMM/LPDDR5_IN_A.WCK1_N")
			(pinfunction "DQS0_A_C")
			(pintype "passive")
		)
		(pad "21" smd rect
			(at 6.425 -1.375)
			(size 0.35 2.35)
			(layers "F.Cu" "F.Mask")
			(net 14 "GND")
			(pinfunction "VSS")
			(pintype "passive")
		)
		(pad "22" smd rect
			(at 6.675 -1.375 180)
			(size 0.35 2.35)
			(layers "B.Cu" "B.Mask")
			(net 181 "/SODIMM/LPDDR5_IN_A.WCK1_P")
			(pinfunction "DQS0_A_t")
			(pintype "passive")
		)
		(pad "23" smd rect
			(at 6.925 -1.375)
			(size 0.35 2.35)
			(layers "F.Cu" "F.Mask")
			(net 177 "/SODIMM/LPDDR5_IN_A.DQ15")
			(pinfunction "DQ4_A")
			(pintype "passive")
		)
		(pad "24" smd rect
			(at 7.175 -1.375 180)
			(size 0.35 2.35)
			(layers "B.Cu" "B.Mask")
			(net 14 "GND")
			(pinfunction "VSS")
			(pintype "passive")
		)
		(pad "25" smd rect
			(at 7.425 -1.375)
			(size 0.35 2.35)
			(layers "F.Cu" "F.Mask")
			(net 14 "GND")
			(pinfunction "VSS")
			(pintype "passive")
		)
		(pad "26" smd rect
			(at 7.675 -1.375 180)
			(size 0.35 2.35)
			(layers "B.Cu" "B.Mask")
			(net 180 "/SODIMM/LPDDR5_IN_A.DQ14")
			(pinfunction "DQ5_A")
			(pintype "passive")
		)
		(pad "27" smd rect
			(at 7.925 -1.375)
			(size 0.35 2.35)
			(layers "F.Cu" "F.Mask")
			(net 178 "/SODIMM/LPDDR5_IN_A.DQ12")
			(pinfunction "DQ6_A")
			(pintype "passive")
		)
		(pad "28" smd rect
			(at 8.175 -1.375 180)
			(size 0.35 2.35)
			(layers "B.Cu" "B.Mask")
			(net 14 "GND")
			(pinfunction "VSS")
			(pintype "passive")
		)
		(pad "29" smd rect
			(at 8.425 -1.375)
			(size 0.35 2.35)
			(layers "F.Cu" "F.Mask")
			(net 14 "GND")
			(pinfunction "VSS")
			(pintype "passive")
		)
		(pad "30" smd rect
			(at 8.675 -1.375 180)
			(size 0.35 2.35)
			(layers "B.Cu" "B.Mask")
			(net 179 "/SODIMM/LPDDR5_IN_A.DQ13")
			(pinfunction "DQ7_A")
			(pintype "passive")
		)
		(pad "31" smd rect
			(at 8.925 -1.375)
			(size 0.35 2.35)
			(layers "F.Cu" "F.Mask")
			(net 128 "/LPDDR5/LPDDR5_A.DQ8")
			(pinfunction "DQ8_A")
			(pintype "passive")
		)
		(pad "32" smd rect
			(at 9.175 -1.375 180)
			(size 0.35 2.35)
			(layers "B.Cu" "B.Mask")
			(net 14 "GND")
			(pinfunction "VSS")
			(pintype "passive")
		)
		(pad "33" smd rect
			(at 9.425 -1.375)
			(size 0.35 2.35)
			(layers "F.Cu" "F.Mask")
			(net 14 "GND")
			(pinfunction "VSS")
			(pintype "passive")
		)
		(pad "34" smd rect
			(at 9.675 -1.375 180)
			(size 0.35 2.35)
			(layers "B.Cu" "B.Mask")
			(net 139 "/LPDDR5/LPDDR5_A.DQ10")
			(pinfunction "DQ09_A")
			(pintype "passive")
		)
		(pad "35" smd rect
			(at 9.925 -1.375)
			(size 0.35 2.35)
			(layers "F.Cu" "F.Mask")
			(net 172 "/LPDDR5/LPDDR5_A.DQ9")
			(pinfunction "DQ10_A")
			(pintype "passive")
		)
		(pad "36" smd rect
			(at 10.175 -1.375 180)
			(size 0.35 2.35)
			(layers "B.Cu" "B.Mask")
			(net 14 "GND")
			(pinfunction "VSS")
			(pintype "passive")
		)
		(pad "37" smd rect
			(at 10.425 -1.375)
			(size 0.35 2.35)
			(layers "F.Cu" "F.Mask")
			(net 14 "GND")
			(pinfunction "VSS")
			(pintype "passive")
		)
		(pad "38" smd rect
			(at 10.675 -1.375 180)
			(size 0.35 2.35)
			(layers "B.Cu" "B.Mask")
			(net 183 "/LPDDR5/LPDDR5_A.DQ11")
			(pinfunction "DQ11_A")
			(pintype "passive")
		)
		(pad "39" smd rect
			(at 10.925 -1.375)
			(size 0.35 2.35)
			(layers "F.Cu" "F.Mask")
			(net 188 "/LPDDR5/LPDDR5_A.RDQS1_N")
			(pinfunction "DQS1_A_C")
			(pintype "passive")
		)
		(pad "40" smd rect
			(at 11.175 -1.375 180)
			(size 0.35 2.35)
			(layers "B.Cu" "B.Mask")
			(net 14 "GND")
			(pinfunction "VSS")
			(pintype "passive")
		)
		(pad "41" smd rect
			(at 11.425 -1.375)
			(size 0.35 2.35)
			(layers "F.Cu" "F.Mask")
			(net 189 "/LPDDR5/LPDDR5_A.RDQS1_P")
			(pinfunction "DQS1_A_t")
			(pintype "passive")
		)
		(pad "42" smd rect
			(at 11.675 -1.375 180)
			(size 0.35 2.35)
			(layers "B.Cu" "B.Mask")
			(net 190 "/LPDDR5/LPDDR5_A.DMI1")
			(pinfunction "DM1_A_n")
			(pintype "passive")
		)
		(pad "43" smd rect
			(at 11.925 -1.375)
			(size 0.35 2.35)
			(layers "F.Cu" "F.Mask")
			(net 14 "GND")
			(pinfunction "VSS")
			(pintype "passive")
		)
		(pad "44" smd rect
			(at 12.175 -1.375 180)
			(size 0.35 2.35)
			(layers "B.Cu" "B.Mask")
			(net 14 "GND")
			(pinfunction "VSS")
			(pintype "passive")
		)
		(pad "45" smd rect
			(at 12.425 -1.375)
			(size 0.35 2.35)
			(layers "F.Cu" "F.Mask")
			(net 191 "/LPDDR5/LPDDR5_A.DQ15")
			(pinfunction "DQ12_A")
			(pintype "passive")
		)
		(pad "46" smd rect
			(at 12.675 -1.375 180)
			(size 0.35 2.35)
			(layers "B.Cu" "B.Mask")
			(net 192 "/LPDDR5/LPDDR5_A.DQ14")
			(pinfunction "DQ13_A")
			(pintype "passive")
		)
		(pad "47" smd rect
			(at 12.925 -1.375)
			(size 0.35 2.35)
			(layers "F.Cu" "F.Mask")
			(net 14 "GND")
			(pinfunction "VSS")
			(pintype "passive")
		)
		(pad "48" smd rect
			(at 13.175 -1.375 180)
			(size 0.35 2.35)
			(layers "B.Cu" "B.Mask")
			(net 14 "GND")
			(pinfunction "VSS")
			(pintype "passive")
		)
		(pad "49" smd rect
			(at 13.425 -1.375)
			(size 0.35 2.35)
			(layers "F.Cu" "F.Mask")
			(net 193 "/LPDDR5/LPDDR5_A.DQ12")
			(pinfunction "DQ14_A")
			(pintype "passive")
		)
		(pad "50" smd rect
			(at 13.675 -1.375 180)
			(size 0.35 2.35)
			(layers "B.Cu" "B.Mask")
			(net 194 "/LPDDR5/LPDDR5_A.DQ13")
			(pinfunction "DQ15_A")
			(pintype "passive")
		)
		(pad "51" smd rect
			(at 13.925 -1.375)
			(size 0.35 2.35)
			(layers "F.Cu" "F.Mask")
			(net 14 "GND")
			(pinfunction "VSS")
			(pintype "passive")
		)
		(pad "52" smd rect
			(at 14.175 -1.375 180)
			(size 0.35 2.35)
			(layers "B.Cu" "B.Mask")
			(net 14 "GND")
			(pinfunction "VSS")
			(pintype "passive")
		)
		(pad "53" smd rect
			(at 14.425 -1.375)
			(size 0.35 2.35)
			(layers "F.Cu" "F.Mask")
			(net 176 "/SODIMM/LPDDR5_IN_A.DQ5")
			(pinfunction "DQ16_A")
			(pintype "passive")
		)
		(pad "54" smd rect
			(at 14.675 -1.375 180)
			(size 0.35 2.35)
			(layers "B.Cu" "B.Mask")
			(net 175 "/SODIMM/LPDDR5_IN_A.DQ4")
			(pinfunction "DQ17_A")
			(pintype "passive")
		)
		(pad "55" smd rect
			(at 14.925 -1.375)
			(size 0.35 2.35)
			(layers "F.Cu" "F.Mask")
			(net 14 "GND")
			(pinfunction "VSS")
			(pintype "passive")
		)
		(pad "56" smd rect
			(at 15.175 -1.375 180)
			(size 0.35 2.35)
			(layers "B.Cu" "B.Mask")
			(net 14 "GND")
			(pinfunction "VSS")
			(pintype "passive")
		)
		(pad "57" smd rect
			(at 15.425 -1.375)
			(size 0.35 2.35)
			(layers "F.Cu" "F.Mask")
			(net 174 "/SODIMM/LPDDR5_IN_A.DQ6")
			(pinfunction "DQ18_A")
			(pintype "passive")
		)
		(pad "58" smd rect
			(at 15.675 -1.375 180)
			(size 0.35 2.35)
			(layers "B.Cu" "B.Mask")
			(net 173 "/SODIMM/LPDDR5_IN_A.DQ7")
			(pinfunction "DQ19_A")
			(pintype "passive")
		)
		(pad "59" smd rect
			(at 15.925 -1.375)
			(size 0.35 2.35)
			(layers "F.Cu" "F.Mask")
			(net 14 "GND")
			(pinfunction "VSS")
			(pintype "passive")
		)
		(pad "60" smd rect
			(at 16.175 -1.375 180)
			(size 0.35 2.35)
			(layers "B.Cu" "B.Mask")
			(net 14 "GND")
			(pinfunction "VSS")
			(pintype "passive")
		)
		(pad "61" smd rect
			(at 16.425 -1.375)
			(size 0.35 2.35)
			(layers "F.Cu" "F.Mask")
			(net 119 "/SODIMM/LPDDR5_IN_A.DMI0")
			(pinfunction "DM2_A_n")
			(pintype "passive")
		)
		(pad "62" smd rect
			(at 16.675 -1.375 180)
			(size 0.35 2.35)
			(layers "B.Cu" "B.Mask")
			(net 171 "/SODIMM/LPDDR5_IN_A.WCK0_N")
			(pinfunction "DQS2_A_C")
			(pintype "passive")
		)
		(pad "63" smd rect
			(at 16.925 -1.375)
			(size 0.35 2.35)
			(layers "F.Cu" "F.Mask")
			(net 14 "GND")
			(pinfunction "VSS")
			(pintype "passive")
		)
		(pad "64" smd rect
			(at 17.175 -1.375 180)
			(size 0.35 2.35)
			(layers "B.Cu" "B.Mask")
			(net 170 "/SODIMM/LPDDR5_IN_A.WCK0_P")
			(pinfunction "DQS2_A_t")
			(pintype "passive")
		)
		(pad "65" smd rect
			(at 17.425 -1.375)
			(size 0.35 2.35)
			(layers "F.Cu" "F.Mask")
			(net 169 "/SODIMM/LPDDR5_IN_A.DQ3")
			(pinfunction "DQ20_A")
			(pintype "passive")
		)
		(pad "66" smd rect
			(at 17.675 -1.375 180)
			(size 0.35 2.35)
			(layers "B.Cu" "B.Mask")
			(net 14 "GND")
			(pinfunction "VSS")
			(pintype "passive")
		)
		(pad "67" smd rect
			(at 17.925 -1.375)
			(size 0.35 2.35)
			(layers "F.Cu" "F.Mask")
			(net 14 "GND")
			(pinfunction "VSS")
			(pintype "passive")
		)
		(pad "68" smd rect
			(at 18.175 -1.375 180)
			(size 0.35 2.35)
			(layers "B.Cu" "B.Mask")
			(net 168 "/SODIMM/LPDDR5_IN_A.DQ1")
			(pinfunction "DQ21_A")
			(pintype "passive")
		)
		(pad "69" smd rect
			(at 18.425 -1.375)
			(size 0.35 2.35)
			(layers "F.Cu" "F.Mask")
			(net 167 "/SODIMM/LPDDR5_IN_A.DQ2")
			(pinfunction "DQ22_A")
			(pintype "passive")
		)
		(pad "70" smd rect
			(at 18.675 -1.375 180)
			(size 0.35 2.35)
			(layers "B.Cu" "B.Mask")
			(net 14 "GND")
			(pinfunction "VSS")
			(pintype "passive")
		)
		(pad "71" smd rect
			(at 18.925 -1.375)
			(size 0.35 2.35)
			(layers "F.Cu" "F.Mask")
			(net 14 "GND")
			(pinfunction "VSS")
			(pintype "passive")
		)
		(pad "72" smd rect
			(at 19.175 -1.375 180)
			(size 0.35 2.35)
			(layers "B.Cu" "B.Mask")
			(net 166 "/SODIMM/LPDDR5_IN_A.DQ0")
			(pinfunction "DQ23_A")
			(pintype "passive")
		)
		(pad "73" smd rect
			(at 19.425 -1.375)
			(size 0.35 2.35)
			(layers "F.Cu" "F.Mask")
			(net 197 "/LPDDR5/LPDDR5_A.DQ5")
			(pinfunction "DQ24_A")
			(pintype "passive")
		)
		(pad "74" smd rect
			(at 19.675 -1.375 180)
			(size 0.35 2.35)
			(layers "B.Cu" "B.Mask")
			(net 14 "GND")
			(pinfunction "VSS")
			(pintype "passive")
		)
		(pad "75" smd rect
			(at 19.925 -1.375)
			(size 0.35 2.35)
			(layers "F.Cu" "F.Mask")
			(net 14 "GND")
			(pinfunction "VSS")
			(pintype "passive")
		)
		(pad "76" smd rect
			(at 20.175 -1.375 180)
			(size 0.35 2.35)
			(layers "B.Cu" "B.Mask")
			(net 198 "/LPDDR5/LPDDR5_A.DQ4")
			(pinfunction "DQ25_A")
			(pintype "passive")
		)
		(pad "77" smd rect
			(at 20.425 -1.375)
			(size 0.35 2.35)
			(layers "F.Cu" "F.Mask")
			(net 196 "/LPDDR5/LPDDR5_A.DQ6")
			(pinfunction "DQ26_A")
			(pintype "passive")
		)
		(pad "78" smd rect
			(at 20.675 -1.375 180)
			(size 0.35 2.35)
			(layers "B.Cu" "B.Mask")
			(net 14 "GND")
			(pinfunction "VSS")
			(pintype "passive")
		)
		(pad "79" smd rect
			(at 20.925 -1.375)
			(size 0.35 2.35)
			(layers "F.Cu" "F.Mask")
			(net 14 "GND")
			(pinfunction "VSS")
			(pintype "passive")
		)
		(pad "80" smd rect
			(at 21.175 -1.375 180)
			(size 0.35 2.35)
			(layers "B.Cu" "B.Mask")
			(net 195 "/LPDDR5/LPDDR5_A.DQ7")
			(pinfunction "DQ27_A")
			(pintype "passive")
		)
		(pad "81" smd rect
			(at 21.425 -1.375)
			(size 0.35 2.35)
			(layers "F.Cu" "F.Mask")
			(net 199 "/LPDDR5/LPDDR5_A.RDQS0_N")
			(pinfunction "DQS3_A_C")
			(pintype "passive")
		)
		(pad "82" smd rect
			(at 21.675 -1.375 180)
			(size 0.35 2.35)
			(layers "B.Cu" "B.Mask")
			(net 14 "GND")
			(pinfunction "VSS")
			(pintype "passive")
		)
		(pad "83" smd rect
			(at 21.925 -1.375)
			(size 0.35 2.35)
			(layers "F.Cu" "F.Mask")
			(net 200 "/LPDDR5/LPDDR5_A.RDQS0_P")
			(pinfunction "DQS3_A_t")
			(pintype "passive")
		)
		(pad "84" smd rect
			(at 22.175 -1.375 180)
			(size 0.35 2.35)
			(layers "B.Cu" "B.Mask")
			(net 201 "/LPDDR5/LPDDR5_A.DMI0")
			(pinfunction "DM3_A_n")
			(pintype "passive")
		)
		(pad "85" smd rect
			(at 22.425 -1.375)
			(size 0.35 2.35)
			(layers "F.Cu" "F.Mask")
			(net 14 "GND")
			(pinfunction "VSS")
			(pintype "passive")
		)
		(pad "86" smd rect
			(at 22.675 -1.375 180)
			(size 0.35 2.35)
			(layers "B.Cu" "B.Mask")
			(net 14 "GND")
			(pinfunction "VSS")
			(pintype "passive")
		)
		(pad "87" smd rect
			(at 22.925 -1.375)
			(size 0.35 2.35)
			(layers "F.Cu" "F.Mask")
			(net 202 "/LPDDR5/LPDDR5_A.DQ3")
			(pinfunction "DQ28_A")
			(pintype "passive")
		)
		(pad "88" smd rect
			(at 23.175 -1.375 180)
			(size 0.35 2.35)
			(layers "B.Cu" "B.Mask")
			(net 204 "/LPDDR5/LPDDR5_A.DQ1")
			(pinfunction "DQ29_A")
			(pintype "passive")
		)
		(pad "89" smd rect
			(at 23.425 -1.375)
			(size 0.35 2.35)
			(layers "F.Cu" "F.Mask")
			(net 14 "GND")
			(pinfunction "VSS")
			(pintype "passive")
		)
		(pad "90" smd rect
			(at 23.675 -1.375 180)
			(size 0.35 2.35)
			(layers "B.Cu" "B.Mask")
			(net 14 "GND")
			(pinfunction "VSS")
			(pintype "passive")
		)
		(pad "91" smd rect
			(at 23.925 -1.375)
			(size 0.35 2.35)
			(layers "F.Cu" "F.Mask")
			(net 203 "/LPDDR5/LPDDR5_A.DQ2")
			(pinfunction "DQ30_A")
			(pintype "passive")
		)
		(pad "92" smd rect
			(at 24.175 -1.375 180)
			(size 0.35 2.35)
			(layers "B.Cu" "B.Mask")
			(net 205 "/LPDDR5/LPDDR5_A.DQ0")
			(pinfunction "DQ31_A")
			(pintype "passive")
		)
		(pad "93" smd rect
			(at 24.425 -1.375)
			(size 0.35 2.35)
			(layers "F.Cu" "F.Mask")
			(net 14 "GND")
			(pinfunction "VSS")
			(pintype "passive")
		)
		(pad "94" smd rect
			(at 24.675 -1.375 180)
			(size 0.35 2.35)
			(layers "B.Cu" "B.Mask")
			(net 14 "GND")
			(pinfunction "VSS")
			(pintype "passive")
		)
		(pad "95" smd rect
			(at 24.925 -1.375)
			(size 0.35 2.35)
			(layers "F.Cu" "F.Mask")
			(net 62 "unconnected-(J1-Pad95)")
			(pinfunction "CB0_A")
			(pintype "passive+no_connect")
		)
		(pad "96" smd rect
			(at 25.175 -1.375 180)
			(size 0.35 2.35)
			(layers "B.Cu" "B.Mask")
			(net 63 "unconnected-(J1-Pad96)")
			(pinfunction "CB1_A")
			(pintype "passive+no_connect")
		)
		(pad "97" smd rect
			(at 25.425 -1.375)
			(size 0.35 2.35)
			(layers "F.Cu" "F.Mask")
			(net 14 "GND")
			(pinfunction "VSS")
			(pintype "passive")
		)
		(pad "98" smd rect
			(at 25.675 -1.375 180)
			(size 0.35 2.35)
			(layers "B.Cu" "B.Mask")
			(net 14 "GND")
			(pinfunction "VSS")
			(pintype "passive")
		)
		(pad "99" smd rect
			(at 25.925 -1.375)
			(size 0.35 2.35)
			(layers "F.Cu" "F.Mask")
			(net 64 "unconnected-(J1-Pad99)")
			(pinfunction "CB2_A")
			(pintype "passive+no_connect")
		)
		(pad "100" smd rect
			(at 26.175 -1.375 180)
			(size 0.35 2.35)
			(layers "B.Cu" "B.Mask")
			(net 65 "unconnected-(J1-Pad100)")
			(pinfunction "DQS4_A_c")
			(pintype "passive+no_connect")
		)
		(pad "101" smd rect
			(at 26.425 -1.375)
			(size 0.35 2.35)
			(layers "F.Cu" "F.Mask")
			(net 14 "GND")
			(pinfunction "VSS")
			(pintype "passive")
		)
		(pad "102" smd rect
			(at 26.675 -1.375 180)
			(size 0.35 2.35)
			(layers "B.Cu" "B.Mask")
			(net 66 "unconnected-(J1-Pad102)")
			(pinfunction "DQS4_A_t")
			(pintype "passive+no_connect")
		)
		(pad "103" smd rect
			(at 26.925 -1.375)
			(size 0.35 2.35)
			(layers "F.Cu" "F.Mask")
			(net 67 "unconnected-(J1-Pad103)")
			(pinfunction "CB3_A")
			(pintype "passive+no_connect")
		)
		(pad "104" smd rect
			(at 27.175 -1.375 180)
			(size 0.35 2.35)
			(layers "B.Cu" "B.Mask")
			(net 14 "GND")
			(pinfunction "VSS")
			(pintype "passive")
		)
		(pad "105" smd rect
			(at 27.425 -1.375)
			(size 0.35 2.35)
			(layers "F.Cu" "F.Mask")
			(net 14 "GND")
			(pinfunction "VSS")
			(pintype "passive")
		)
		(pad "106" smd rect
			(at 27.675 -1.375 180)
			(size 0.35 2.35)
			(layers "B.Cu" "B.Mask")
			(net 165 "/SODIMM/LPDDR5_IN_A.CS0")
			(pinfunction "CS0_A_n")
			(pintype "passive")
		)
		(pad "107" smd rect
			(at 27.925 -1.375)
			(size 0.35 2.35)
			(layers "F.Cu" "F.Mask")
			(net 164 "/SODIMM/LPDDR5_IN_A.CA0")
			(pinfunction "CA0_A")
			(pintype "passive")
		)
		(pad "108" smd rect
			(at 28.175 -1.375 180)
			(size 0.35 2.35)
			(layers "B.Cu" "B.Mask")
			(net 68 "unconnected-(J1-Pad108)")
			(pinfunction "ALERT_n")
			(pintype "passive+no_connect")
		)
		(pad "109" smd rect
			(at 28.425 -1.375)
			(size 0.35 2.35)
			(layers "F.Cu" "F.Mask")
			(net 163 "/SODIMM/LPDDR5_IN_A.CA1")
			(pinfunction "CA1_A")
			(pintype "passive")
		)
		(pad "110" smd rect
			(at 28.675 -1.375 180)
			(size 0.35 2.35)
			(layers "B.Cu" "B.Mask")
			(net 162 "/SODIMM/LPDDR5_IN_A.CS1")
			(pinfunction "CS1_A_n")
			(pintype "passive")
		)
		(pad "111" smd rect
			(at 28.925 -1.375)
			(size 0.35 2.35)
			(layers "F.Cu" "F.Mask")
			(net 14 "GND")
			(pinfunction "VSS")
			(pintype "passive")
		)
		(pad "112" smd rect
			(at 29.175 -1.375 180)
			(size 0.35 2.35)
			(layers "B.Cu" "B.Mask")
			(net 14 "GND")
			(pinfunction "VSS")
			(pintype "passive")
		)
		(pad "113" smd rect
			(at 29.425 -1.375)
			(size 0.35 2.35)
			(layers "F.Cu" "F.Mask")
			(net 161 "/SODIMM/LPDDR5_IN_A.CA2")
			(pinfunction "CA2_A")
			(pintype "passive")
		)
		(pad "114" smd rect
			(at 29.675 -1.375 180)
			(size 0.35 2.35)
			(layers "B.Cu" "B.Mask")
			(net 160 "/SODIMM/LPDDR5_IN_A.CA3")
			(pinfunction "CA3_A")
			(pintype "passive")
		)
		(pad "115" smd rect
			(at 29.925 -1.375)
			(size 0.35 2.35)
			(layers "F.Cu" "F.Mask")
			(net 159 "/SODIMM/LPDDR5_IN_A.CA4")
			(pinfunction "CA4_A")
			(pintype "passive")
		)
		(pad "116" smd rect
			(at 30.175 -1.375 180)
			(size 0.35 2.35)
			(layers "B.Cu" "B.Mask")
			(net 158 "/SODIMM/LPDDR5_IN_A.CA5")
			(pinfunction "CA5_A")
			(pintype "passive")
		)
		(pad "117" smd rect
			(at 30.425 -1.375)
			(size 0.35 2.35)
			(layers "F.Cu" "F.Mask")
			(net 14 "GND")
			(pinfunction "VSS")
			(pintype "passive")
		)
		(pad "118" smd rect
			(at 30.675 -1.375 180)
			(size 0.35 2.35)
			(layers "B.Cu" "B.Mask")
			(net 14 "GND")
			(pinfunction "VSS")
			(pintype "passive")
		)
		(pad "119" smd rect
			(at 30.925 -1.375)
			(size 0.35 2.35)
			(layers "F.Cu" "F.Mask")
			(net 157 "/SODIMM/LPDDR5_IN_A.CA6")
			(pinfunction "CA6_A")
			(pintype "passive")
		)
		(pad "120" smd rect
			(at 31.175 -1.375 180)
			(size 0.35 2.35)
			(layers "B.Cu" "B.Mask")
			(net 74 "unconnected-(J1-Pad120)")
			(pinfunction "CA7_A")
			(pintype "passive+no_connect")
		)
		(pad "121" smd rect
			(at 31.425 -1.375)
			(size 0.35 2.35)
			(layers "F.Cu" "F.Mask")
			(net 75 "unconnected-(J1-Pad121)")
			(pinfunction "CA8_A")
			(pintype "passive+no_connect")
		)
		(pad "122" smd rect
			(at 31.675 -1.375 180)
			(size 0.35 2.35)
			(layers "B.Cu" "B.Mask")
			(net 76 "unconnected-(J1-Pad122)")
			(pinfunction "CA9_A")
			(pintype "passive+no_connect")
		)
		(pad "123" smd rect
			(at 31.925 -1.375)
			(size 0.35 2.35)
			(layers "F.Cu" "F.Mask")
			(net 14 "GND")
			(pinfunction "VSS")
			(pintype "passive")
		)
		(pad "124" smd rect
			(at 32.175 -1.375 180)
			(size 0.35 2.35)
			(layers "B.Cu" "B.Mask")
			(net 14 "GND")
			(pinfunction "VSS")
			(pintype "passive")
		)
		(pad "125" smd rect
			(at 32.425 -1.375)
			(size 0.35 2.35)
			(layers "F.Cu" "F.Mask")
			(net 77 "unconnected-(J1-Pad125)")
			(pinfunction "CA10_A")
			(pintype "passive+no_connect")
		)
		(pad "126" smd rect
			(at 32.675 -1.375 180)
			(size 0.35 2.35)
			(layers "B.Cu" "B.Mask")
			(net 78 "unconnected-(J1-Pad126)")
			(pinfunction "CA11_A")
			(pintype "passive+no_connect")
		)
		(pad "127" smd rect
			(at 34.425 -1.375)
			(size 0.35 2.35)
			(layers "F.Cu" "F.Mask")
			(net 79 "unconnected-(J1-Pad127)")
			(pinfunction "CA12_A")
			(pintype "passive+no_connect")
		)
		(pad "128" smd rect
			(at 34.675 -1.375 180)
			(size 0.35 2.35)
			(layers "B.Cu" "B.Mask")
			(net 80 "unconnected-(J1-Pad128)")
			(pinfunction "RFU")
			(pintype "passive+no_connect")
		)
		(pad "129" smd rect
			(at 34.925 -1.375)
			(size 0.35 2.35)
			(layers "F.Cu" "F.Mask")
			(net 14 "GND")
			(pinfunction "VSS")
			(pintype "passive")
		)
		(pad "130" smd rect
			(at 35.175 -1.375 180)
			(size 0.35 2.35)
			(layers "B.Cu" "B.Mask")
			(net 33 "Net-(J1-Pad130)")
			(pinfunction "TB_DETECT")
			(pintype "input")
		)
		(pad "131" smd rect
			(at 35.425 -1.375)
			(size 0.35 2.35)
			(layers "F.Cu" "F.Mask")
			(net 156 "/SODIMM/LPDDR5_IN_A.CK_P")
			(pinfunction "CK0_A_t")
			(pintype "passive")
		)
		(pad "132" smd rect
			(at 35.675 -1.375 180)
			(size 0.35 2.35)
			(layers "B.Cu" "B.Mask")
			(net 81 "unconnected-(J1-Pad132)")
			(pinfunction "CK1_A_t")
			(pintype "passive+no_connect")
		)
		(pad "133" smd rect
			(at 35.925 -1.375)
			(size 0.35 2.35)
			(layers "F.Cu" "F.Mask")
			(net 155 "/SODIMM/LPDDR5_IN_A.CK_N")
			(pinfunction "CK0_A_c")
			(pintype "passive")
		)
		(pad "134" smd rect
			(at 36.175 -1.375 180)
			(size 0.35 2.35)
			(layers "B.Cu" "B.Mask")
			(net 82 "unconnected-(J1-Pad134)")
			(pinfunction "CK1_A_c")
			(pintype "passive+no_connect")
		)
		(pad "135" smd rect
			(at 36.425 -1.375)
			(size 0.35 2.35)
			(layers "F.Cu" "F.Mask")
			(net 14 "GND")
			(pinfunction "VSS")
			(pintype "passive")
		)
		(pad "136" smd rect
			(at 36.675 -1.375 180)
			(size 0.35 2.35)
			(layers "B.Cu" "B.Mask")
			(net 14 "GND")
			(pinfunction "VSS")
			(pintype "passive")
		)
		(pad "137" smd rect
			(at 36.925 -1.375)
			(size 0.35 2.35)
			(layers "F.Cu" "F.Mask")
			(net 154 "/SODIMM/LPDDR5_IN_B.CK_P")
			(pinfunction "CK0_B_t")
			(pintype "passive")
		)
		(pad "138" smd rect
			(at 37.175 -1.375 180)
			(size 0.35 2.35)
			(layers "B.Cu" "B.Mask")
			(net 83 "unconnected-(J1-Pad138)")
			(pinfunction "CK1_B_t")
			(pintype "passive+no_connect")
		)
		(pad "139" smd rect
			(at 37.425 -1.375)
			(size 0.35 2.35)
			(layers "F.Cu" "F.Mask")
			(net 153 "/SODIMM/LPDDR5_IN_B.CK_N")
			(pinfunction "CK0_B_c")
			(pintype "passive")
		)
		(pad "140" smd rect
			(at 37.675 -1.375 180)
			(size 0.35 2.35)
			(layers "B.Cu" "B.Mask")
			(net 84 "unconnected-(J1-Pad140)")
			(pinfunction "CK1_B_C")
			(pintype "passive+no_connect")
		)
		(pad "141" smd rect
			(at 37.925 -1.375)
			(size 0.35 2.35)
			(layers "F.Cu" "F.Mask")
			(net 14 "GND")
			(pinfunction "VSS")
			(pintype "passive")
		)
		(pad "142" smd rect
			(at 38.175 -1.375 180)
			(size 0.35 2.35)
			(layers "B.Cu" "B.Mask")
			(net 14 "GND")
			(pinfunction "VSS")
			(pintype "passive")
		)
		(pad "143" smd rect
			(at 38.425 -1.375)
			(size 0.35 2.35)
			(layers "F.Cu" "F.Mask")
			(net 85 "unconnected-(J1-Pad143)")
			(pinfunction "RFU")
			(pintype "passive+no_connect")
		)
		(pad "144" smd rect
			(at 38.675 -1.375 180)
			(size 0.35 2.35)
			(layers "B.Cu" "B.Mask")
			(net 86 "unconnected-(J1-Pad144)")
			(pinfunction "CA12_B")
			(pintype "passive+no_connect")
		)
		(pad "145" smd rect
			(at 38.925 -1.375)
			(size 0.35 2.35)
			(layers "F.Cu" "F.Mask")
			(net 87 "unconnected-(J1-Pad145)")
			(pinfunction "CA11_B")
			(pintype "passive+no_connect")
		)
		(pad "146" smd rect
			(at 39.175 -1.375 180)
			(size 0.35 2.35)
			(layers "B.Cu" "B.Mask")
			(net 88 "unconnected-(J1-Pad146)")
			(pinfunction "CA10_B")
			(pintype "passive+no_connect")
		)
		(pad "147" smd rect
			(at 39.425 -1.375)
			(size 0.35 2.35)
			(layers "F.Cu" "F.Mask")
			(net 14 "GND")
			(pinfunction "VSS")
			(pintype "passive")
		)
		(pad "148" smd rect
			(at 39.675 -1.375 180)
			(size 0.35 2.35)
			(layers "B.Cu" "B.Mask")
			(net 14 "GND")
			(pinfunction "VSS")
			(pintype "passive")
		)
		(pad "149" smd rect
			(at 39.925 -1.375)
			(size 0.35 2.35)
			(layers "F.Cu" "F.Mask")
			(net 89 "unconnected-(J1-Pad149)")
			(pinfunction "CA9_B")
			(pintype "passive+no_connect")
		)
		(pad "150" smd rect
			(at 40.175 -1.375 180)
			(size 0.35 2.35)
			(layers "B.Cu" "B.Mask")
			(net 90 "unconnected-(J1-Pad150)")
			(pinfunction "CA8_B")
			(pintype "passive+no_connect")
		)
		(pad "151" smd rect
			(at 40.425 -1.375)
			(size 0.35 2.35)
			(layers "F.Cu" "F.Mask")
			(net 91 "unconnected-(J1-Pad151)")
			(pinfunction "CA7_B")
			(pintype "passive+no_connect")
		)
		(pad "152" smd rect
			(at 40.675 -1.375 180)
			(size 0.35 2.35)
			(layers "B.Cu" "B.Mask")
			(net 152 "/SODIMM/LPDDR5_IN_B.CA6")
			(pinfunction "CA6_B")
			(pintype "passive")
		)
		(pad "153" smd rect
			(at 40.925 -1.375)
			(size 0.35 2.35)
			(layers "F.Cu" "F.Mask")
			(net 14 "GND")
			(pinfunction "VSS")
			(pintype "passive")
		)
		(pad "154" smd rect
			(at 41.175 -1.375 180)
			(size 0.35 2.35)
			(layers "B.Cu" "B.Mask")
			(net 14 "GND")
			(pinfunction "VSS")
			(pintype "passive")
		)
		(pad "155" smd rect
			(at 41.425 -1.375)
			(size 0.35 2.35)
			(layers "F.Cu" "F.Mask")
			(net 151 "/SODIMM/LPDDR5_IN_B.CA5")
			(pinfunction "CA5_B")
			(pintype "passive")
		)
		(pad "156" smd rect
			(at 41.675 -1.375 180)
			(size 0.35 2.35)
			(layers "B.Cu" "B.Mask")
			(net 150 "/SODIMM/LPDDR5_IN_B.CA4")
			(pinfunction "CA4_B")
			(pintype "passive")
		)
		(pad "157" smd rect
			(at 41.925 -1.375)
			(size 0.35 2.35)
			(layers "F.Cu" "F.Mask")
			(net 149 "/SODIMM/LPDDR5_IN_B.CA3")
			(pinfunction "CA3_B")
			(pintype "passive")
		)
		(pad "158" smd rect
			(at 42.175 -1.375 180)
			(size 0.35 2.35)
			(layers "B.Cu" "B.Mask")
			(net 148 "/SODIMM/LPDDR5_IN_B.CA2")
			(pinfunction "CA2_B")
			(pintype "passive")
		)
		(pad "159" smd rect
			(at 42.425 -1.375)
			(size 0.35 2.35)
			(layers "F.Cu" "F.Mask")
			(net 14 "GND")
			(pinfunction "VSS")
			(pintype "passive")
		)
		(pad "160" smd rect
			(at 42.675 -1.375 180)
			(size 0.35 2.35)
			(layers "B.Cu" "B.Mask")
			(net 14 "GND")
			(pinfunction "VSS")
			(pintype "passive")
		)
		(pad "161" smd rect
			(at 42.925 -1.375)
			(size 0.35 2.35)
			(layers "F.Cu" "F.Mask")
			(net 147 "/SODIMM/LPDDR5_IN_B.CS0")
			(pinfunction "CS0_B_n")
			(pintype "passive")
		)
		(pad "162" smd rect
			(at 43.175 -1.375 180)
			(size 0.35 2.35)
			(layers "B.Cu" "B.Mask")
			(net 146 "/SODIMM/LPDDR5_IN_B.CA1")
			(pinfunction "CA1_B")
			(pintype "passive")
		)
		(pad "163" smd rect
			(at 43.425 -1.375)
			(size 0.35 2.35)
			(layers "F.Cu" "F.Mask")
			(net 34 "/SODIMM/~{RESET}")
			(pinfunction "RESET_n")
			(pintype "passive")
		)
		(pad "164" smd rect
			(at 43.675 -1.375 180)
			(size 0.35 2.35)
			(layers "B.Cu" "B.Mask")
			(net 145 "/SODIMM/LPDDR5_IN_B.CA0")
			(pinfunction "CA0_B")
			(pintype "passive")
		)
		(pad "165" smd rect
			(at 43.925 -1.375)
			(size 0.35 2.35)
			(layers "F.Cu" "F.Mask")
			(net 144 "/SODIMM/LPDDR5_IN_B.CS1")
			(pinfunction "CS1_B_N")
			(pintype "passive")
		)
		(pad "166" smd rect
			(at 44.175 -1.375 180)
			(size 0.35 2.35)
			(layers "B.Cu" "B.Mask")
			(net 14 "GND")
			(pinfunction "VSS")
			(pintype "passive")
		)
		(pad "167" smd rect
			(at 44.425 -1.375)
			(size 0.35 2.35)
			(layers "F.Cu" "F.Mask")
			(net 14 "GND")
			(pinfunction "VSS")
			(pintype "passive")
		)
		(pad "168" smd rect
			(at 44.675 -1.375 180)
			(size 0.35 2.35)
			(layers "B.Cu" "B.Mask")
			(net 93 "unconnected-(J1-Pad168)")
			(pinfunction "CB0_B")
			(pintype "passive+no_connect")
		)
		(pad "169" smd rect
			(at 44.925 -1.375)
			(size 0.35 2.35)
			(layers "F.Cu" "F.Mask")
			(net 94 "unconnected-(J1-Pad169)")
			(pinfunction "DQS4_B_c")
			(pintype "passive+no_connect")
		)
		(pad "170" smd rect
			(at 45.175 -1.375 180)
			(size 0.35 2.35)
			(layers "B.Cu" "B.Mask")
			(net 14 "GND")
			(pinfunction "VSS")
			(pintype "passive")
		)
		(pad "171" smd rect
			(at 45.425 -1.375)
			(size 0.35 2.35)
			(layers "F.Cu" "F.Mask")
			(net 95 "unconnected-(J1-Pad171)")
			(pinfunction "DQS4_B_T")
			(pintype "passive+no_connect")
		)
		(pad "172" smd rect
			(at 45.675 -1.375 180)
			(size 0.35 2.35)
			(layers "B.Cu" "B.Mask")
			(net 96 "unconnected-(J1-Pad172)")
			(pinfunction "CB1_B")
			(pintype "passive+no_connect")
		)
		(pad "173" smd rect
			(at 45.925 -1.375)
			(size 0.35 2.35)
			(layers "F.Cu" "F.Mask")
			(net 14 "GND")
			(pinfunction "VSS")
			(pintype "passive")
		)
		(pad "174" smd rect
			(at 46.175 -1.375 180)
			(size 0.35 2.35)
			(layers "B.Cu" "B.Mask")
			(net 14 "GND")
			(pinfunction "VSS")
			(pintype "passive")
		)
		(pad "175" smd rect
			(at 46.425 -1.375)
			(size 0.35 2.35)
			(layers "F.Cu" "F.Mask")
			(net 97 "unconnected-(J1-Pad175)")
			(pinfunction "CB3_B")
			(pintype "passive+no_connect")
		)
		(pad "176" smd rect
			(at 46.675 -1.375 180)
			(size 0.35 2.35)
			(layers "B.Cu" "B.Mask")
			(net 98 "unconnected-(J1-Pad176)")
			(pinfunction "CB2_B")
			(pintype "passive+no_connect")
		)
		(pad "177" smd rect
			(at 46.925 -1.375)
			(size 0.35 2.35)
			(layers "F.Cu" "F.Mask")
			(net 14 "GND")
			(pinfunction "VSS")
			(pintype "passive")
		)
		(pad "178" smd rect
			(at 47.175 -1.375 180)
			(size 0.35 2.35)
			(layers "B.Cu" "B.Mask")
			(net 14 "GND")
			(pinfunction "VSS")
			(pintype "passive")
		)
		(pad "179" smd rect
			(at 47.425 -1.375)
			(size 0.35 2.35)
			(layers "F.Cu" "F.Mask")
			(net 206 "/LPDDR5/LPDDR5_B.DQ8")
			(pinfunction "DQ0_B")
			(pintype "passive")
		)
		(pad "180" smd rect
			(at 47.675 -1.375 180)
			(size 0.35 2.35)
			(layers "B.Cu" "B.Mask")
			(net 208 "/LPDDR5/LPDDR5_B.DQ10")
			(pinfunction "DQ1_B")
			(pintype "passive")
		)
		(pad "181" smd rect
			(at 47.925 -1.375)
			(size 0.35 2.35)
			(layers "F.Cu" "F.Mask")
			(net 14 "GND")
			(pinfunction "VSS")
			(pintype "passive")
		)
		(pad "182" smd rect
			(at 48.175 -1.375 180)
			(size 0.35 2.35)
			(layers "B.Cu" "B.Mask")
			(net 14 "GND")
			(pinfunction "VSS")
			(pintype "passive")
		)
		(pad "183" smd rect
			(at 48.425 -1.375)
			(size 0.35 2.35)
			(layers "F.Cu" "F.Mask")
			(net 207 "/LPDDR5/LPDDR5_B.DQ9")
			(pinfunction "DQ2_B")
			(pintype "passive")
		)
		(pad "184" smd rect
			(at 48.675 -1.375 180)
			(size 0.35 2.35)
			(layers "B.Cu" "B.Mask")
			(net 209 "/LPDDR5/LPDDR5_B.DQ11")
			(pinfunction "DQ3_B")
			(pintype "passive")
		)
		(pad "185" smd rect
			(at 48.925 -1.375)
			(size 0.35 2.35)
			(layers "F.Cu" "F.Mask")
			(net 14 "GND")
			(pinfunction "VSS")
			(pintype "passive")
		)
		(pad "186" smd rect
			(at 49.175 -1.375 180)
			(size 0.35 2.35)
			(layers "B.Cu" "B.Mask")
			(net 14 "GND")
			(pinfunction "VSS")
			(pintype "passive")
		)
		(pad "187" smd rect
			(at 49.425 -1.375)
			(size 0.35 2.35)
			(layers "F.Cu" "F.Mask")
			(net 223 "/LPDDR5/LPDDR5_B.DMI1")
			(pinfunction "DM0_B_n")
			(pintype "passive")
		)
		(pad "188" smd rect
			(at 49.675 -1.375 180)
			(size 0.35 2.35)
			(layers "B.Cu" "B.Mask")
			(net 210 "/LPDDR5/LPDDR5_B.RDQS1_N")
			(pinfunction "DQS0_B_C")
			(pintype "passive")
		)
		(pad "189" smd rect
			(at 49.925 -1.375)
			(size 0.35 2.35)
			(layers "F.Cu" "F.Mask")
			(net 14 "GND")
			(pinfunction "VSS")
			(pintype "passive")
		)
		(pad "190" smd rect
			(at 50.175 -1.375 180)
			(size 0.35 2.35)
			(layers "B.Cu" "B.Mask")
			(net 211 "/LPDDR5/LPDDR5_B.RDQS1_P")
			(pinfunction "DQS0_B_t")
			(pintype "passive")
		)
		(pad "191" smd rect
			(at 50.425 -1.375)
			(size 0.35 2.35)
			(layers "F.Cu" "F.Mask")
			(net 216 "/LPDDR5/LPDDR5_B.DQ15")
			(pinfunction "DQ4_B")
			(pintype "passive")
		)
		(pad "192" smd rect
			(at 50.675 -1.375 180)
			(size 0.35 2.35)
			(layers "B.Cu" "B.Mask")
			(net 14 "GND")
			(pinfunction "VSS")
			(pintype "passive")
		)
		(pad "193" smd rect
			(at 50.925 -1.375)
			(size 0.35 2.35)
			(layers "F.Cu" "F.Mask")
			(net 14 "GND")
			(pinfunction "VSS")
			(pintype "passive")
		)
		(pad "194" smd rect
			(at 51.175 -1.375 180)
			(size 0.35 2.35)
			(layers "B.Cu" "B.Mask")
			(net 215 "/LPDDR5/LPDDR5_B.DQ14")
			(pinfunction "DQ5_B")
			(pintype "passive")
		)
		(pad "195" smd rect
			(at 51.425 -1.375)
			(size 0.35 2.35)
			(layers "F.Cu" "F.Mask")
			(net 213 "/LPDDR5/LPDDR5_B.DQ12")
			(pinfunction "DQ6_B")
			(pintype "passive")
		)
		(pad "196" smd rect
			(at 51.675 -1.375 180)
			(size 0.35 2.35)
			(layers "B.Cu" "B.Mask")
			(net 14 "GND")
			(pinfunction "VSS")
			(pintype "passive")
		)
		(pad "197" smd rect
			(at 51.925 -1.375)
			(size 0.35 2.35)
			(layers "F.Cu" "F.Mask")
			(net 14 "GND")
			(pinfunction "VSS")
			(pintype "passive")
		)
		(pad "198" smd rect
			(at 52.175 -1.375 180)
			(size 0.35 2.35)
			(layers "B.Cu" "B.Mask")
			(net 214 "/LPDDR5/LPDDR5_B.DQ13")
			(pinfunction "DQ7_B")
			(pintype "passive")
		)
		(pad "199" smd rect
			(at 52.425 -1.375)
			(size 0.35 2.35)
			(layers "F.Cu" "F.Mask")
			(net 143 "/SODIMM/LPDDR5_IN_B.DQ8")
			(pinfunction "DQ8_B")
			(pintype "passive")
		)
		(pad "200" smd rect
			(at 52.675 -1.375 180)
			(size 0.35 2.35)
			(layers "B.Cu" "B.Mask")
			(net 14 "GND")
			(pinfunction "VSS")
			(pintype "passive")
		)
		(pad "201" smd rect
			(at 52.925 -1.375)
			(size 0.35 2.35)
			(layers "F.Cu" "F.Mask")
			(net 14 "GND")
			(pinfunction "VSS")
			(pintype "passive")
		)
		(pad "202" smd rect
			(at 53.175 -1.375 180)
			(size 0.35 2.35)
			(layers "B.Cu" "B.Mask")
			(net 141 "/SODIMM/LPDDR5_IN_B.DQ10")
			(pinfunction "DQ9_B")
			(pintype "passive")
		)
		(pad "203" smd rect
			(at 53.425 -1.375)
			(size 0.35 2.35)
			(layers "F.Cu" "F.Mask")
			(net 142 "/SODIMM/LPDDR5_IN_B.DQ9")
			(pinfunction "DQ10_B")
			(pintype "passive")
		)
		(pad "204" smd rect
			(at 53.675 -1.375 180)
			(size 0.35 2.35)
			(layers "B.Cu" "B.Mask")
			(net 14 "GND")
			(pinfunction "VSS")
			(pintype "passive")
		)
		(pad "205" smd rect
			(at 53.925 -1.375)
			(size 0.35 2.35)
			(layers "F.Cu" "F.Mask")
			(net 14 "GND")
			(pinfunction "VSS")
			(pintype "passive")
		)
		(pad "206" smd rect
			(at 54.175 -1.375 180)
			(size 0.35 2.35)
			(layers "B.Cu" "B.Mask")
			(net 140 "/SODIMM/LPDDR5_IN_B.DQ11")
			(pinfunction "DQ11_B")
			(pintype "passive")
		)
		(pad "207" smd rect
			(at 54.425 -1.375)
			(size 0.35 2.35)
			(layers "F.Cu" "F.Mask")
			(net 138 "/SODIMM/LPDDR5_IN_B.WCK1_N")
			(pinfunction "DQS1_B_C")
			(pintype "passive")
		)
		(pad "208" smd rect
			(at 54.675 -1.375 180)
			(size 0.35 2.35)
			(layers "B.Cu" "B.Mask")
			(net 14 "GND")
			(pinfunction "VSS")
			(pintype "passive")
		)
		(pad "209" smd rect
			(at 54.925 -1.375)
			(size 0.35 2.35)
			(layers "F.Cu" "F.Mask")
			(net 137 "/SODIMM/LPDDR5_IN_B.WCK1_P")
			(pinfunction "DQS1_B_t")
			(pintype "passive")
		)
		(pad "210" smd rect
			(at 55.175 -1.375 180)
			(size 0.35 2.35)
			(layers "B.Cu" "B.Mask")
			(net 121 "/SODIMM/LPDDR5_IN_B.DMI1")
			(pinfunction "DM1_B_n")
			(pintype "passive")
		)
		(pad "211" smd rect
			(at 55.425 -1.375)
			(size 0.35 2.35)
			(layers "F.Cu" "F.Mask")
			(net 14 "GND")
			(pinfunction "VSS")
			(pintype "passive")
		)
		(pad "212" smd rect
			(at 55.675 -1.375 180)
			(size 0.35 2.35)
			(layers "B.Cu" "B.Mask")
			(net 14 "GND")
			(pinfunction "VSS")
			(pintype "passive")
		)
		(pad "213" smd rect
			(at 55.925 -1.375)
			(size 0.35 2.35)
			(layers "F.Cu" "F.Mask")
			(net 133 "/SODIMM/LPDDR5_IN_B.DQ15")
			(pinfunction "DQ12_B")
			(pintype "passive")
		)
		(pad "214" smd rect
			(at 56.175 -1.375 180)
			(size 0.35 2.35)
			(layers "B.Cu" "B.Mask")
			(net 134 "/SODIMM/LPDDR5_IN_B.DQ14")
			(pinfunction "DQ13_B")
			(pintype "passive")
		)
		(pad "215" smd rect
			(at 56.425 -1.375)
			(size 0.35 2.35)
			(layers "F.Cu" "F.Mask")
			(net 14 "GND")
			(pinfunction "VSS")
			(pintype "passive")
		)
		(pad "216" smd rect
			(at 56.675 -1.375 180)
			(size 0.35 2.35)
			(layers "B.Cu" "B.Mask")
			(net 14 "GND")
			(pinfunction "VSS")
			(pintype "passive")
		)
		(pad "217" smd rect
			(at 56.925 -1.375)
			(size 0.35 2.35)
			(layers "F.Cu" "F.Mask")
			(net 136 "/SODIMM/LPDDR5_IN_B.DQ12")
			(pinfunction "DQ14_B")
			(pintype "passive")
		)
		(pad "218" smd rect
			(at 57.175 -1.375 180)
			(size 0.35 2.35)
			(layers "B.Cu" "B.Mask")
			(net 135 "/SODIMM/LPDDR5_IN_B.DQ13")
			(pinfunction "DQ15_B")
			(pintype "passive")
		)
		(pad "219" smd rect
			(at 57.425 -1.375)
			(size 0.35 2.35)
			(layers "F.Cu" "F.Mask")
			(net 14 "GND")
			(pinfunction "VSS")
			(pintype "passive")
		)
		(pad "220" smd rect
			(at 57.675 -1.375 180)
			(size 0.35 2.35)
			(layers "B.Cu" "B.Mask")
			(net 14 "GND")
			(pinfunction "VSS")
			(pintype "passive")
		)
		(pad "221" smd rect
			(at 57.925 -1.375)
			(size 0.35 2.35)
			(layers "F.Cu" "F.Mask")
			(net 219 "/LPDDR5/LPDDR5_B.DQ5")
			(pinfunction "DQ16_B")
			(pintype "passive")
		)
		(pad "222" smd rect
			(at 58.175 -1.375 180)
			(size 0.35 2.35)
			(layers "B.Cu" "B.Mask")
			(net 220 "/LPDDR5/LPDDR5_B.DQ4")
			(pinfunction "DQ17_B")
			(pintype "passive")
		)
		(pad "223" smd rect
			(at 58.425 -1.375)
			(size 0.35 2.35)
			(layers "F.Cu" "F.Mask")
			(net 14 "GND")
			(pinfunction "VSS")
			(pintype "passive")
		)
		(pad "224" smd rect
			(at 58.675 -1.375 180)
			(size 0.35 2.35)
			(layers "B.Cu" "B.Mask")
			(net 14 "GND")
			(pinfunction "VSS")
			(pintype "passive")
		)
		(pad "225" smd rect
			(at 58.925 -1.375)
			(size 0.35 2.35)
			(layers "F.Cu" "F.Mask")
			(net 218 "/LPDDR5/LPDDR5_B.DQ6")
			(pinfunction "DQ18_B")
			(pintype "passive")
		)
		(pad "226" smd rect
			(at 59.175 -1.375 180)
			(size 0.35 2.35)
			(layers "B.Cu" "B.Mask")
			(net 217 "/LPDDR5/LPDDR5_B.DQ7")
			(pinfunction "DQ19_B")
			(pintype "passive")
		)
		(pad "227" smd rect
			(at 59.425 -1.375)
			(size 0.35 2.35)
			(layers "F.Cu" "F.Mask")
			(net 14 "GND")
			(pinfunction "VSS")
			(pintype "passive")
		)
		(pad "228" smd rect
			(at 59.675 -1.375 180)
			(size 0.35 2.35)
			(layers "B.Cu" "B.Mask")
			(net 14 "GND")
			(pinfunction "VSS")
			(pintype "passive")
		)
		(pad "229" smd rect
			(at 59.925 -1.375)
			(size 0.35 2.35)
			(layers "F.Cu" "F.Mask")
			(net 212 "/LPDDR5/LPDDR5_B.DMI0")
			(pinfunction "DM2_B_n")
			(pintype "passive")
		)
		(pad "230" smd rect
			(at 60.175 -1.375 180)
			(size 0.35 2.35)
			(layers "B.Cu" "B.Mask")
			(net 221 "/LPDDR5/LPDDR5_B.RDQS0_N")
			(pinfunction "DQS2_B_C")
			(pintype "passive")
		)
		(pad "231" smd rect
			(at 60.425 -1.375)
			(size 0.35 2.35)
			(layers "F.Cu" "F.Mask")
			(net 14 "GND")
			(pinfunction "VSS")
			(pintype "passive")
		)
		(pad "232" smd rect
			(at 60.675 -1.375 180)
			(size 0.35 2.35)
			(layers "B.Cu" "B.Mask")
			(net 222 "/LPDDR5/LPDDR5_B.RDQS0_P")
			(pinfunction "DQS2_B_t")
			(pintype "passive")
		)
		(pad "233" smd rect
			(at 60.925 -1.375)
			(size 0.35 2.35)
			(layers "F.Cu" "F.Mask")
			(net 224 "/LPDDR5/LPDDR5_B.DQ3")
			(pinfunction "DQ20_B")
			(pintype "passive")
		)
		(pad "234" smd rect
			(at 61.175 -1.375 180)
			(size 0.35 2.35)
			(layers "B.Cu" "B.Mask")
			(net 14 "GND")
			(pinfunction "VSS")
			(pintype "passive")
		)
		(pad "235" smd rect
			(at 61.425 -1.375)
			(size 0.35 2.35)
			(layers "F.Cu" "F.Mask")
			(net 14 "GND")
			(pinfunction "VSS")
			(pintype "passive")
		)
		(pad "236" smd rect
			(at 61.675 -1.375 180)
			(size 0.35 2.35)
			(layers "B.Cu" "B.Mask")
			(net 226 "/LPDDR5/LPDDR5_B.DQ1")
			(pinfunction "DQ21_B")
			(pintype "passive")
		)
		(pad "237" smd rect
			(at 61.925 -1.375)
			(size 0.35 2.35)
			(layers "F.Cu" "F.Mask")
			(net 225 "/LPDDR5/LPDDR5_B.DQ2")
			(pinfunction "DQ22_B")
			(pintype "passive")
		)
		(pad "238" smd rect
			(at 62.175 -1.375 180)
			(size 0.35 2.35)
			(layers "B.Cu" "B.Mask")
			(net 14 "GND")
			(pinfunction "VSS")
			(pintype "passive")
		)
		(pad "239" smd rect
			(at 62.425 -1.375)
			(size 0.35 2.35)
			(layers "F.Cu" "F.Mask")
			(net 14 "GND")
			(pinfunction "VSS")
			(pintype "passive")
		)
		(pad "240" smd rect
			(at 62.675 -1.375 180)
			(size 0.35 2.35)
			(layers "B.Cu" "B.Mask")
			(net 227 "/LPDDR5/LPDDR5_B.DQ0")
			(pinfunction "DQ23_B")
			(pintype "passive")
		)
		(pad "241" smd rect
			(at 62.925 -1.375)
			(size 0.35 2.35)
			(layers "F.Cu" "F.Mask")
			(net 130 "/SODIMM/LPDDR5_IN_B.DQ5")
			(pinfunction "DQ24_B")
			(pintype "passive")
		)
		(pad "242" smd rect
			(at 63.175 -1.375 180)
			(size 0.35 2.35)
			(layers "B.Cu" "B.Mask")
			(net 14 "GND")
			(pinfunction "VSS")
			(pintype "passive")
		)
		(pad "243" smd rect
			(at 63.425 -1.375)
			(size 0.35 2.35)
			(layers "F.Cu" "F.Mask")
			(net 14 "GND")
			(pinfunction "VSS")
			(pintype "passive")
		)
		(pad "244" smd rect
			(at 63.675 -1.375 180)
			(size 0.35 2.35)
			(layers "B.Cu" "B.Mask")
			(net 129 "/SODIMM/LPDDR5_IN_B.DQ4")
			(pinfunction "DQ25_B")
			(pintype "passive")
		)
		(pad "245" smd rect
			(at 63.925 -1.375)
			(size 0.35 2.35)
			(layers "F.Cu" "F.Mask")
			(net 131 "/SODIMM/LPDDR5_IN_B.DQ6")
			(pinfunction "DQ26_B")
			(pintype "passive")
		)
		(pad "246" smd rect
			(at 64.175 -1.375 180)
			(size 0.35 2.35)
			(layers "B.Cu" "B.Mask")
			(net 14 "GND")
			(pinfunction "VSS")
			(pintype "passive")
		)
		(pad "247" smd rect
			(at 64.425 -1.375)
			(size 0.35 2.35)
			(layers "F.Cu" "F.Mask")
			(net 14 "GND")
			(pinfunction "VSS")
			(pintype "passive")
		)
		(pad "248" smd rect
			(at 64.675 -1.375 180)
			(size 0.35 2.35)
			(layers "B.Cu" "B.Mask")
			(net 132 "/SODIMM/LPDDR5_IN_B.DQ7")
			(pinfunction "DQ27_B")
			(pintype "passive")
		)
		(pad "249" smd rect
			(at 64.925 -1.375)
			(size 0.35 2.35)
			(layers "F.Cu" "F.Mask")
			(net 127 "/SODIMM/LPDDR5_IN_B.WCK0_N")
			(pinfunction "DQS3_B_c")
			(pintype "passive")
		)
		(pad "250" smd rect
			(at 65.175 -1.375 180)
			(size 0.35 2.35)
			(layers "B.Cu" "B.Mask")
			(net 14 "GND")
			(pinfunction "VSS")
			(pintype "passive")
		)
		(pad "251" smd rect
			(at 65.425 -1.375)
			(size 0.35 2.35)
			(layers "F.Cu" "F.Mask")
			(net 126 "/SODIMM/LPDDR5_IN_B.WCK0_P")
			(pinfunction "DQS3_B_t")
			(pintype "passive")
		)
		(pad "252" smd rect
			(at 65.675 -1.375 180)
			(size 0.35 2.35)
			(layers "B.Cu" "B.Mask")
			(net 120 "/SODIMM/LPDDR5_IN_B.DMI0")
			(pinfunction "DM3_B_n")
			(pintype "passive")
		)
		(pad "253" smd rect
			(at 65.925 -1.375)
			(size 0.35 2.35)
			(layers "F.Cu" "F.Mask")
			(net 14 "GND")
			(pinfunction "VSS")
			(pintype "passive")
		)
		(pad "254" smd rect
			(at 66.175 -1.375 180)
			(size 0.35 2.35)
			(layers "B.Cu" "B.Mask")
			(net 14 "GND")
			(pinfunction "VSS")
			(pintype "passive")
		)
		(pad "255" smd rect
			(at 66.425 -1.375)
			(size 0.35 2.35)
			(layers "F.Cu" "F.Mask")
			(net 125 "/SODIMM/LPDDR5_IN_B.DQ3")
			(pinfunction "DQ28_B")
			(pintype "passive")
		)
		(pad "256" smd rect
			(at 66.675 -1.375 180)
			(size 0.35 2.35)
			(layers "B.Cu" "B.Mask")
			(net 123 "/SODIMM/LPDDR5_IN_B.DQ1")
			(pinfunction "DQ29_B")
			(pintype "passive")
		)
		(pad "257" smd rect
			(at 66.925 -1.375)
			(size 0.35 2.35)
			(layers "F.Cu" "F.Mask")
			(net 14 "GND")
			(pinfunction "VSS")
			(pintype "passive")
		)
		(pad "258" smd rect
			(at 67.175 -1.375 180)
			(size 0.35 2.35)
			(layers "B.Cu" "B.Mask")
			(net 14 "GND")
			(pinfunction "VSS")
			(pintype "passive")
		)
		(pad "259" smd rect
			(at 67.425 -1.375)
			(size 0.35 2.35)
			(layers "F.Cu" "F.Mask")
			(net 124 "/SODIMM/LPDDR5_IN_B.DQ2")
			(pinfunction "DQ30_B")
			(pintype "passive")
		)
		(pad "260" smd rect
			(at 67.675 -1.375 180)
			(size 0.35 2.35)
			(layers "B.Cu" "B.Mask")
			(net 122 "/SODIMM/LPDDR5_IN_B.DQ0")
			(pinfunction "DQ31_B")
			(pintype "passive")
		)
		(pad "261" smd rect
			(at 67.925 -1.375)
			(size 0.35 2.35)
			(layers "F.Cu" "F.Mask")
			(net 14 "GND")
			(pinfunction "VSS")
			(pintype "passive")
		)
		(pad "262" smd rect
			(at 68.175 -1.375 180)
			(size 0.35 2.35)
			(layers "B.Cu" "B.Mask")
			(net 14 "GND")
			(pinfunction "VSS")
			(pintype "passive")
		)
	)
	(footprint "antmicro-footprints:R_0603_1608Metric"
		(layer "F.Cu")
		(at 114.25 70.9 180)
		(descr "Resistor SMD 0603")
		(tags "resistor SMD 0603")
		(property "Reference" "R45"
			(at -1.45 -1.7 0)
			(unlocked yes)
			(layer "F.SilkS")
			(effects
				(font
					(size 0.7 0.7)
					(thickness 0.15)
				)
				(justify right bottom)
			)
		)
		(property "Value" "R_0R_22.4A_0603"
			(at 0 1.6 0)
			(layer "F.Fab")
			(effects
				(font
					(size 0.7 0.7)
					(thickness 0.15)
				)
				(justify right bottom)
			)
		)
		(property "Author" "Antmicro"
			(at 228.5 141.8 0)
			(layer "F.Fab")
			(hide yes)
			(effects
				(font
					(size 1 1)
					(thickness 0.15)
				)
			)
		)
		(property "License" "Apache-2.0"
			(at 228.5 141.8 0)
			(layer "F.Fab")
			(hide yes)
			(effects
				(font
					(size 1 1)
					(thickness 0.15)
				)
			)
		)
		(property "MPN" "PMR03EZPJ000"
			(at 228.5 141.8 0)
			(layer "F.Fab")
			(hide yes)
			(effects
				(font
					(size 1 1)
					(thickness 0.15)
				)
			)
		)
		(property "Manufacturer" "ROHM Semiconductor"
			(at 228.5 141.8 0)
			(layer "F.Fab")
			(hide yes)
			(effects
				(font
					(size 1 1)
					(thickness 0.15)
				)
			)
		)
		(property "Max. Curr." "22.4A"
			(at 228.5 141.8 0)
			(layer "F.Fab")
			(hide yes)
			(effects
				(font
					(size 1 1)
					(thickness 0.15)
				)
			)
		)
		(property "Tolerance" "template_tolerance"
			(at 228.5 141.8 0)
			(layer "F.Fab")
			(hide yes)
			(effects
				(font
					(size 1 1)
					(thickness 0.15)
				)
			)
		)
		(property "Val" "0R"
			(at 228.5 141.8 0)
			(layer "F.Fab")
			(hide yes)
			(effects
				(font
					(size 1 1)
					(thickness 0.15)
				)
			)
		)
		(sheetname "Power supply")
		(sheetfile "power_supply.kicad_sch")
		(attr smd)
		(fp_line
			(start -0.3 0.3)
			(end 0.3 0.3)
			(stroke
				(width 0.15)
				(type solid)
			)
			(layer "F.SilkS")
		)
		(fp_line
			(start -0.3 -0.3)
			(end 0.3 -0.3)
			(stroke
				(width 0.15)
				(type solid)
			)
			(layer "F.SilkS")
		)
		(fp_rect
			(start -1.25 -0.7)
			(end 1.25 0.7)
			(stroke
				(width 0.05)
				(type solid)
			)
			(fill no)
			(layer "F.CrtYd")
		)
		(fp_rect
			(start -0.8 -0.4)
			(end 0.8 0.4)
			(stroke
				(width 0.15)
				(type solid)
			)
			(fill no)
			(layer "F.Fab")
		)
		(pad "1" smd roundrect
			(at -0.7 0 180)
			(size 0.6 0.8)
			(layers "F.Cu" "F.Mask" "F.Paste")
			(roundrect_rratio 0.2)
			(net 13 "+1V05")
			(pintype "passive")
		)
		(pad "2" smd roundrect
			(at 0.7 0 180)
			(size 0.6 0.8)
			(layers "F.Cu" "F.Mask" "F.Paste")
			(roundrect_rratio 0.2)
			(net 9 "/Power supply/VOUT3")
			(pintype "passive")
		)
	)
	(footprint "antmicro-footprints:R_0402_1005Metric"
		(layer "F.Cu")
		(at 162.075 65.35)
		(descr "Resistor SMD 0402")
		(tags "resistor SMD 0402")
		(property "Reference" "R29"
			(at -7.175 0.65 0)
			(unlocked yes)
			(layer "F.SilkS")
			(effects
				(font
					(size 0.7 0.7)
					(thickness 0.15)
				)
				(justify left bottom)
			)
		)
		(property "Value" "R_0R_0402"
			(at -1.011843 1.772047 0)
			(layer "F.Fab")
			(effects
				(font
					(size 0.7 0.7)
					(thickness 0.15)
				)
				(justify left bottom)
			)
		)
		(property "Author" "Antmicro"
			(at 0 0 0)
			(layer "F.Fab")
			(hide yes)
			(effects
				(font
					(size 1 1)
					(thickness 0.15)
				)
			)
		)
		(property "Current" "1A"
			(at 0 0 0)
			(layer "F.Fab")
			(hide yes)
			(effects
				(font
					(size 1 1)
					(thickness 0.15)
				)
			)
		)
		(property "License" "Apache-2.0"
			(at 0 0 0)
			(layer "F.Fab")
			(hide yes)
			(effects
				(font
					(size 1 1)
					(thickness 0.15)
				)
			)
		)
		(property "MPN" "ERJ2GE0R00X"
			(at 0 0 0)
			(layer "F.Fab")
			(hide yes)
			(effects
				(font
					(size 1 1)
					(thickness 0.15)
				)
			)
		)
		(property "Manufacturer" "Panasonic"
			(at 0 0 0)
			(layer "F.Fab")
			(hide yes)
			(effects
				(font
					(size 1 1)
					(thickness 0.15)
				)
			)
		)
		(property "Tolerance" ""
			(at 0 0 0)
			(layer "F.Fab")
			(hide yes)
			(effects
				(font
					(size 1 1)
					(thickness 0.15)
				)
			)
		)
		(property "Val" "0R"
			(at 0 0 0)
			(layer "F.Fab")
			(hide yes)
			(effects
				(font
					(size 1 1)
					(thickness 0.15)
				)
			)
		)
		(sheetname "Power supply")
		(sheetfile "power_supply.kicad_sch")
		(attr smd exclude_from_pos_files exclude_from_bom dnp)
		(fp_rect
			(start -0.93 -0.47)
			(end 0.93 0.47)
			(stroke
				(width 0.05)
				(type solid)
			)
			(fill no)
			(layer "F.CrtYd")
		)
		(fp_rect
			(start -0.5 -0.25)
			(end 0.5 0.25)
			(stroke
				(width 0.15)
				(type solid)
			)
			(fill no)
			(layer "F.Fab")
		)
		(pad "1" smd roundrect
			(at -0.485 0)
			(size 0.59 0.64)
			(layers "F.Cu" "F.Mask" "F.Paste")
			(roundrect_rratio 0.25)
			(net 20 "/Power supply/PWR_EN")
			(pintype "passive")
		)
		(pad "2" smd roundrect
			(at 0.485 0)
			(size 0.59 0.64)
			(layers "F.Cu" "F.Mask" "F.Paste")
			(roundrect_rratio 0.25)
			(net 61 "Net-(R29-Pad2)")
			(pintype "passive")
		)
	)
	(footprint "antmicro-footprints:TP_SMD_0.75mm"
		(layer "F.Cu")
		(at 102.4 71)
		(property "Reference" "TP7"
			(at -2.3 5.6 0)
			(unlocked yes)
			(layer "F.SilkS")
			(effects
				(font
					(size 0.7 0.7)
					(thickness 0.15)
				)
				(justify left bottom)
			)
		)
		(property "Value" "TP_0.75mm_SMD"
			(at 0 1.2 0)
			(layer "F.Fab")
			(effects
				(font
					(size 0.7 0.7)
					(thickness 0.15)
				)
				(justify left bottom)
			)
		)
		(property "Author" "Antmicro"
			(at 0 0 0)
			(layer "F.Fab")
			(hide yes)
			(effects
				(font
					(size 1 1)
					(thickness 0.15)
				)
			)
		)
		(property "License" "Apache-2.0"
			(at 0 0 0)
			(layer "F.Fab")
			(hide yes)
			(effects
				(font
					(size 1 1)
					(thickness 0.15)
				)
			)
		)
		(property "MPN" ""
			(at 0 0 0)
			(layer "F.Fab")
			(hide yes)
			(effects
				(font
					(size 1 1)
					(thickness 0.15)
				)
			)
		)
		(property "Manufacturer" ""
			(at 0 0 0)
			(layer "F.Fab")
			(hide yes)
			(effects
				(font
					(size 1 1)
					(thickness 0.15)
				)
			)
		)
		(sheetname "Power supply")
		(sheetfile "power_supply.kicad_sch")
		(attr exclude_from_pos_files)
		(pad "1" smd circle
			(at 0 0)
			(size 0.75 0.75)
			(layers "F.Cu" "F.Mask")
			(net 10 "/Power supply/VOUT4")
			(pinfunction "1")
			(pintype "passive")
		)
	)
	(footprint "antmicro-footprints:R_Array_4x0402_Panasonic_EXB28V"
		(layer "F.Cu")
		(at 166.2 93.8)
		(property "Reference" "R57"
			(at -1.301 -1.45 0)
			(unlocked yes)
			(layer "F.SilkS")
			(effects
				(font
					(size 0.7 0.7)
					(thickness 0.15)
				)
				(justify left bottom)
			)
		)
		(property "Value" "R_4x100R_0402_array"
			(at -1.5 2 0)
			(layer "F.Fab")
			(effects
				(font
					(size 0.7 0.7)
					(thickness 0.15)
				)
				(justify left bottom)
			)
		)
		(property "Author" "Antmicro"
			(at 0 0 0)
			(layer "F.Fab")
			(hide yes)
			(effects
				(font
					(size 1 1)
					(thickness 0.15)
				)
			)
		)
		(property "License" "Apache-2.0"
			(at 0 0 0)
			(layer "F.Fab")
			(hide yes)
			(effects
				(font
					(size 1 1)
					(thickness 0.15)
				)
			)
		)
		(property "MPN" "EXB-28V101JX"
			(at 0 0 0)
			(layer "F.Fab")
			(hide yes)
			(effects
				(font
					(size 1 1)
					(thickness 0.15)
				)
			)
		)
		(property "Manufacturer" "Panasonic"
			(at 0 0 0)
			(layer "F.Fab")
			(hide yes)
			(effects
				(font
					(size 1 1)
					(thickness 0.15)
				)
			)
		)
		(property "Val" "R_4x100R_0402"
			(at 0 0 0)
			(layer "F.Fab")
			(hide yes)
			(effects
				(font
					(size 1 1)
					(thickness 0.15)
				)
			)
		)
		(sheetname "Translators1")
		(sheetfile "translators.kicad_sch")
		(attr smd)
		(fp_line
			(start -1.25 -0.5)
			(end -1.25 0.498)
			(stroke
				(width 0.15)
				(type solid)
			)
			(layer "F.SilkS")
		)
		(fp_line
			(start 1.25 0.499)
			(end 1.25 -0.499)
			(stroke
				(width 0.15)
				(type solid)
			)
			(layer "F.SilkS")
		)
		(fp_rect
			(start -1.25 -0.8)
			(end 1.25 0.8)
			(stroke
				(width 0.05)
				(type solid)
			)
			(fill no)
			(layer "F.CrtYd")
		)
		(fp_line
			(start -1 -0.5)
			(end 0.998 -0.5)
			(stroke
				(width 0.15)
				(type solid)
			)
			(layer "F.Fab")
		)
		(fp_line
			(start -1 0.498)
			(end -1 -0.5)
			(stroke
				(width 0.15)
				(type solid)
			)
			(layer "F.Fab")
		)
		(fp_line
			(start 0.998 -0.5)
			(end 0.998 0.498)
			(stroke
				(width 0.15)
				(type solid)
			)
			(layer "F.Fab")
		)
		(fp_line
			(start 0.998 0.498)
			(end -1 0.498)
			(stroke
				(width 0.15)
				(type solid)
			)
			(layer "F.Fab")
		)
		(pad "1" smd roundrect
			(at -0.8875 0.45)
			(size 0.525 0.5)
			(layers "F.Cu" "F.Mask" "F.Paste")
			(roundrect_rratio 0.25)
			(net 125 "/SODIMM/LPDDR5_IN_B.DQ3")
			(pinfunction "R1.1")
			(pintype "passive")
		)
		(pad "2" smd roundrect
			(at -0.25 0.45)
			(size 0.25 0.5)
			(layers "F.Cu" "F.Mask" "F.Paste")
			(roundrect_rratio 0.25)
			(net 123 "/SODIMM/LPDDR5_IN_B.DQ1")
			(pinfunction "R2.1")
			(pintype "passive")
		)
		(pad "3" smd roundrect
			(at 0.25 0.45)
			(size 0.25 0.5)
			(layers "F.Cu" "F.Mask" "F.Paste")
			(roundrect_rratio 0.25)
			(net 124 "/SODIMM/LPDDR5_IN_B.DQ2")
			(pinfunction "R3.1")
			(pintype "passive")
		)
		(pad "4" smd roundrect
			(at 0.8875 0.45)
			(size 0.525 0.5)
			(layers "F.Cu" "F.Mask" "F.Paste")
			(roundrect_rratio 0.25)
			(net 122 "/SODIMM/LPDDR5_IN_B.DQ0")
			(pinfunction "R4.1")
			(pintype "passive")
		)
		(pad "5" smd roundrect
			(at 0.8875 -0.45)
			(size 0.525 0.5)
			(layers "F.Cu" "F.Mask" "F.Paste")
			(roundrect_rratio 0.25)
			(net 227 "/LPDDR5/LPDDR5_B.DQ0")
			(pinfunction "R4.2")
			(pintype "passive")
		)
		(pad "6" smd roundrect
			(at 0.25 -0.45)
			(size 0.25 0.5)
			(layers "F.Cu" "F.Mask" "F.Paste")
			(roundrect_rratio 0.25)
			(net 225 "/LPDDR5/LPDDR5_B.DQ2")
			(pinfunction "R3.2")
			(pintype "passive")
		)
		(pad "7" smd roundrect
			(at -0.25 -0.45)
			(size 0.25 0.5)
			(layers "F.Cu" "F.Mask" "F.Paste")
			(roundrect_rratio 0.25)
			(net 226 "/LPDDR5/LPDDR5_B.DQ1")
			(pinfunction "R2.2")
			(pintype "passive")
		)
		(pad "8" smd roundrect
			(at -0.8875 -0.45)
			(size 0.525 0.5)
			(layers "F.Cu" "F.Mask" "F.Paste")
			(roundrect_rratio 0.25)
			(net 224 "/LPDDR5/LPDDR5_B.DQ3")
			(pinfunction "R1.2")
			(pintype "passive")
		)
	)
	(footprint "antmicro-footprints:R_0402_1005Metric"
		(layer "F.Cu")
		(at 164.075 65.35 180)
		(descr "Resistor SMD 0402")
		(tags "resistor SMD 0402")
		(property "Reference" "R31"
			(at 4.975 -0.65 0)
			(unlocked yes)
			(layer "F.SilkS")
			(effects
				(font
					(size 0.7 0.7)
					(thickness 0.15)
				)
				(justify right bottom)
			)
		)
		(property "Value" "R_25k5_0402"
			(at -1.011843 1.772047 0)
			(layer "F.Fab")
			(effects
				(font
					(size 0.7 0.7)
					(thickness 0.15)
				)
				(justify right bottom)
			)
		)
		(property "Author" "Antmicro"
			(at 328.15 130.7 0)
			(layer "F.Fab")
			(hide yes)
			(effects
				(font
					(size 1 1)
					(thickness 0.15)
				)
			)
		)
		(property "License" "Apache-2.0"
			(at 328.15 130.7 0)
			(layer "F.Fab")
			(hide yes)
			(effects
				(font
					(size 1 1)
					(thickness 0.15)
				)
			)
		)
		(property "MPN" "CR0402-FX-2552GLF"
			(at 328.15 130.7 0)
			(layer "F.Fab")
			(hide yes)
			(effects
				(font
					(size 1 1)
					(thickness 0.15)
				)
			)
		)
		(property "Manufacturer" "Bourns"
			(at 328.15 130.7 0)
			(layer "F.Fab")
			(hide yes)
			(effects
				(font
					(size 1 1)
					(thickness 0.15)
				)
			)
		)
		(property "Tolerance" "1%"
			(at 328.15 130.7 0)
			(layer "F.Fab")
			(hide yes)
			(effects
				(font
					(size 1 1)
					(thickness 0.15)
				)
			)
		)
		(property "Val" "25k5"
			(at 328.15 130.7 0)
			(layer "F.Fab")
			(hide yes)
			(effects
				(font
					(size 1 1)
					(thickness 0.15)
				)
			)
		)
		(sheetname "Power supply")
		(sheetfile "power_supply.kicad_sch")
		(attr smd)
		(fp_rect
			(start -0.93 -0.47)
			(end 0.93 0.47)
			(stroke
				(width 0.05)
				(type solid)
			)
			(fill no)
			(layer "F.CrtYd")
		)
		(fp_rect
			(start -0.5 -0.25)
			(end 0.5 0.25)
			(stroke
				(width 0.15)
				(type solid)
			)
			(fill no)
			(layer "F.Fab")
		)
		(pad "1" smd roundrect
			(at -0.485 0 180)
			(size 0.59 0.64)
			(layers "F.Cu" "F.Mask" "F.Paste")
			(roundrect_rratio 0.25)
			(net 61 "Net-(R29-Pad2)")
			(pintype "passive")
		)
		(pad "2" smd roundrect
			(at 0.485 0 180)
			(size 0.59 0.64)
			(layers "F.Cu" "F.Mask" "F.Paste")
			(roundrect_rratio 0.25)
			(net 1 "+1V1")
			(pintype "passive")
		)
	)
	(footprint "antmicro-footprints:R_0402_1005Metric"
		(layer "F.Cu")
		(at 153.95 93.8 90)
		(descr "Resistor SMD 0402")
		(tags "resistor SMD 0402")
		(property "Reference" "R88"
			(at -1.8 -1.15 0)
			(unlocked yes)
			(layer "F.SilkS")
			(effects
				(font
					(size 0.7 0.7)
					(thickness 0.15)
				)
				(justify left bottom)
			)
		)
		(property "Value" "R_100R_0402"
			(at -1.011843 1.772047 90)
			(layer "F.Fab")
			(effects
				(font
					(size 0.7 0.7)
					(thickness 0.15)
				)
				(justify left bottom)
			)
		)
		(property "Author" "Antmicro"
			(at 247.75 -60.15 0)
			(layer "F.Fab")
			(hide yes)
			(effects
				(font
					(size 1 1)
					(thickness 0.15)
				)
			)
		)
		(property "License" "Apache-2.0"
			(at 247.75 -60.15 0)
			(layer "F.Fab")
			(hide yes)
			(effects
				(font
					(size 1 1)
					(thickness 0.15)
				)
			)
		)
		(property "MPN" "CR0402-FX-1000GLF"
			(at 247.75 -60.15 0)
			(layer "F.Fab")
			(hide yes)
			(effects
				(font
					(size 1 1)
					(thickness 0.15)
				)
			)
		)
		(property "Manufacturer" "Bourns"
			(at 247.75 -60.15 0)
			(layer "F.Fab")
			(hide yes)
			(effects
				(font
					(size 1 1)
					(thickness 0.15)
				)
			)
		)
		(property "Tolerance" "1%"
			(at 247.75 -60.15 0)
			(layer "F.Fab")
			(hide yes)
			(effects
				(font
					(size 1 1)
					(thickness 0.15)
				)
			)
		)
		(property "Val" "100R"
			(at 247.75 -60.15 0)
			(layer "F.Fab")
			(hide yes)
			(effects
				(font
					(size 1 1)
					(thickness 0.15)
				)
			)
		)
		(sheetname "Translators1")
		(sheetfile "translators.kicad_sch")
		(attr smd)
		(fp_rect
			(start -0.93 -0.47)
			(end 0.93 0.47)
			(stroke
				(width 0.05)
				(type solid)
			)
			(fill no)
			(layer "F.CrtYd")
		)
		(fp_rect
			(start -0.5 -0.25)
			(end 0.5 0.25)
			(stroke
				(width 0.15)
				(type solid)
			)
			(fill no)
			(layer "F.Fab")
		)
		(pad "1" smd roundrect
			(at -0.485 0 90)
			(size 0.59 0.64)
			(layers "F.Cu" "F.Mask" "F.Paste")
			(roundrect_rratio 0.25)
			(net 121 "/SODIMM/LPDDR5_IN_B.DMI1")
			(pintype "passive")
		)
		(pad "2" smd roundrect
			(at 0.485 0 90)
			(size 0.59 0.64)
			(layers "F.Cu" "F.Mask" "F.Paste")
			(roundrect_rratio 0.25)
			(net 223 "/LPDDR5/LPDDR5_B.DMI1")
			(pintype "passive")
		)
	)
	(footprint "antmicro-footprints:SOT-523"
		(layer "F.Cu")
		(at 168.175 64.75)
		(property "Reference" "Q2"
			(at -1.375 9.35 0)
			(unlocked yes)
			(layer "F.SilkS")
			(effects
				(font
					(size 0.7 0.7)
					(thickness 0.15)
				)
				(justify left bottom)
			)
		)
		(property "Value" "DMG1012T-7"
			(at 0.1 1.824 0)
			(layer "F.Fab")
			(effects
				(font
					(size 0.7 0.7)
					(thickness 0.15)
				)
				(justify left bottom)
			)
		)
		(property "Author" "Antmicro"
			(at 0 0 0)
			(layer "F.Fab")
			(hide yes)
			(effects
				(font
					(size 1 1)
					(thickness 0.15)
				)
			)
		)
		(property "License" "Apache-2.0"
			(at 0 0 0)
			(layer "F.Fab")
			(hide yes)
			(effects
				(font
					(size 1 1)
					(thickness 0.15)
				)
			)
		)
		(property "MPN" "DMG1012T-7"
			(at 0 0 0)
			(layer "F.Fab")
			(hide yes)
			(effects
				(font
					(size 1 1)
					(thickness 0.15)
				)
			)
		)
		(property "Manufacturer" "Diodes Incorporated"
			(at 0 0 0)
			(layer "F.Fab")
			(hide yes)
			(effects
				(font
					(size 1 1)
					(thickness 0.15)
				)
			)
		)
		(sheetname "Power supply")
		(sheetfile "power_supply.kicad_sch")
		(attr smd)
		(fp_line
			(start -0.927 -0.351)
			(end -0.725 -0.551)
			(stroke
				(width 0.15)
				(type solid)
			)
			(layer "F.SilkS")
		)
		(fp_line
			(start -0.927 -0.051)
			(end -0.927 -0.351)
			(stroke
				(width 0.15)
				(type solid)
			)
			(layer "F.SilkS")
		)
		(fp_line
			(start -0.725 -0.551)
			(end -0.277 -0.551)
			(stroke
				(width 0.15)
				(type solid)
			)
			(layer "F.SilkS")
		)
		(fp_line
			(start -0.277 -0.551)
			(end -0.277 -0.75)
			(stroke
				(width 0.15)
				(type solid)
			)
			(layer "F.SilkS")
		)
		(fp_circle
			(center -0.9652 0.9652)
			(end -0.9152 0.9652)
			(stroke
				(width 0.15)
				(type solid)
			)
			(fill yes)
			(layer "F.SilkS")
		)
		(fp_line
			(start -1.12 -1.16)
			(end -1.12 1.15)
			(stroke
				(width 0.05)
				(type solid)
			)
			(layer "F.CrtYd")
		)
		(fp_line
			(start -1.12 -1.16)
			(end 1.1 -1.16)
			(stroke
				(width 0.05)
				(type solid)
			)
			(layer "F.CrtYd")
		)
		(fp_line
			(start -1.12 1.15)
			(end 1.1 1.15)
			(stroke
				(width 0.05)
				(type solid)
			)
			(layer "F.CrtYd")
		)
		(fp_line
			(start 1.1 -1.16)
			(end 1.1 1.15)
			(stroke
				(width 0.05)
				(type solid)
			)
			(layer "F.CrtYd")
		)
		(fp_line
			(start -0.802 -0.276)
			(end -0.802 0.424)
			(stroke
				(width 0.15)
				(type solid)
			)
			(layer "F.Fab")
		)
		(fp_line
			(start -0.652 -0.425)
			(end -0.802 -0.276)
			(stroke
				(width 0.15)
				(type solid)
			)
			(layer "F.Fab")
		)
		(fp_line
			(start 0.8 -0.425)
			(end -0.652 -0.425)
			(stroke
				(width 0.15)
				(type solid)
			)
			(layer "F.Fab")
		)
		(fp_line
			(start 0.8 -0.425)
			(end 0.8 0.424)
			(stroke
				(width 0.15)
				(type solid)
			)
			(layer "F.Fab")
		)
		(fp_line
			(start 0.8 0.424)
			(end -0.802 0.424)
			(stroke
				(width 0.15)
				(type solid)
			)
			(layer "F.Fab")
		)
		(fp_circle
			(center -0.9652 0.9652)
			(end -0.9144 0.9652)
			(stroke
				(width 0.15)
				(type solid)
			)
			(fill no)
			(layer "F.Fab")
		)
		(pad "1" smd rect
			(at -0.5 0.65)
			(size 0.4 0.51)
			(layers "F.Cu" "F.Mask" "F.Paste")
			(net 41 "/Power supply/PWRGD")
			(pinfunction "G")
			(pintype "bidirectional")
		)
		(pad "2" smd rect
			(at 0.498 0.65)
			(size 0.4 0.51)
			(layers "F.Cu" "F.Mask" "F.Paste")
			(net 14 "GND")
			(pinfunction "S")
			(pintype "bidirectional")
		)
		(pad "3" smd rect
			(at 0 -0.652)
			(size 0.4 0.51)
			(layers "F.Cu" "F.Mask" "F.Paste")
			(net 17 "Net-(D2-Pad2)")
			(pinfunction "D")
			(pintype "bidirectional")
		)
	)
	(footprint "antmicro-footprints:C_0402_1005Metric"
		(layer "F.Cu")
		(at 167.6 67.45 180)
		(descr "Capacitor SMD 0402")
		(tags "capacitor SMD 0402")
		(property "Reference" "C13"
			(at -1.1 -8.95 0)
			(unlocked yes)
			(layer "F.SilkS")
			(effects
				(font
					(size 0.7 0.7)
					(thickness 0.15)
				)
				(justify right bottom)
			)
		)
		(property "Value" "C_10n_0402"
			(at -1.022927 2.155213 0)
			(layer "F.Fab")
			(effects
				(font
					(size 0.7 0.7)
					(thickness 0.15)
				)
				(justify right bottom)
			)
		)
		(property "Author" "Antmicro"
			(at 335.2 134.9 0)
			(layer "F.Fab")
			(hide yes)
			(effects
				(font
					(size 1 1)
					(thickness 0.15)
				)
			)
		)
		(property "Dielectric" "X7R"
			(at 335.2 134.9 0)
			(layer "F.Fab")
			(hide yes)
			(effects
				(font
					(size 1 1)
					(thickness 0.15)
				)
			)
		)
		(property "License" "Apache-2.0"
			(at 335.2 134.9 0)
			(layer "F.Fab")
			(hide yes)
			(effects
				(font
					(size 1 1)
					(thickness 0.15)
				)
			)
		)
		(property "MPN" "GRM155R71H103KA88D"
			(at 335.2 134.9 0)
			(layer "F.Fab")
			(hide yes)
			(effects
				(font
					(size 1 1)
					(thickness 0.15)
				)
			)
		)
		(property "Manufacturer" "Murata"
			(at 335.2 134.9 0)
			(layer "F.Fab")
			(hide yes)
			(effects
				(font
					(size 1 1)
					(thickness 0.15)
				)
			)
		)
		(property "Val" "10n"
			(at 335.2 134.9 0)
			(layer "F.Fab")
			(hide yes)
			(effects
				(font
					(size 1 1)
					(thickness 0.15)
				)
			)
		)
		(property "Voltage" "50V"
			(at 335.2 134.9 0)
			(layer "F.Fab")
			(hide yes)
			(effects
				(font
					(size 1 1)
					(thickness 0.15)
				)
			)
		)
		(sheetname "Power supply")
		(sheetfile "power_supply.kicad_sch")
		(attr smd)
		(fp_rect
			(start -0.9659 -0.481258)
			(end 0.9649 0.458742)
			(stroke
				(width 0.05)
				(type solid)
			)
			(fill no)
			(layer "F.CrtYd")
		)
		(fp_line
			(start 0.499 0.248)
			(end -0.499 0.248)
			(stroke
				(width 0.15)
				(type solid)
			)
			(layer "F.Fab")
		)
		(fp_line
			(start 0.499 -0.25)
			(end 0.499 0.248)
			(stroke
				(width 0.15)
				(type solid)
			)
			(layer "F.Fab")
		)
		(fp_line
			(start -0.499 0.248)
			(end -0.499 -0.25)
			(stroke
				(width 0.15)
				(type solid)
			)
			(layer "F.Fab")
		)
		(fp_line
			(start -0.499 -0.25)
			(end 0.499 -0.25)
			(stroke
				(width 0.15)
				(type solid)
			)
			(layer "F.Fab")
		)
		(pad "1" smd roundrect
			(at -0.484 0 180)
			(size 0.59 0.64)
			(layers "F.Cu" "F.Mask" "F.Paste")
			(roundrect_rratio 0.25)
			(net 14 "GND")
			(pintype "passive")
		)
		(pad "2" smd roundrect
			(at 0.484 0 180)
			(size 0.59 0.64)
			(layers "F.Cu" "F.Mask" "F.Paste")
			(roundrect_rratio 0.25)
			(net 6 "Net-(C13-Pad2)")
			(pintype "passive")
		)
	)
	(footprint "antmicro-footprints:R_0402_1005Metric"
		(layer "F.Cu")
		(at 161.55 61.9 90)
		(descr "Resistor SMD 0402")
		(tags "resistor SMD 0402")
		(property "Reference" "R3"
			(at -0.7 -0.65 90)
			(unlocked yes)
			(layer "F.SilkS")
			(effects
				(font
					(size 0.7 0.7)
					(thickness 0.15)
				)
				(justify left bottom)
			)
		)
		(property "Value" "R_0R_0402"
			(at -1.011843 1.772047 90)
			(layer "F.Fab")
			(effects
				(font
					(size 0.7 0.7)
					(thickness 0.15)
				)
				(justify left bottom)
			)
		)
		(property "Author" "Antmicro"
			(at 223.45 -99.65 0)
			(layer "F.Fab")
			(hide yes)
			(effects
				(font
					(size 1 1)
					(thickness 0.15)
				)
			)
		)
		(property "Current" "1A"
			(at 223.45 -99.65 0)
			(layer "F.Fab")
			(hide yes)
			(effects
				(font
					(size 1 1)
					(thickness 0.15)
				)
			)
		)
		(property "License" "Apache-2.0"
			(at 223.45 -99.65 0)
			(layer "F.Fab")
			(hide yes)
			(effects
				(font
					(size 1 1)
					(thickness 0.15)
				)
			)
		)
		(property "MPN" "ERJ2GE0R00X"
			(at 223.45 -99.65 0)
			(layer "F.Fab")
			(hide yes)
			(effects
				(font
					(size 1 1)
					(thickness 0.15)
				)
			)
		)
		(property "Manufacturer" "Panasonic"
			(at 223.45 -99.65 0)
			(layer "F.Fab")
			(hide yes)
			(effects
				(font
					(size 1 1)
					(thickness 0.15)
				)
			)
		)
		(property "Tolerance" ""
			(at 223.45 -99.65 0)
			(layer "F.Fab")
			(hide yes)
			(effects
				(font
					(size 1 1)
					(thickness 0.15)
				)
			)
		)
		(property "Val" "0R"
			(at 223.45 -99.65 0)
			(layer "F.Fab")
			(hide yes)
			(effects
				(font
					(size 1 1)
					(thickness 0.15)
				)
			)
		)
		(sheetname "Power supply")
		(sheetfile "power_supply.kicad_sch")
		(attr smd)
		(fp_rect
			(start -0.93 -0.47)
			(end 0.93 0.47)
			(stroke
				(width 0.05)
				(type solid)
			)
			(fill no)
			(layer "F.CrtYd")
		)
		(fp_rect
			(start -0.5 -0.25)
			(end 0.5 0.25)
			(stroke
				(width 0.15)
				(type solid)
			)
			(fill no)
			(layer "F.Fab")
		)
		(pad "1" smd roundrect
			(at -0.485 0 90)
			(size 0.59 0.64)
			(layers "F.Cu" "F.Mask" "F.Paste")
			(roundrect_rratio 0.25)
			(net 61 "Net-(R29-Pad2)")
			(pintype "passive")
		)
		(pad "2" smd roundrect
			(at 0.485 0 90)
			(size 0.59 0.64)
			(layers "F.Cu" "F.Mask" "F.Paste")
			(roundrect_rratio 0.25)
			(net 228 "/Power supply/DCDC_PWRGD")
			(pintype "passive")
		)
	)
	(footprint "antmicro-footprints:R_0402_1005Metric"
		(layer "F.Cu")
		(at 168.875 61.45 -90)
		(descr "Resistor SMD 0402")
		(tags "resistor SMD 0402")
		(property "Reference" "R42"
			(at 9.45 -0.125 90)
			(unlocked yes)
			(layer "F.SilkS")
			(effects
				(font
					(size 0.7 0.7)
					(thickness 0.15)
				)
				(justify right bottom)
			)
		)
		(property "Value" "R_1k_0402"
			(at -1.011843 1.772047 90)
			(layer "F.Fab")
			(effects
				(font
					(size 0.7 0.7)
					(thickness 0.15)
				)
				(justify right bottom)
			)
		)
		(property "Author" "Antmicro"
			(at 107.425 230.325 0)
			(layer "F.Fab")
			(hide yes)
			(effects
				(font
					(size 1 1)
					(thickness 0.15)
				)
			)
		)
		(property "License" "Apache-2.0"
			(at 107.425 230.325 0)
			(layer "F.Fab")
			(hide yes)
			(effects
				(font
					(size 1 1)
					(thickness 0.15)
				)
			)
		)
		(property "MPN" "CR0402-FX-1001GLF"
			(at 107.425 230.325 0)
			(layer "F.Fab")
			(hide yes)
			(effects
				(font
					(size 1 1)
					(thickness 0.15)
				)
			)
		)
		(property "Manufacturer" "Bourns"
			(at 107.425 230.325 0)
			(layer "F.Fab")
			(hide yes)
			(effects
				(font
					(size 1 1)
					(thickness 0.15)
				)
			)
		)
		(property "Tolerance" "1%"
			(at 107.425 230.325 0)
			(layer "F.Fab")
			(hide yes)
			(effects
				(font
					(size 1 1)
					(thickness 0.15)
				)
			)
		)
		(property "Val" "1k"
			(at 107.425 230.325 0)
			(layer "F.Fab")
			(hide yes)
			(effects
				(font
					(size 1 1)
					(thickness 0.15)
				)
			)
		)
		(sheetname "Power supply")
		(sheetfile "power_supply.kicad_sch")
		(attr smd)
		(fp_rect
			(start -0.93 -0.47)
			(end 0.93 0.47)
			(stroke
				(width 0.05)
				(type solid)
			)
			(fill no)
			(layer "F.CrtYd")
		)
		(fp_rect
			(start -0.5 -0.25)
			(end 0.5 0.25)
			(stroke
				(width 0.15)
				(type solid)
			)
			(fill no)
			(layer "F.Fab")
		)
		(pad "1" smd roundrect
			(at -0.485 0 270)
			(size 0.59 0.64)
			(layers "F.Cu" "F.Mask" "F.Paste")
			(roundrect_rratio 0.25)
			(net 5 "+5V")
			(pintype "passive")
		)
		(pad "2" smd roundrect
			(at 0.485 0 270)
			(size 0.59 0.64)
			(layers "F.Cu" "F.Mask" "F.Paste")
			(roundrect_rratio 0.25)
			(net 16 "Net-(D2-Pad1)")
			(pintype "passive")
		)
	)
	(footprint "antmicro-footprints:R_0402_1005Metric"
		(layer "F.Cu")
		(at 103.3 73.75 180)
		(descr "Resistor SMD 0402")
		(tags "resistor SMD 0402")
		(property "Reference" "R40"
			(at -0.9 -2.45 0)
			(unlocked yes)
			(layer "F.SilkS")
			(effects
				(font
					(size 0.7 0.7)
					(thickness 0.15)
				)
				(justify right bottom)
			)
		)
		(property "Value" "R_120k_0402"
			(at -1.011843 1.772047 0)
			(layer "F.Fab")
			(effects
				(font
					(size 0.7 0.7)
					(thickness 0.15)
				)
				(justify right bottom)
			)
		)
		(property "Author" "Antmicro"
			(at 206.6 147.5 0)
			(layer "F.Fab")
			(hide yes)
			(effects
				(font
					(size 1 1)
					(thickness 0.15)
				)
			)
		)
		(property "License" "Apache-2.0"
			(at 206.6 147.5 0)
			(layer "F.Fab")
			(hide yes)
			(effects
				(font
					(size 1 1)
					(thickness 0.15)
				)
			)
		)
		(property "MPN" "CR0402-FX-1203GLF"
			(at 206.6 147.5 0)
			(layer "F.Fab")
			(hide yes)
			(effects
				(font
					(size 1 1)
					(thickness 0.15)
				)
			)
		)
		(property "Manufacturer" "Bourns"
			(at 206.6 147.5 0)
			(layer "F.Fab")
			(hide yes)
			(effects
				(font
					(size 1 1)
					(thickness 0.15)
				)
			)
		)
		(property "Tolerance" "1%"
			(at 206.6 147.5 0)
			(layer "F.Fab")
			(hide yes)
			(effects
				(font
					(size 1 1)
					(thickness 0.15)
				)
			)
		)
		(property "Val" "120k"
			(at 206.6 147.5 0)
			(layer "F.Fab")
			(hide yes)
			(effects
				(font
					(size 1 1)
					(thickness 0.15)
				)
			)
		)
		(sheetname "Power supply")
		(sheetfile "power_supply.kicad_sch")
		(attr smd)
		(fp_rect
			(start -0.93 -0.47)
			(end 0.93 0.47)
			(stroke
				(width 0.05)
				(type solid)
			)
			(fill no)
			(layer "F.CrtYd")
		)
		(fp_rect
			(start -0.5 -0.25)
			(end 0.5 0.25)
			(stroke
				(width 0.15)
				(type solid)
			)
			(fill no)
			(layer "F.Fab")
		)
		(pad "1" smd roundrect
			(at -0.485 0 180)
			(size 0.59 0.64)
			(layers "F.Cu" "F.Mask" "F.Paste")
			(roundrect_rratio 0.25)
			(net 73 "/Power supply/FB4")
			(pintype "passive")
		)
		(pad "2" smd roundrect
			(at 0.485 0 180)
			(size 0.59 0.64)
			(layers "F.Cu" "F.Mask" "F.Paste")
			(roundrect_rratio 0.25)
			(net 14 "GND")
			(pintype "passive")
		)
	)
	(footprint "antmicro-footprints:R_0402_1005Metric"
		(layer "F.Cu")
		(at 132.1 93.8 90)
		(descr "Resistor SMD 0402")
		(tags "resistor SMD 0402")
		(property "Reference" "R59"
			(at -1.122484 1.5 90)
			(unlocked yes)
			(layer "F.SilkS")
			(effects
				(font
					(size 0.7 0.7)
					(thickness 0.15)
				)
				(justify left bottom)
			)
		)
		(property "Value" "R_100R_0402"
			(at -1.011843 1.772047 90)
			(layer "F.Fab")
			(effects
				(font
					(size 0.7 0.7)
					(thickness 0.15)
				)
				(justify left bottom)
			)
		)
		(property "Author" "Antmicro"
			(at 225.9 -38.3 0)
			(layer "F.Fab")
			(hide yes)
			(effects
				(font
					(size 1 1)
					(thickness 0.15)
				)
			)
		)
		(property "License" "Apache-2.0"
			(at 225.9 -38.3 0)
			(layer "F.Fab")
			(hide yes)
			(effects
				(font
					(size 1 1)
					(thickness 0.15)
				)
			)
		)
		(property "MPN" "CR0402-FX-1000GLF"
			(at 225.9 -38.3 0)
			(layer "F.Fab")
			(hide yes)
			(effects
				(font
					(size 1 1)
					(thickness 0.15)
				)
			)
		)
		(property "Manufacturer" "Bourns"
			(at 225.9 -38.3 0)
			(layer "F.Fab")
			(hide yes)
			(effects
				(font
					(size 1 1)
					(thickness 0.15)
				)
			)
		)
		(property "Tolerance" "1%"
			(at 225.9 -38.3 0)
			(layer "F.Fab")
			(hide yes)
			(effects
				(font
					(size 1 1)
					(thickness 0.15)
				)
			)
		)
		(property "Val" "100R"
			(at 225.9 -38.3 0)
			(layer "F.Fab")
			(hide yes)
			(effects
				(font
					(size 1 1)
					(thickness 0.15)
				)
			)
		)
		(sheetname "Translators")
		(sheetfile "translators.kicad_sch")
		(attr smd)
		(fp_rect
			(start -0.93 -0.47)
			(end 0.93 0.47)
			(stroke
				(width 0.05)
				(type solid)
			)
			(fill no)
			(layer "F.CrtYd")
		)
		(fp_rect
			(start -0.5 -0.25)
			(end 0.5 0.25)
			(stroke
				(width 0.15)
				(type solid)
			)
			(fill no)
			(layer "F.Fab")
		)
		(pad "1" smd roundrect
			(at -0.485 0 90)
			(size 0.59 0.64)
			(layers "F.Cu" "F.Mask" "F.Paste")
			(roundrect_rratio 0.25)
			(net 157 "/SODIMM/LPDDR5_IN_A.CA6")
			(pintype "passive")
		)
		(pad "2" smd roundrect
			(at 0.485 0 90)
			(size 0.59 0.64)
			(layers "F.Cu" "F.Mask" "F.Paste")
			(roundrect_rratio 0.25)
			(net 55 "/LPDDR5/LPDDR5_A.CA6")
			(pintype "passive")
		)
	)
	(footprint "antmicro-footprints:LED_0603_1608Metric_G"
		(layer "F.Cu")
		(at 167.675 62.25 -90)
		(descr "LED SMD 0603 Green")
		(tags "LED SMD 0603 Green")
		(property "Reference" "D2"
			(at 9.45 -0.225 90)
			(unlocked yes)
			(layer "F.SilkS")
			(effects
				(font
					(size 0.7 0.7)
					(thickness 0.15)
				)
				(justify right bottom)
			)
		)
		(property "Value" "LED_G_0603_KP-1608CGCK"
			(at -0.001 1.599 90)
			(layer "F.Fab")
			(effects
				(font
					(size 0.7 0.7)
					(thickness 0.15)
				)
				(justify right bottom)
			)
		)
		(property "Author" "Antmicro"
			(at 105.425 229.925 0)
			(layer "F.Fab")
			(hide yes)
			(effects
				(font
					(size 1 1)
					(thickness 0.15)
				)
			)
		)
		(property "License" "Apache-2.0"
			(at 105.425 229.925 0)
			(layer "F.Fab")
			(hide yes)
			(effects
				(font
					(size 1 1)
					(thickness 0.15)
				)
			)
		)
		(property "MPN" "KP-1608CGCK"
			(at 105.425 229.925 0)
			(layer "F.Fab")
			(hide yes)
			(effects
				(font
					(size 1 1)
					(thickness 0.15)
				)
			)
		)
		(property "Manufacturer" "Kingbright"
			(at 105.425 229.925 0)
			(layer "F.Fab")
			(hide yes)
			(effects
				(font
					(size 1 1)
					(thickness 0.15)
				)
			)
		)
		(sheetname "Power supply")
		(sheetfile "power_supply.kicad_sch")
		(attr smd)
		(fp_line
			(start -0.271 0.348)
			(end 0.269 0.348)
			(stroke
				(width 0.15)
				(type solid)
			)
			(layer "F.SilkS")
		)
		(fp_line
			(start 1.249 0.319)
			(end 1.249 -0.321)
			(stroke
				(width 0.15)
				(type solid)
			)
			(layer "F.SilkS")
		)
		(fp_line
			(start -0.107 -0.001)
			(end -0.291 -0.001)
			(stroke
				(width 0.1)
				(type solid)
			)
			(layer "F.SilkS")
		)
		(fp_line
			(start 0.092 -0.001)
			(end -0.107 0.198)
			(stroke
				(width 0.1)
				(type solid)
			)
			(layer "F.SilkS")
		)
		(fp_line
			(start 0.092 -0.001)
			(end 0.292 -0.001)
			(stroke
				(width 0.1)
				(type solid)
			)
			(layer "F.SilkS")
		)
		(fp_line
			(start -0.107 -0.201)
			(end -0.107 0.198)
			(stroke
				(width 0.1)
				(type solid)
			)
			(layer "F.SilkS")
		)
		(fp_line
			(start -0.107 -0.201)
			(end 0.092 -0.001)
			(stroke
				(width 0.1)
				(type solid)
			)
			(layer "F.SilkS")
		)
		(fp_line
			(start 0.092 -0.201)
			(end 0.092 0.198)
			(stroke
				(width 0.1)
				(type solid)
			)
			(layer "F.SilkS")
		)
		(fp_line
			(start -0.271 -0.349)
			(end 0.269 -0.349)
			(stroke
				(width 0.15)
				(type solid)
			)
			(layer "F.SilkS")
		)
		(fp_rect
			(start -1.2192 -0.6096)
			(end 1.27 0.6016)
			(stroke
				(width 0.05)
				(type solid)
			)
			(fill no)
			(layer "F.CrtYd")
		)
		(fp_line
			(start -0.202 0.201)
			(end 0.1 -0.001)
			(stroke
				(width 0.15)
				(type solid)
			)
			(layer "F.Fab")
		)
		(fp_line
			(start 0.198 0.201)
			(end 0.198 -0.101)
			(stroke
				(width 0.15)
				(type solid)
			)
			(layer "F.Fab")
		)
		(fp_line
			(start -0.849 0.025)
			(end -0.442 0.381)
			(stroke
				(width 0.15)
				(type solid)
			)
			(layer "F.Fab")
		)
		(fp_line
			(start -0.6 -0.001)
			(end -0.202 -0.001)
			(stroke
				(width 0.15)
				(type solid)
			)
			(layer "F.Fab")
		)
		(fp_line
			(start -0.202 -0.001)
			(end -0.202 0.201)
			(stroke
				(width 0.15)
				(type solid)
			)
			(layer "F.Fab")
		)
		(fp_line
			(start 0.1 -0.001)
			(end -0.202 -0.201)
			(stroke
				(width 0.15)
				(type solid)
			)
			(layer "F.Fab")
		)
		(fp_line
			(start 0.198 -0.001)
			(end 0.596 -0.001)
			(stroke
				(width 0.15)
				(type solid)
			)
			(layer "F.Fab")
		)
		(fp_line
			(start -0.202 -0.201)
			(end -0.202 -0.001)
			(stroke
				(width 0.15)
				(type solid)
			)
			(layer "F.Fab")
		)
		(fp_line
			(start 0.198 -0.201)
			(end 0.198 -0.101)
			(stroke
				(width 0.15)
				(type solid)
			)
			(layer "F.Fab")
		)
		(fp_rect
			(start -0.849 -0.401)
			(end 0.849 0.401)
			(stroke
				(width 0.15)
				(type solid)
			)
			(fill no)
			(layer "F.Fab")
		)
		(pad "1" smd rect
			(at -0.751 -0.001 90)
			(size 0.8 0.8)
			(layers "F.Cu" "F.Mask" "F.Paste")
			(net 16 "Net-(D2-Pad1)")
			(pinfunction "1")
			(pintype "passive")
		)
		(pad "2" smd rect
			(at 0.749 -0.001 90)
			(size 0.8 0.8)
			(layers "F.Cu" "F.Mask" "F.Paste")
			(net 17 "Net-(D2-Pad2)")
			(pinfunction "2")
			(pintype "passive")
		)
	)
	(footprint "antmicro-footprints:C_0402_1005Metric"
		(layer "F.Cu")
		(at 162.475 70.65)
		(descr "Capacitor SMD 0402")
		(tags "capacitor SMD 0402")
		(property "Reference" "C8"
			(at -0.975 2.45 0)
			(unlocked yes)
			(layer "F.SilkS")
			(effects
				(font
					(size 0.7 0.7)
					(thickness 0.15)
				)
				(justify left bottom)
			)
		)
		(property "Value" "C_4u7_0402"
			(at -1.022927 2.155213 0)
			(layer "F.Fab")
			(effects
				(font
					(size 0.7 0.7)
					(thickness 0.15)
				)
				(justify left bottom)
			)
		)
		(property "Author" "Antmicro"
			(at 0 0 0)
			(layer "F.Fab")
			(hide yes)
			(effects
				(font
					(size 1 1)
					(thickness 0.15)
				)
			)
		)
		(property "Dielectric" ""
			(at 0 0 0)
			(layer "F.Fab")
			(hide yes)
			(effects
				(font
					(size 1 1)
					(thickness 0.15)
				)
			)
		)
		(property "License" "Apache-2.0"
			(at 0 0 0)
			(layer "F.Fab")
			(hide yes)
			(effects
				(font
					(size 1 1)
					(thickness 0.15)
				)
			)
		)
		(property "MPN" "GRM155R61A475MEAAD"
			(at 0 0 0)
			(layer "F.Fab")
			(hide yes)
			(effects
				(font
					(size 1 1)
					(thickness 0.15)
				)
			)
		)
		(property "Manufacturer" "Murata"
			(at 0 0 0)
			(layer "F.Fab")
			(hide yes)
			(effects
				(font
					(size 1 1)
					(thickness 0.15)
				)
			)
		)
		(property "Val" "4u7"
			(at 0 0 0)
			(layer "F.Fab")
			(hide yes)
			(effects
				(font
					(size 1 1)
					(thickness 0.15)
				)
			)
		)
		(property "Voltage" ""
			(at 0 0 0)
			(layer "F.Fab")
			(hide yes)
			(effects
				(font
					(size 1 1)
					(thickness 0.15)
				)
			)
		)
		(sheetname "Power supply")
		(sheetfile "power_supply.kicad_sch")
		(attr smd)
		(fp_rect
			(start -0.9659 -0.481258)
			(end 0.9649 0.458742)
			(stroke
				(width 0.05)
				(type solid)
			)
			(fill no)
			(layer "F.CrtYd")
		)
		(fp_line
			(start -0.499 -0.25)
			(end 0.499 -0.25)
			(stroke
				(width 0.15)
				(type solid)
			)
			(layer "F.Fab")
		)
		(fp_line
			(start -0.499 0.248)
			(end -0.499 -0.25)
			(stroke
				(width 0.15)
				(type solid)
			)
			(layer "F.Fab")
		)
		(fp_line
			(start 0.499 -0.25)
			(end 0.499 0.248)
			(stroke
				(width 0.15)
				(type solid)
			)
			(layer "F.Fab")
		)
		(fp_line
			(start 0.499 0.248)
			(end -0.499 0.248)
			(stroke
				(width 0.15)
				(type solid)
			)
			(layer "F.Fab")
		)
		(pad "1" smd roundrect
			(at -0.484 0)
			(size 0.59 0.64)
			(layers "F.Cu" "F.Mask" "F.Paste")
			(roundrect_rratio 0.25)
			(net 14 "GND")
			(pintype "passive")
		)
		(pad "2" smd roundrect
			(at 0.484 0)
			(size 0.59 0.64)
			(layers "F.Cu" "F.Mask" "F.Paste")
			(roundrect_rratio 0.25)
			(net 1 "+1V1")
			(pintype "passive")
		)
	)
	(footprint "antmicro-footprints:R_0402_1005Metric"
		(layer "F.Cu")
		(at 111.4 65.625 90)
		(descr "Resistor SMD 0402")
		(tags "resistor SMD 0402")
		(property "Reference" "R36"
			(at -2.975 0.4 90)
			(unlocked yes)
			(layer "F.SilkS")
			(effects
				(font
					(size 0.7 0.7)
					(thickness 0.15)
				)
				(justify left bottom)
			)
		)
		(property "Value" "R_200k_0402"
			(at -1.011843 1.772047 90)
			(layer "F.Fab")
			(effects
				(font
					(size 0.7 0.7)
					(thickness 0.15)
				)
				(justify left bottom)
			)
		)
		(property "Author" "Antmicro"
			(at 177.025 -45.775 0)
			(layer "F.Fab")
			(hide yes)
			(effects
				(font
					(size 1 1)
					(thickness 0.15)
				)
			)
		)
		(property "License" "Apache-2.0"
			(at 177.025 -45.775 0)
			(layer "F.Fab")
			(hide yes)
			(effects
				(font
					(size 1 1)
					(thickness 0.15)
				)
			)
		)
		(property "MPN" "CR0402-FX-2003GLF"
			(at 177.025 -45.775 0)
			(layer "F.Fab")
			(hide yes)
			(effects
				(font
					(size 1 1)
					(thickness 0.15)
				)
			)
		)
		(property "Manufacturer" "Bourns"
			(at 177.025 -45.775 0)
			(layer "F.Fab")
			(hide yes)
			(effects
				(font
					(size 1 1)
					(thickness 0.15)
				)
			)
		)
		(property "Tolerance" "1%"
			(at 177.025 -45.775 0)
			(layer "F.Fab")
			(hide yes)
			(effects
				(font
					(size 1 1)
					(thickness 0.15)
				)
			)
		)
		(property "Val" "200k"
			(at 177.025 -45.775 0)
			(layer "F.Fab")
			(hide yes)
			(effects
				(font
					(size 1 1)
					(thickness 0.15)
				)
			)
		)
		(sheetname "Power supply")
		(sheetfile "power_supply.kicad_sch")
		(attr smd)
		(fp_rect
			(start -0.93 -0.47)
			(end 0.93 0.47)
			(stroke
				(width 0.05)
				(type solid)
			)
			(fill no)
			(layer "F.CrtYd")
		)
		(fp_rect
			(start -0.5 -0.25)
			(end 0.5 0.25)
			(stroke
				(width 0.15)
				(type solid)
			)
			(fill no)
			(layer "F.Fab")
		)
		(pad "1" smd roundrect
			(at -0.485 0 90)
			(size 0.59 0.64)
			(layers "F.Cu" "F.Mask" "F.Paste")
			(roundrect_rratio 0.25)
			(net 71 "/Power supply/FB2")
			(pintype "passive")
		)
		(pad "2" smd roundrect
			(at 0.485 0 90)
			(size 0.59 0.64)
			(layers "F.Cu" "F.Mask" "F.Paste")
			(roundrect_rratio 0.25)
			(net 14 "GND")
			(pintype "passive")
		)
	)
	(footprint "antmicro-footprints:C_0603_1608Metric"
		(layer "F.Cu")
		(at 108.025 62.575)
		(descr "Capacitor SMD 0603")
		(tags "capacitor 0603")
		(property "Reference" "C17"
			(at -1.125 1.325 0)
			(unlocked yes)
			(layer "F.SilkS")
			(effects
				(font
					(size 0.7 0.7)
					(thickness 0.15)
				)
				(justify left bottom)
			)
		)
		(property "Value" "C_22u_0603"
			(at -1.42757 1.770288 0)
			(layer "F.Fab")
			(effects
				(font
					(size 0.7 0.7)
					(thickness 0.15)
				)
				(justify left bottom)
			)
		)
		(property "Author" "Antmicro"
			(at 0 0 0)
			(layer "F.Fab")
			(hide yes)
			(effects
				(font
					(size 1 1)
					(thickness 0.15)
				)
			)
		)
		(property "Dielectric" ""
			(at 0 0 0)
			(layer "F.Fab")
			(hide yes)
			(effects
				(font
					(size 1 1)
					(thickness 0.15)
				)
			)
		)
		(property "License" "Apache-2.0"
			(at 0 0 0)
			(layer "F.Fab")
			(hide yes)
			(effects
				(font
					(size 1 1)
					(thickness 0.15)
				)
			)
		)
		(property "MPN" "GRM188R60J226MEA0D"
			(at 0 0 0)
			(layer "F.Fab")
			(hide yes)
			(effects
				(font
					(size 1 1)
					(thickness 0.15)
				)
			)
		)
		(property "Manufacturer" "Murata"
			(at 0 0 0)
			(layer "F.Fab")
			(hide yes)
			(effects
				(font
					(size 1 1)
					(thickness 0.15)
				)
			)
		)
		(property "Val" "22u"
			(at 0 0 0)
			(layer "F.Fab")
			(hide yes)
			(effects
				(font
					(size 1 1)
					(thickness 0.15)
				)
			)
		)
		(property "Voltage" ""
			(at 0 0 0)
			(layer "F.Fab")
			(hide yes)
			(effects
				(font
					(size 1 1)
					(thickness 0.15)
				)
			)
		)
		(sheetname "Power supply")
		(sheetfile "power_supply.kicad_sch")
		(attr smd)
		(fp_line
			(start -0.3 -0.3)
			(end 0.3 -0.3)
			(stroke
				(width 0.15)
				(type solid)
			)
			(layer "F.SilkS")
		)
		(fp_line
			(start -0.3 0.3)
			(end 0.3 0.3)
			(stroke
				(width 0.15)
				(type solid)
			)
			(layer "F.SilkS")
		)
		(fp_rect
			(start -1.24 -0.7)
			(end 1.24 0.7)
			(stroke
				(width 0.05)
				(type solid)
			)
			(fill no)
			(layer "F.CrtYd")
		)
		(fp_rect
			(start -0.8 -0.4)
			(end 0.8 0.4)
			(stroke
				(width 0.15)
				(type solid)
			)
			(fill no)
			(layer "F.Fab")
		)
		(pad "1" smd roundrect
			(at -0.7 0)
			(size 0.6 0.8)
			(layers "F.Cu" "F.Mask" "F.Paste")
			(roundrect_rratio 0.2)
			(net 14 "GND")
			(pintype "passive")
		)
		(pad "2" smd roundrect
			(at 0.7 0)
			(size 0.6 0.8)
			(layers "F.Cu" "F.Mask" "F.Paste")
			(roundrect_rratio 0.2)
			(net 8 "/Power supply/VOUT2")
			(pintype "passive")
		)
	)
	(footprint "antmicro-footprints:C_0402_1005Metric"
		(layer "F.Cu")
		(at 162.475 71.65)
		(descr "Capacitor SMD 0402")
		(tags "capacitor SMD 0402")
		(property "Reference" "C9"
			(at -0.975 2.65 0)
			(unlocked yes)
			(layer "F.SilkS")
			(effects
				(font
					(size 0.7 0.7)
					(thickness 0.15)
				)
				(justify left bottom)
			)
		)
		(property "Value" "C_4u7_0402"
			(at -1.022927 2.155213 0)
			(layer "F.Fab")
			(effects
				(font
					(size 0.7 0.7)
					(thickness 0.15)
				)
				(justify left bottom)
			)
		)
		(property "Author" "Antmicro"
			(at 0 0 0)
			(layer "F.Fab")
			(hide yes)
			(effects
				(font
					(size 1 1)
					(thickness 0.15)
				)
			)
		)
		(property "Dielectric" ""
			(at 0 0 0)
			(layer "F.Fab")
			(hide yes)
			(effects
				(font
					(size 1 1)
					(thickness 0.15)
				)
			)
		)
		(property "License" "Apache-2.0"
			(at 0 0 0)
			(layer "F.Fab")
			(hide yes)
			(effects
				(font
					(size 1 1)
					(thickness 0.15)
				)
			)
		)
		(property "MPN" "GRM155R61A475MEAAD"
			(at 0 0 0)
			(layer "F.Fab")
			(hide yes)
			(effects
				(font
					(size 1 1)
					(thickness 0.15)
				)
			)
		)
		(property "Manufacturer" "Murata"
			(at 0 0 0)
			(layer "F.Fab")
			(hide yes)
			(effects
				(font
					(size 1 1)
					(thickness 0.15)
				)
			)
		)
		(property "Val" "4u7"
			(at 0 0 0)
			(layer "F.Fab")
			(hide yes)
			(effects
				(font
					(size 1 1)
					(thickness 0.15)
				)
			)
		)
		(property "Voltage" ""
			(at 0 0 0)
			(layer "F.Fab")
			(hide yes)
			(effects
				(font
					(size 1 1)
					(thickness 0.15)
				)
			)
		)
		(sheetname "Power supply")
		(sheetfile "power_supply.kicad_sch")
		(attr smd)
		(fp_rect
			(start -0.9659 -0.481258)
			(end 0.9649 0.458742)
			(stroke
				(width 0.05)
				(type solid)
			)
			(fill no)
			(layer "F.CrtYd")
		)
		(fp_line
			(start -0.499 -0.25)
			(end 0.499 -0.25)
			(stroke
				(width 0.15)
				(type solid)
			)
			(layer "F.Fab")
		)
		(fp_line
			(start -0.499 0.248)
			(end -0.499 -0.25)
			(stroke
				(width 0.15)
				(type solid)
			)
			(layer "F.Fab")
		)
		(fp_line
			(start 0.499 -0.25)
			(end 0.499 0.248)
			(stroke
				(width 0.15)
				(type solid)
			)
			(layer "F.Fab")
		)
		(fp_line
			(start 0.499 0.248)
			(end -0.499 0.248)
			(stroke
				(width 0.15)
				(type solid)
			)
			(layer "F.Fab")
		)
		(pad "1" smd roundrect
			(at -0.484 0)
			(size 0.59 0.64)
			(layers "F.Cu" "F.Mask" "F.Paste")
			(roundrect_rratio 0.25)
			(net 14 "GND")
			(pintype "passive")
		)
		(pad "2" smd roundrect
			(at 0.484 0)
			(size 0.59 0.64)
			(layers "F.Cu" "F.Mask" "F.Paste")
			(roundrect_rratio 0.25)
			(net 1 "+1V1")
			(pintype "passive")
		)
	)
	(footprint "antmicro-footprints:C_0402_1005Metric"
		(layer "F.Cu")
		(at 125.6 78.95 90)
		(descr "Capacitor SMD 0402")
		(tags "capacitor SMD 0402")
		(property "Reference" "C63"
			(at 0.95 0.325 90)
			(unlocked yes)
			(layer "F.SilkS")
			(effects
				(font
					(size 0.7 0.7)
					(thickness 0.15)
				)
				(justify left bottom)
			)
		)
		(property "Value" "C_4u7_0402"
			(at -1.022927 2.155213 90)
			(layer "F.Fab")
			(effects
				(font
					(size 0.7 0.7)
					(thickness 0.15)
				)
				(justify left bottom)
			)
		)
		(property "Author" "Antmicro"
			(at 204.55 -46.65 0)
			(layer "F.Fab")
			(hide yes)
			(effects
				(font
					(size 1 1)
					(thickness 0.15)
				)
			)
		)
		(property "Dielectric" ""
			(at 204.55 -46.65 0)
			(layer "F.Fab")
			(hide yes)
			(effects
				(font
					(size 1 1)
					(thickness 0.15)
				)
			)
		)
		(property "License" "Apache-2.0"
			(at 204.55 -46.65 0)
			(layer "F.Fab")
			(hide yes)
			(effects
				(font
					(size 1 1)
					(thickness 0.15)
				)
			)
		)
		(property "MPN" "GRM155R61A475MEAAD"
			(at 204.55 -46.65 0)
			(layer "F.Fab")
			(hide yes)
			(effects
				(font
					(size 1 1)
					(thickness 0.15)
				)
			)
		)
		(property "Manufacturer" "Murata"
			(at 204.55 -46.65 0)
			(layer "F.Fab")
			(hide yes)
			(effects
				(font
					(size 1 1)
					(thickness 0.15)
				)
			)
		)
		(property "Val" "4u7"
			(at 204.55 -46.65 0)
			(layer "F.Fab")
			(hide yes)
			(effects
				(font
					(size 1 1)
					(thickness 0.15)
				)
			)
		)
		(property "Voltage" ""
			(at 204.55 -46.65 0)
			(layer "F.Fab")
			(hide yes)
			(effects
				(font
					(size 1 1)
					(thickness 0.15)
				)
			)
		)
		(sheetname "LPDDR5")
		(sheetfile "lpddr5.kicad_sch")
		(attr smd)
		(fp_rect
			(start -0.9659 -0.481258)
			(end 0.9649 0.458742)
			(stroke
				(width 0.05)
				(type solid)
			)
			(fill no)
			(layer "F.CrtYd")
		)
		(fp_line
			(start 0.499 -0.25)
			(end 0.499 0.248)
			(stroke
				(width 0.15)
				(type solid)
			)
			(layer "F.Fab")
		)
		(fp_line
			(start -0.499 -0.25)
			(end 0.499 -0.25)
			(stroke
				(width 0.15)
				(type solid)
			)
			(layer "F.Fab")
		)
		(fp_line
			(start 0.499 0.248)
			(end -0.499 0.248)
			(stroke
				(width 0.15)
				(type solid)
			)
			(layer "F.Fab")
		)
		(fp_line
			(start -0.499 0.248)
			(end -0.499 -0.25)
			(stroke
				(width 0.15)
				(type solid)
			)
			(layer "F.Fab")
		)
		(pad "1" smd roundrect
			(at -0.484 0 90)
			(size 0.59 0.64)
			(layers "F.Cu" "F.Mask" "F.Paste")
			(roundrect_rratio 0.25)
			(net 14 "GND")
			(pintype "passive")
		)
		(pad "2" smd roundrect
			(at 0.484 0 90)
			(size 0.59 0.64)
			(layers "F.Cu" "F.Mask" "F.Paste")
			(roundrect_rratio 0.25)
			(net 12 "+0V9")
			(pintype "passive")
		)
	)
	(footprint "antmicro-footprints:R_Array_4x0402_Panasonic_EXB28V"
		(layer "F.Cu")
		(at 127.7 93.8)
		(property "Reference" "R7"
			(at -0.7 -1.4 0)
			(unlocked yes)
			(layer "F.SilkS")
			(effects
				(font
					(size 0.7 0.7)
					(thickness 0.15)
				)
				(justify left bottom)
			)
		)
		(property "Value" "R_4x100R_0402_array"
			(at -1.5 2 0)
			(layer "F.Fab")
			(effects
				(font
					(size 0.7 0.7)
					(thickness 0.15)
				)
				(justify left bottom)
			)
		)
		(property "Author" "Antmicro"
			(at 0 0 0)
			(layer "F.Fab")
			(hide yes)
			(effects
				(font
					(size 1 1)
					(thickness 0.15)
				)
			)
		)
		(property "License" "Apache-2.0"
			(at 0 0 0)
			(layer "F.Fab")
			(hide yes)
			(effects
				(font
					(size 1 1)
					(thickness 0.15)
				)
			)
		)
		(property "MPN" "EXB-28V101JX"
			(at 0 0 0)
			(layer "F.Fab")
			(hide yes)
			(effects
				(font
					(size 1 1)
					(thickness 0.15)
				)
			)
		)
		(property "Manufacturer" "Panasonic"
			(at 0 0 0)
			(layer "F.Fab")
			(hide yes)
			(effects
				(font
					(size 1 1)
					(thickness 0.15)
				)
			)
		)
		(property "Val" "R_4x100R_0402"
			(at 0 0 0)
			(layer "F.Fab")
			(hide yes)
			(effects
				(font
					(size 1 1)
					(thickness 0.15)
				)
			)
		)
		(sheetname "Translators")
		(sheetfile "translators.kicad_sch")
		(attr smd)
		(fp_line
			(start -1.25 -0.5)
			(end -1.25 0.498)
			(stroke
				(width 0.15)
				(type solid)
			)
			(layer "F.SilkS")
		)
		(fp_line
			(start 1.25 0.499)
			(end 1.25 -0.499)
			(stroke
				(width 0.15)
				(type solid)
			)
			(layer "F.SilkS")
		)
		(fp_rect
			(start -1.25 -0.8)
			(end 1.25 0.8)
			(stroke
				(width 0.05)
				(type solid)
			)
			(fill no)
			(layer "F.CrtYd")
		)
		(fp_line
			(start -1 -0.5)
			(end 0.998 -0.5)
			(stroke
				(width 0.15)
				(type solid)
			)
			(layer "F.Fab")
		)
		(fp_line
			(start -1 0.498)
			(end -1 -0.5)
			(stroke
				(width 0.15)
				(type solid)
			)
			(layer "F.Fab")
		)
		(fp_line
			(start 0.998 -0.5)
			(end 0.998 0.498)
			(stroke
				(width 0.15)
				(type solid)
			)
			(layer "F.Fab")
		)
		(fp_line
			(start 0.998 0.498)
			(end -1 0.498)
			(stroke
				(width 0.15)
				(type solid)
			)
			(layer "F.Fab")
		)
		(pad "1" smd roundrect
			(at -0.8875 0.45)
			(size 0.525 0.5)
			(layers "F.Cu" "F.Mask" "F.Paste")
			(roundrect_rratio 0.25)
			(net 165 "/SODIMM/LPDDR5_IN_A.CS0")
			(pinfunction "R1.1")
			(pintype "passive")
		)
		(pad "2" smd roundrect
			(at -0.25 0.45)
			(size 0.25 0.5)
			(layers "F.Cu" "F.Mask" "F.Paste")
			(roundrect_rratio 0.25)
			(net 162 "/SODIMM/LPDDR5_IN_A.CS1")
			(pinfunction "R2.1")
			(pintype "passive")
		)
		(pad "3" smd roundrect
			(at 0.25 0.45)
			(size 0.25 0.5)
			(layers "F.Cu" "F.Mask" "F.Paste")
			(roundrect_rratio 0.25)
			(net 164 "/SODIMM/LPDDR5_IN_A.CA0")
			(pinfunction "R3.1")
			(pintype "passive")
		)
		(pad "4" smd roundrect
			(at 0.8875 0.45)
			(size 0.525 0.5)
			(layers "F.Cu" "F.Mask" "F.Paste")
			(roundrect_rratio 0.25)
			(net 163 "/SODIMM/LPDDR5_IN_A.CA1")
			(pinfunction "R4.1")
			(pintype "passive")
		)
		(pad "5" smd roundrect
			(at 0.8875 -0.45)
			(size 0.525 0.5)
			(layers "F.Cu" "F.Mask" "F.Paste")
			(roundrect_rratio 0.25)
			(net 58 "/LPDDR5/LPDDR5_A.CA1")
			(pinfunction "R4.2")
			(pintype "passive")
		)
		(pad "6" smd roundrect
			(at 0.25 -0.45)
			(size 0.25 0.5)
			(layers "F.Cu" "F.Mask" "F.Paste")
			(roundrect_rratio 0.25)
			(net 57 "/LPDDR5/LPDDR5_A.CA0")
			(pinfunction "R3.2")
			(pintype "passive")
		)
		(pad "7" smd roundrect
			(at -0.25 -0.45)
			(size 0.25 0.5)
			(layers "F.Cu" "F.Mask" "F.Paste")
			(roundrect_rratio 0.25)
			(net 44 "/LPDDR5/LPDDR5_A.CS1")
			(pinfunction "R2.2")
			(pintype "passive")
		)
		(pad "8" smd roundrect
			(at -0.8875 -0.45)
			(size 0.525 0.5)
			(layers "F.Cu" "F.Mask" "F.Paste")
			(roundrect_rratio 0.25)
			(net 43 "/LPDDR5/LPDDR5_A.CS0")
			(pinfunction "R1.2")
			(pintype "passive")
		)
	)
	(footprint "antmicro-footprints:C_0402_1005Metric"
		(layer "F.Cu")
		(at 133.675 88.275)
		(descr "Capacitor SMD 0402")
		(tags "capacitor SMD 0402")
		(property "Reference" "C58"
			(at -3.275 0.25 0)
			(unlocked yes)
			(layer "F.SilkS")
			(effects
				(font
					(size 0.7 0.7)
					(thickness 0.15)
				)
				(justify left bottom)
			)
		)
		(property "Value" "C_4u7_0402"
			(at -1.022927 2.155213 0)
			(layer "F.Fab")
			(effects
				(font
					(size 0.7 0.7)
					(thickness 0.15)
				)
				(justify left bottom)
			)
		)
		(property "Author" "Antmicro"
			(at 0 0 0)
			(layer "F.Fab")
			(hide yes)
			(effects
				(font
					(size 1 1)
					(thickness 0.15)
				)
			)
		)
		(property "Dielectric" ""
			(at 0 0 0)
			(layer "F.Fab")
			(hide yes)
			(effects
				(font
					(size 1 1)
					(thickness 0.15)
				)
			)
		)
		(property "License" "Apache-2.0"
			(at 0 0 0)
			(layer "F.Fab")
			(hide yes)
			(effects
				(font
					(size 1 1)
					(thickness 0.15)
				)
			)
		)
		(property "MPN" "GRM155R61A475MEAAD"
			(at 0 0 0)
			(layer "F.Fab")
			(hide yes)
			(effects
				(font
					(size 1 1)
					(thickness 0.15)
				)
			)
		)
		(property "Manufacturer" "Murata"
			(at 0 0 0)
			(layer "F.Fab")
			(hide yes)
			(effects
				(font
					(size 1 1)
					(thickness 0.15)
				)
			)
		)
		(property "Val" "4u7"
			(at 0 0 0)
			(layer "F.Fab")
			(hide yes)
			(effects
				(font
					(size 1 1)
					(thickness 0.15)
				)
			)
		)
		(property "Voltage" ""
			(at 0 0 0)
			(layer "F.Fab")
			(hide yes)
			(effects
				(font
					(size 1 1)
					(thickness 0.15)
				)
			)
		)
		(sheetname "LPDDR5")
		(sheetfile "lpddr5.kicad_sch")
		(attr smd)
		(fp_rect
			(start -0.9659 -0.481258)
			(end 0.9649 0.458742)
			(stroke
				(width 0.05)
				(type solid)
			)
			(fill no)
			(layer "F.CrtYd")
		)
		(fp_line
			(start -0.499 -0.25)
			(end 0.499 -0.25)
			(stroke
				(width 0.15)
				(type solid)
			)
			(layer "F.Fab")
		)
		(fp_line
			(start -0.499 0.248)
			(end -0.499 -0.25)
			(stroke
				(width 0.15)
				(type solid)
			)
			(layer "F.Fab")
		)
		(fp_line
			(start 0.499 -0.25)
			(end 0.499 0.248)
			(stroke
				(width 0.15)
				(type solid)
			)
			(layer "F.Fab")
		)
		(fp_line
			(start 0.499 0.248)
			(end -0.499 0.248)
			(stroke
				(width 0.15)
				(type solid)
			)
			(layer "F.Fab")
		)
		(pad "1" smd roundrect
			(at -0.484 0)
			(size 0.59 0.64)
			(layers "F.Cu" "F.Mask" "F.Paste")
			(roundrect_rratio 0.25)
			(net 14 "GND")
			(pintype "passive")
		)
		(pad "2" smd roundrect
			(at 0.484 0)
			(size 0.59 0.64)
			(layers "F.Cu" "F.Mask" "F.Paste")
			(roundrect_rratio 0.25)
			(net 13 "+1V05")
			(pintype "passive")
		)
	)
	(footprint "antmicro-footprints:R_0402_1005Metric"
		(layer "F.Cu")
		(at 165.975 65.35 180)
		(descr "Resistor SMD 0402")
		(tags "resistor SMD 0402")
		(property "Reference" "R41"
			(at 4.875 -0.65 0)
			(unlocked yes)
			(layer "F.SilkS")
			(effects
				(font
					(size 0.7 0.7)
					(thickness 0.15)
				)
				(justify right bottom)
			)
		)
		(property "Value" "R_25k5_0402"
			(at -1.011843 1.772047 0)
			(layer "F.Fab")
			(effects
				(font
					(size 0.7 0.7)
					(thickness 0.15)
				)
				(justify right bottom)
			)
		)
		(property "Author" "Antmicro"
			(at 331.95 130.7 0)
			(layer "F.Fab")
			(hide yes)
			(effects
				(font
					(size 1 1)
					(thickness 0.15)
				)
			)
		)
		(property "License" "Apache-2.0"
			(at 331.95 130.7 0)
			(layer "F.Fab")
			(hide yes)
			(effects
				(font
					(size 1 1)
					(thickness 0.15)
				)
			)
		)
		(property "MPN" "CR0402-FX-2552GLF"
			(at 331.95 130.7 0)
			(layer "F.Fab")
			(hide yes)
			(effects
				(font
					(size 1 1)
					(thickness 0.15)
				)
			)
		)
		(property "Manufacturer" "Bourns"
			(at 331.95 130.7 0)
			(layer "F.Fab")
			(hide yes)
			(effects
				(font
					(size 1 1)
					(thickness 0.15)
				)
			)
		)
		(property "Tolerance" "1%"
			(at 331.95 130.7 0)
			(layer "F.Fab")
			(hide yes)
			(effects
				(font
					(size 1 1)
					(thickness 0.15)
				)
			)
		)
		(property "Val" "25k5"
			(at 331.95 130.7 0)
			(layer "F.Fab")
			(hide yes)
			(effects
				(font
					(size 1 1)
					(thickness 0.15)
				)
			)
		)
		(sheetname "Power supply")
		(sheetfile "power_supply.kicad_sch")
		(attr smd)
		(fp_rect
			(start -0.93 -0.47)
			(end 0.93 0.47)
			(stroke
				(width 0.05)
				(type solid)
			)
			(fill no)
			(layer "F.CrtYd")
		)
		(fp_rect
			(start -0.5 -0.25)
			(end 0.5 0.25)
			(stroke
				(width 0.15)
				(type solid)
			)
			(fill no)
			(layer "F.Fab")
		)
		(pad "1" smd roundrect
			(at -0.485 0 180)
			(size 0.59 0.64)
			(layers "F.Cu" "F.Mask" "F.Paste")
			(roundrect_rratio 0.25)
			(net 41 "/Power supply/PWRGD")
			(pintype "passive")
		)
		(pad "2" smd roundrect
			(at 0.485 0 180)
			(size 0.59 0.64)
			(layers "F.Cu" "F.Mask" "F.Paste")
			(roundrect_rratio 0.25)
			(net 1 "+1V1")
			(pintype "passive")
		)
	)
	(footprint "antmicro-footprints:R_0603_1608Metric"
		(layer "F.Cu")
		(at 102.85 61.075)
		(descr "Resistor SMD 0603")
		(tags "resistor SMD 0603")
		(property "Reference" "R43"
			(at -1.25 1.225 90)
			(unlocked yes)
			(layer "F.SilkS")
			(effects
				(font
					(size 0.7 0.7)
					(thickness 0.15)
				)
				(justify left bottom)
			)
		)
		(property "Value" "R_0R_22.4A_0603"
			(at 0 1.6 0)
			(layer "F.Fab")
			(effects
				(font
					(size 0.7 0.7)
					(thickness 0.15)
				)
				(justify left bottom)
			)
		)
		(property "Author" "Antmicro"
			(at 0 0 0)
			(layer "F.Fab")
			(hide yes)
			(effects
				(font
					(size 1 1)
					(thickness 0.15)
				)
			)
		)
		(property "License" "Apache-2.0"
			(at 0 0 0)
			(layer "F.Fab")
			(hide yes)
			(effects
				(font
					(size 1 1)
					(thickness 0.15)
				)
			)
		)
		(property "MPN" "PMR03EZPJ000"
			(at 0 0 0)
			(layer "F.Fab")
			(hide yes)
			(effects
				(font
					(size 1 1)
					(thickness 0.15)
				)
			)
		)
		(property "Manufacturer" "ROHM Semiconductor"
			(at 0 0 0)
			(layer "F.Fab")
			(hide yes)
			(effects
				(font
					(size 1 1)
					(thickness 0.15)
				)
			)
		)
		(property "Max. Curr." "22.4A"
			(at 0 0 0)
			(layer "F.Fab")
			(hide yes)
			(effects
				(font
					(size 1 1)
					(thickness 0.15)
				)
			)
		)
		(property "Tolerance" "template_tolerance"
			(at 0 0 0)
			(layer "F.Fab")
			(hide yes)
			(effects
				(font
					(size 1 1)
					(thickness 0.15)
				)
			)
		)
		(property "Val" "0R"
			(at 0 0 0)
			(layer "F.Fab")
			(hide yes)
			(effects
				(font
					(size 1 1)
					(thickness 0.15)
				)
			)
		)
		(sheetname "Power supply")
		(sheetfile "power_supply.kicad_sch")
		(attr smd)
		(fp_line
			(start -0.3 -0.3)
			(end 0.3 -0.3)
			(stroke
				(width 0.15)
				(type solid)
			)
			(layer "F.SilkS")
		)
		(fp_line
			(start -0.3 0.3)
			(end 0.3 0.3)
			(stroke
				(width 0.15)
				(type solid)
			)
			(layer "F.SilkS")
		)
		(fp_rect
			(start -1.25 -0.7)
			(end 1.25 0.7)
			(stroke
				(width 0.05)
				(type solid)
			)
			(fill no)
			(layer "F.CrtYd")
		)
		(fp_rect
			(start -0.8 -0.4)
			(end 0.8 0.4)
			(stroke
				(width 0.15)
				(type solid)
			)
			(fill no)
			(layer "F.Fab")
		)
		(pad "1" smd roundrect
			(at -0.7 0)
			(size 0.6 0.8)
			(layers "F.Cu" "F.Mask" "F.Paste")
			(roundrect_rratio 0.2)
			(net 35 "+1V8")
			(pintype "passive")
		)
		(pad "2" smd roundrect
			(at 0.7 0)
			(size 0.6 0.8)
			(layers "F.Cu" "F.Mask" "F.Paste")
			(roundrect_rratio 0.2)
			(net 7 "/Power supply/VOUT1")
			(pintype "passive")
		)
	)
	(footprint "antmicro-footprints:R_Array_4x0402_Panasonic_EXB28V"
		(layer "F.Cu")
		(at 119.35 93.8)
		(property "Reference" "R4"
			(at -1.301 -1.45 0)
			(unlocked yes)
			(layer "F.SilkS")
			(effects
				(font
					(size 0.7 0.7)
					(thickness 0.15)
				)
				(justify left bottom)
			)
		)
		(property "Value" "R_4x100R_0402_array"
			(at -1.5 2 0)
			(layer "F.Fab")
			(effects
				(font
					(size 0.7 0.7)
					(thickness 0.15)
				)
				(justify left bottom)
			)
		)
		(property "Author" "Antmicro"
			(at 0 0 0)
			(layer "F.Fab")
			(hide yes)
			(effects
				(font
					(size 1 1)
					(thickness 0.15)
				)
			)
		)
		(property "License" "Apache-2.0"
			(at 0 0 0)
			(layer "F.Fab")
			(hide yes)
			(effects
				(font
					(size 1 1)
					(thickness 0.15)
				)
			)
		)
		(property "MPN" "EXB-28V101JX"
			(at 0 0 0)
			(layer "F.Fab")
			(hide yes)
			(effects
				(font
					(size 1 1)
					(thickness 0.15)
				)
			)
		)
		(property "Manufacturer" "Panasonic"
			(at 0 0 0)
			(layer "F.Fab")
			(hide yes)
			(effects
				(font
					(size 1 1)
					(thickness 0.15)
				)
			)
		)
		(property "Val" "R_4x100R_0402"
			(at 0 0 0)
			(layer "F.Fab")
			(hide yes)
			(effects
				(font
					(size 1 1)
					(thickness 0.15)
				)
			)
		)
		(sheetname "Translators")
		(sheetfile "translators.kicad_sch")
		(attr smd)
		(fp_line
			(start -1.25 -0.5)
			(end -1.25 0.498)
			(stroke
				(width 0.15)
				(type solid)
			)
			(layer "F.SilkS")
		)
		(fp_line
			(start 1.25 0.499)
			(end 1.25 -0.499)
			(stroke
				(width 0.15)
				(type solid)
			)
			(layer "F.SilkS")
		)
		(fp_rect
			(start -1.25 -0.8)
			(end 1.25 0.8)
			(stroke
				(width 0.05)
				(type solid)
			)
			(fill no)
			(layer "F.CrtYd")
		)
		(fp_line
			(start -1 -0.5)
			(end 0.998 -0.5)
			(stroke
				(width 0.15)
				(type solid)
			)
			(layer "F.Fab")
		)
		(fp_line
			(start -1 0.498)
			(end -1 -0.5)
			(stroke
				(width 0.15)
				(type solid)
			)
			(layer "F.Fab")
		)
		(fp_line
			(start 0.998 -0.5)
			(end 0.998 0.498)
			(stroke
				(width 0.15)
				(type solid)
			)
			(layer "F.Fab")
		)
		(fp_line
			(start 0.998 0.498)
			(end -1 0.498)
			(stroke
				(width 0.15)
				(type solid)
			)
			(layer "F.Fab")
		)
		(pad "1" smd roundrect
			(at -0.8875 0.45)
			(size 0.525 0.5)
			(layers "F.Cu" "F.Mask" "F.Paste")
			(roundrect_rratio 0.25)
			(net 169 "/SODIMM/LPDDR5_IN_A.DQ3")
			(pinfunction "R1.1")
			(pintype "passive")
		)
		(pad "2" smd roundrect
			(at -0.25 0.45)
			(size 0.25 0.5)
			(layers "F.Cu" "F.Mask" "F.Paste")
			(roundrect_rratio 0.25)
			(net 168 "/SODIMM/LPDDR5_IN_A.DQ1")
			(pinfunction "R2.1")
			(pintype "passive")
		)
		(pad "3" smd roundrect
			(at 0.25 0.45)
			(size 0.25 0.5)
			(layers "F.Cu" "F.Mask" "F.Paste")
			(roundrect_rratio 0.25)
			(net 167 "/SODIMM/LPDDR5_IN_A.DQ2")
			(pinfunction "R3.1")
			(pintype "passive")
		)
		(pad "4" smd roundrect
			(at 0.8875 0.45)
			(size 0.525 0.5)
			(layers "F.Cu" "F.Mask" "F.Paste")
			(roundrect_rratio 0.25)
			(net 166 "/SODIMM/LPDDR5_IN_A.DQ0")
			(pinfunction "R4.1")
			(pintype "passive")
		)
		(pad "5" smd roundrect
			(at 0.8875 -0.45)
			(size 0.525 0.5)
			(layers "F.Cu" "F.Mask" "F.Paste")
			(roundrect_rratio 0.25)
			(net 205 "/LPDDR5/LPDDR5_A.DQ0")
			(pinfunction "R4.2")
			(pintype "passive")
		)
		(pad "6" smd roundrect
			(at 0.25 -0.45)
			(size 0.25 0.5)
			(layers "F.Cu" "F.Mask" "F.Paste")
			(roundrect_rratio 0.25)
			(net 203 "/LPDDR5/LPDDR5_A.DQ2")
			(pinfunction "R3.2")
			(pintype "passive")
		)
		(pad "7" smd roundrect
			(at -0.25 -0.45)
			(size 0.25 0.5)
			(layers "F.Cu" "F.Mask" "F.Paste")
			(roundrect_rratio 0.25)
			(net 204 "/LPDDR5/LPDDR5_A.DQ1")
			(pinfunction "R2.2")
			(pintype "passive")
		)
		(pad "8" smd roundrect
			(at -0.8875 -0.45)
			(size 0.525 0.5)
			(layers "F.Cu" "F.Mask" "F.Paste")
			(roundrect_rratio 0.25)
			(net 202 "/LPDDR5/LPDDR5_A.DQ3")
			(pinfunction "R1.2")
			(pintype "passive")
		)
	)
	(footprint "antmicro-footprints:R_0402_1005Metric"
		(layer "F.Cu")
		(at 110 73.75)
		(descr "Resistor SMD 0402")
		(tags "resistor SMD 0402")
		(property "Reference" "R38"
			(at 0.9 0.45 0)
			(unlocked yes)
			(layer "F.SilkS")
			(effects
				(font
					(size 0.7 0.7)
					(thickness 0.15)
				)
				(justify left bottom)
			)
		)
		(property "Value" "R_130k_0402"
			(at -1.011843 1.772047 0)
			(layer "F.Fab")
			(effects
				(font
					(size 0.7 0.7)
					(thickness 0.15)
				)
				(justify left bottom)
			)
		)
		(property "Author" "Antmicro"
			(at 0 0 0)
			(layer "F.Fab")
			(hide yes)
			(effects
				(font
					(size 1 1)
					(thickness 0.15)
				)
			)
		)
		(property "License" "Apache-2.0"
			(at 0 0 0)
			(layer "F.Fab")
			(hide yes)
			(effects
				(font
					(size 1 1)
					(thickness 0.15)
				)
			)
		)
		(property "MPN" "CR0402-FX-1303GLF"
			(at 0 0 0)
			(layer "F.Fab")
			(hide yes)
			(effects
				(font
					(size 1 1)
					(thickness 0.15)
				)
			)
		)
		(property "Manufacturer" "Bourns"
			(at 0 0 0)
			(layer "F.Fab")
			(hide yes)
			(effects
				(font
					(size 1 1)
					(thickness 0.15)
				)
			)
		)
		(property "Tolerance" "1%"
			(at 0 0 0)
			(layer "F.Fab")
			(hide yes)
			(effects
				(font
					(size 1 1)
					(thickness 0.15)
				)
			)
		)
		(property "Val" "130k"
			(at 0 0 0)
			(layer "F.Fab")
			(hide yes)
			(effects
				(font
					(size 1 1)
					(thickness 0.15)
				)
			)
		)
		(sheetname "Power supply")
		(sheetfile "power_supply.kicad_sch")
		(attr smd)
		(fp_rect
			(start -0.93 -0.47)
			(end 0.93 0.47)
			(stroke
				(width 0.05)
				(type solid)
			)
			(fill no)
			(layer "F.CrtYd")
		)
		(fp_rect
			(start -0.5 -0.25)
			(end 0.5 0.25)
			(stroke
				(width 0.15)
				(type solid)
			)
			(fill no)
			(layer "F.Fab")
		)
		(pad "1" smd roundrect
			(at -0.485 0)
			(size 0.59 0.64)
			(layers "F.Cu" "F.Mask" "F.Paste")
			(roundrect_rratio 0.25)
			(net 72 "/Power supply/FB3")
			(pintype "passive")
		)
		(pad "2" smd roundrect
			(at 0.485 0)
			(size 0.59 0.64)
			(layers "F.Cu" "F.Mask" "F.Paste")
			(roundrect_rratio 0.25)
			(net 14 "GND")
			(pintype "passive")
		)
	)
	(footprint "antmicro-footprints:C_0402_1005Metric"
		(layer "F.Cu")
		(at 133.675 72.275)
		(descr "Capacitor SMD 0402")
		(tags "capacitor SMD 0402")
		(property "Reference" "C62"
			(at -1.075 -0.75 0)
			(unlocked yes)
			(layer "F.SilkS")
			(effects
				(font
					(size 0.7 0.7)
					(thickness 0.15)
				)
				(justify left bottom)
			)
		)
		(property "Value" "C_4u7_0402"
			(at -1.022927 2.155213 0)
			(layer "F.Fab")
			(effects
				(font
					(size 0.7 0.7)
					(thickness 0.15)
				)
				(justify left bottom)
			)
		)
		(property "Author" "Antmicro"
			(at 0 0 0)
			(layer "F.Fab")
			(hide yes)
			(effects
				(font
					(size 1 1)
					(thickness 0.15)
				)
			)
		)
		(property "Dielectric" ""
			(at 0 0 0)
			(layer "F.Fab")
			(hide yes)
			(effects
				(font
					(size 1 1)
					(thickness 0.15)
				)
			)
		)
		(property "License" "Apache-2.0"
			(at 0 0 0)
			(layer "F.Fab")
			(hide yes)
			(effects
				(font
					(size 1 1)
					(thickness 0.15)
				)
			)
		)
		(property "MPN" "GRM155R61A475MEAAD"
			(at 0 0 0)
			(layer "F.Fab")
			(hide yes)
			(effects
				(font
					(size 1 1)
					(thickness 0.15)
				)
			)
		)
		(property "Manufacturer" "Murata"
			(at 0 0 0)
			(layer "F.Fab")
			(hide yes)
			(effects
				(font
					(size 1 1)
					(thickness 0.15)
				)
			)
		)
		(property "Val" "4u7"
			(at 0 0 0)
			(layer "F.Fab")
			(hide yes)
			(effects
				(font
					(size 1 1)
					(thickness 0.15)
				)
			)
		)
		(property "Voltage" ""
			(at 0 0 0)
			(layer "F.Fab")
			(hide yes)
			(effects
				(font
					(size 1 1)
					(thickness 0.15)
				)
			)
		)
		(sheetname "LPDDR5")
		(sheetfile "lpddr5.kicad_sch")
		(attr smd)
		(fp_rect
			(start -0.9659 -0.481258)
			(end 0.9649 0.458742)
			(stroke
				(width 0.05)
				(type solid)
			)
			(fill no)
			(layer "F.CrtYd")
		)
		(fp_line
			(start -0.499 -0.25)
			(end 0.499 -0.25)
			(stroke
				(width 0.15)
				(type solid)
			)
			(layer "F.Fab")
		)
		(fp_line
			(start -0.499 0.248)
			(end -0.499 -0.25)
			(stroke
				(width 0.15)
				(type solid)
			)
			(layer "F.Fab")
		)
		(fp_line
			(start 0.499 -0.25)
			(end 0.499 0.248)
			(stroke
				(width 0.15)
				(type solid)
			)
			(layer "F.Fab")
		)
		(fp_line
			(start 0.499 0.248)
			(end -0.499 0.248)
			(stroke
				(width 0.15)
				(type solid)
			)
			(layer "F.Fab")
		)
		(pad "1" smd roundrect
			(at -0.484 0)
			(size 0.59 0.64)
			(layers "F.Cu" "F.Mask" "F.Paste")
			(roundrect_rratio 0.25)
			(net 14 "GND")
			(pintype "passive")
		)
		(pad "2" smd roundrect
			(at 0.484 0)
			(size 0.59 0.64)
			(layers "F.Cu" "F.Mask" "F.Paste")
			(roundrect_rratio 0.25)
			(net 13 "+1V05")
			(pintype "passive")
		)
	)
	(footprint "antmicro-footprints:C_0402_1005Metric"
		(layer "F.Cu")
		(at 144.25 79 90)
		(descr "Capacitor SMD 0402")
		(tags "capacitor SMD 0402")
		(property "Reference" "C60"
			(at 1 0.325 90)
			(unlocked yes)
			(layer "F.SilkS")
			(effects
				(font
					(size 0.7 0.7)
					(thickness 0.15)
				)
				(justify left bottom)
			)
		)
		(property "Value" "C_4u7_0402"
			(at -1.022927 2.155213 90)
			(layer "F.Fab")
			(effects
				(font
					(size 0.7 0.7)
					(thickness 0.15)
				)
				(justify left bottom)
			)
		)
		(property "Author" "Antmicro"
			(at 223.25 -65.25 0)
			(layer "F.Fab")
			(hide yes)
			(effects
				(font
					(size 1 1)
					(thickness 0.15)
				)
			)
		)
		(property "Dielectric" ""
			(at 223.25 -65.25 0)
			(layer "F.Fab")
			(hide yes)
			(effects
				(font
					(size 1 1)
					(thickness 0.15)
				)
			)
		)
		(property "License" "Apache-2.0"
			(at 223.25 -65.25 0)
			(layer "F.Fab")
			(hide yes)
			(effects
				(font
					(size 1 1)
					(thickness 0.15)
				)
			)
		)
		(property "MPN" "GRM155R61A475MEAAD"
			(at 223.25 -65.25 0)
			(layer "F.Fab")
			(hide yes)
			(effects
				(font
					(size 1 1)
					(thickness 0.15)
				)
			)
		)
		(property "Manufacturer" "Murata"
			(at 223.25 -65.25 0)
			(layer "F.Fab")
			(hide yes)
			(effects
				(font
					(size 1 1)
					(thickness 0.15)
				)
			)
		)
		(property "Val" "4u7"
			(at 223.25 -65.25 0)
			(layer "F.Fab")
			(hide yes)
			(effects
				(font
					(size 1 1)
					(thickness 0.15)
				)
			)
		)
		(property "Voltage" ""
			(at 223.25 -65.25 0)
			(layer "F.Fab")
			(hide yes)
			(effects
				(font
					(size 1 1)
					(thickness 0.15)
				)
			)
		)
		(sheetname "LPDDR5")
		(sheetfile "lpddr5.kicad_sch")
		(attr smd)
		(fp_rect
			(start -0.9659 -0.481258)
			(end 0.9649 0.458742)
			(stroke
				(width 0.05)
				(type solid)
			)
			(fill no)
			(layer "F.CrtYd")
		)
		(fp_line
			(start 0.499 -0.25)
			(end 0.499 0.248)
			(stroke
				(width 0.15)
				(type solid)
			)
			(layer "F.Fab")
		)
		(fp_line
			(start -0.499 -0.25)
			(end 0.499 -0.25)
			(stroke
				(width 0.15)
				(type solid)
			)
			(layer "F.Fab")
		)
		(fp_line
			(start 0.499 0.248)
			(end -0.499 0.248)
			(stroke
				(width 0.15)
				(type solid)
			)
			(layer "F.Fab")
		)
		(fp_line
			(start -0.499 0.248)
			(end -0.499 -0.25)
			(stroke
				(width 0.15)
				(type solid)
			)
			(layer "F.Fab")
		)
		(pad "1" smd roundrect
			(at -0.484 0 90)
			(size 0.59 0.64)
			(layers "F.Cu" "F.Mask" "F.Paste")
			(roundrect_rratio 0.25)
			(net 14 "GND")
			(pintype "passive")
		)
		(pad "2" smd roundrect
			(at 0.484 0 90)
			(size 0.59 0.64)
			(layers "F.Cu" "F.Mask" "F.Paste")
			(roundrect_rratio 0.25)
			(net 12 "+0V9")
			(pintype "passive")
		)
	)
	(footprint "antmicro-footprints:R_0402_1005Metric"
		(layer "F.Cu")
		(at 136.15 91.35 90)
		(descr "Resistor SMD 0402")
		(tags "resistor SMD 0402")
		(property "Reference" "R15"
			(at -1.05 1.45 90)
			(unlocked yes)
			(layer "F.SilkS")
			(effects
				(font
					(size 0.7 0.7)
					(thickness 0.15)
				)
				(justify left bottom)
			)
		)
		(property "Value" "R_100R_0402"
			(at -1.011843 1.772047 90)
			(layer "F.Fab")
			(effects
				(font
					(size 0.7 0.7)
					(thickness 0.15)
				)
				(justify left bottom)
			)
		)
		(property "Author" "Antmicro"
			(at 227.5 -44.8 0)
			(layer "F.Fab")
			(hide yes)
			(effects
				(font
					(size 1 1)
					(thickness 0.15)
				)
			)
		)
		(property "License" "Apache-2.0"
			(at 227.5 -44.8 0)
			(layer "F.Fab")
			(hide yes)
			(effects
				(font
					(size 1 1)
					(thickness 0.15)
				)
			)
		)
		(property "MPN" "CR0402-FX-1000GLF"
			(at 227.5 -44.8 0)
			(layer "F.Fab")
			(hide yes)
			(effects
				(font
					(size 1 1)
					(thickness 0.15)
				)
			)
		)
		(property "Manufacturer" "Bourns"
			(at 227.5 -44.8 0)
			(layer "F.Fab")
			(hide yes)
			(effects
				(font
					(size 1 1)
					(thickness 0.15)
				)
			)
		)
		(property "Tolerance" "1%"
			(at 227.5 -44.8 0)
			(layer "F.Fab")
			(hide yes)
			(effects
				(font
					(size 1 1)
					(thickness 0.15)
				)
			)
		)
		(property "Val" "100R"
			(at 227.5 -44.8 0)
			(layer "F.Fab")
			(hide yes)
			(effects
				(font
					(size 1 1)
					(thickness 0.15)
				)
			)
		)
		(sheetname "Translators")
		(sheetfile "translators.kicad_sch")
		(attr smd)
		(fp_rect
			(start -0.93 -0.47)
			(end 0.93 0.47)
			(stroke
				(width 0.05)
				(type solid)
			)
			(fill no)
			(layer "F.CrtYd")
		)
		(fp_rect
			(start -0.5 -0.25)
			(end 0.5 0.25)
			(stroke
				(width 0.15)
				(type solid)
			)
			(fill no)
			(layer "F.Fab")
		)
		(pad "1" smd roundrect
			(at -0.485 0 90)
			(size 0.59 0.64)
			(layers "F.Cu" "F.Mask" "F.Paste")
			(roundrect_rratio 0.25)
			(net 155 "/SODIMM/LPDDR5_IN_A.CK_N")
			(pintype "passive")
		)
		(pad "2" smd roundrect
			(at 0.485 0 90)
			(size 0.59 0.64)
			(layers "F.Cu" "F.Mask" "F.Paste")
			(roundrect_rratio 0.25)
			(net 50 "/LPDDR5/LPDDR5_A.CK_N")
			(pintype "passive")
		)
	)
	(footprint "antmicro-footprints:TP_SMD_1mm"
		(layer "F.Cu")
		(at 119.25 65.4 90)
		(property "Reference" "TP2"
			(at 0.6 0.35 90)
			(unlocked yes)
			(layer "F.SilkS")
			(effects
				(font
					(size 0.7 0.7)
					(thickness 0.15)
				)
				(justify left bottom)
			)
		)
		(property "Value" "TP_1mm_SMD"
			(at 0 1.4 90)
			(layer "F.Fab")
			(effects
				(font
					(size 0.7 0.7)
					(thickness 0.15)
				)
				(justify left bottom)
			)
		)
		(property "Author" "Antmicro"
			(at 184.65 -53.85 0)
			(layer "F.Fab")
			(hide yes)
			(effects
				(font
					(size 1 1)
					(thickness 0.15)
				)
			)
		)
		(property "License" "Apache-2.0"
			(at 184.65 -53.85 0)
			(layer "F.Fab")
			(hide yes)
			(effects
				(font
					(size 1 1)
					(thickness 0.15)
				)
			)
		)
		(property "MPN" ""
			(at 184.65 -53.85 0)
			(layer "F.Fab")
			(hide yes)
			(effects
				(font
					(size 1 1)
					(thickness 0.15)
				)
			)
		)
		(property "Manufacturer" ""
			(at 184.65 -53.85 0)
			(layer "F.Fab")
			(hide yes)
			(effects
				(font
					(size 1 1)
					(thickness 0.15)
				)
			)
		)
		(sheetname "Power supply")
		(sheetfile "power_supply.kicad_sch")
		(attr exclude_from_pos_files)
		(pad "1" smd circle
			(at 0 0 90)
			(size 1 1)
			(layers "F.Cu" "F.Mask")
			(net 38 "/Power supply/I2C.SDA")
			(pinfunction "1")
			(pintype "passive")
		)
	)
	(footprint "antmicro-footprints:R_0402_1005Metric"
		(layer "F.Cu")
		(at 110.0025 72.755)
		(descr "Resistor SMD 0402")
		(tags "resistor SMD 0402")
		(property "Reference" "R37"
			(at 0.8975 0.445 0)
			(unlocked yes)
			(layer "F.SilkS")
			(effects
				(font
					(size 0.7 0.7)
					(thickness 0.15)
				)
				(justify left bottom)
			)
		)
		(property "Value" "R_100k_0402"
			(at -1.011843 1.772047 0)
			(layer "F.Fab")
			(effects
				(font
					(size 0.7 0.7)
					(thickness 0.15)
				)
				(justify left bottom)
			)
		)
		(property "Author" "Antmicro"
			(at 0 0 0)
			(layer "F.Fab")
			(hide yes)
			(effects
				(font
					(size 1 1)
					(thickness 0.15)
				)
			)
		)
		(property "License" "Apache-2.0"
			(at 0 0 0)
			(layer "F.Fab")
			(hide yes)
			(effects
				(font
					(size 1 1)
					(thickness 0.15)
				)
			)
		)
		(property "MPN" "CR0402-FX-1003GLF"
			(at 0 0 0)
			(layer "F.Fab")
			(hide yes)
			(effects
				(font
					(size 1 1)
					(thickness 0.15)
				)
			)
		)
		(property "Manufacturer" "Bourns"
			(at 0 0 0)
			(layer "F.Fab")
			(hide yes)
			(effects
				(font
					(size 1 1)
					(thickness 0.15)
				)
			)
		)
		(property "Tolerance" "1%"
			(at 0 0 0)
			(layer "F.Fab")
			(hide yes)
			(effects
				(font
					(size 1 1)
					(thickness 0.15)
				)
			)
		)
		(property "Val" "100k"
			(at 0 0 0)
			(layer "F.Fab")
			(hide yes)
			(effects
				(font
					(size 1 1)
					(thickness 0.15)
				)
			)
		)
		(sheetname "Power supply")
		(sheetfile "power_supply.kicad_sch")
		(attr smd)
		(fp_rect
			(start -0.93 -0.47)
			(end 0.93 0.47)
			(stroke
				(width 0.05)
				(type solid)
			)
			(fill no)
			(layer "F.CrtYd")
		)
		(fp_rect
			(start -0.5 -0.25)
			(end 0.5 0.25)
			(stroke
				(width 0.15)
				(type solid)
			)
			(fill no)
			(layer "F.Fab")
		)
		(pad "1" smd roundrect
			(at -0.485 0)
			(size 0.59 0.64)
			(layers "F.Cu" "F.Mask" "F.Paste")
			(roundrect_rratio 0.25)
			(net 72 "/Power supply/FB3")
			(pintype "passive")
		)
		(pad "2" smd roundrect
			(at 0.485 0)
			(size 0.59 0.64)
			(layers "F.Cu" "F.Mask" "F.Paste")
			(roundrect_rratio 0.25)
			(net 9 "/Power supply/VOUT3")
			(pintype "passive")
		)
	)
	(footprint "antmicro-footprints:R_Array_4x0402_Panasonic_EXB28V"
		(layer "F.Cu")
		(at 162.7125 93.8)
		(property "Reference" "R58"
			(at -1.301 -1.45 0)
			(unlocked yes)
			(layer "F.SilkS")
			(effects
				(font
					(size 0.7 0.7)
					(thickness 0.15)
				)
				(justify left bottom)
			)
		)
		(property "Value" "R_4x100R_0402_array"
			(at -1.5 2 0)
			(layer "F.Fab")
			(effects
				(font
					(size 0.7 0.7)
					(thickness 0.15)
				)
				(justify left bottom)
			)
		)
		(property "Author" "Antmicro"
			(at 0 0 0)
			(layer "F.Fab")
			(hide yes)
			(effects
				(font
					(size 1 1)
					(thickness 0.15)
				)
			)
		)
		(property "License" "Apache-2.0"
			(at 0 0 0)
			(layer "F.Fab")
			(hide yes)
			(effects
				(font
					(size 1 1)
					(thickness 0.15)
				)
			)
		)
		(property "MPN" "EXB-28V101JX"
			(at 0 0 0)
			(layer "F.Fab")
			(hide yes)
			(effects
				(font
					(size 1 1)
					(thickness 0.15)
				)
			)
		)
		(property "Manufacturer" "Panasonic"
			(at 0 0 0)
			(layer "F.Fab")
			(hide yes)
			(effects
				(font
					(size 1 1)
					(thickness 0.15)
				)
			)
		)
		(property "Val" "R_4x100R_0402"
			(at 0 0 0)
			(layer "F.Fab")
			(hide yes)
			(effects
				(font
					(size 1 1)
					(thickness 0.15)
				)
			)
		)
		(sheetname "Translators1")
		(sheetfile "translators.kicad_sch")
		(attr smd)
		(fp_line
			(start -1.25 -0.5)
			(end -1.25 0.498)
			(stroke
				(width 0.15)
				(type solid)
			)
			(layer "F.SilkS")
		)
		(fp_line
			(start 1.25 0.499)
			(end 1.25 -0.499)
			(stroke
				(width 0.15)
				(type solid)
			)
			(layer "F.SilkS")
		)
		(fp_rect
			(start -1.25 -0.8)
			(end 1.25 0.8)
			(stroke
				(width 0.05)
				(type solid)
			)
			(fill no)
			(layer "F.CrtYd")
		)
		(fp_line
			(start -1 -0.5)
			(end 0.998 -0.5)
			(stroke
				(width 0.15)
				(type solid)
			)
			(layer "F.Fab")
		)
		(fp_line
			(start -1 0.498)
			(end -1 -0.5)
			(stroke
				(width 0.15)
				(type solid)
			)
			(layer "F.Fab")
		)
		(fp_line
			(start 0.998 -0.5)
			(end 0.998 0.498)
			(stroke
				(width 0.15)
				(type solid)
			)
			(layer "F.Fab")
		)
		(fp_line
			(start 0.998 0.498)
			(end -1 0.498)
			(stroke
				(width 0.15)
				(type solid)
			)
			(layer "F.Fab")
		)
		(pad "1" smd roundrect
			(at -0.8875 0.45)
			(size 0.525 0.5)
			(layers "F.Cu" "F.Mask" "F.Paste")
			(roundrect_rratio 0.25)
			(net 130 "/SODIMM/LPDDR5_IN_B.DQ5")
			(pinfunction "R1.1")
			(pintype "passive")
		)
		(pad "2" smd roundrect
			(at -0.25 0.45)
			(size 0.25 0.5)
			(layers "F.Cu" "F.Mask" "F.Paste")
			(roundrect_rratio 0.25)
			(net 129 "/SODIMM/LPDDR5_IN_B.DQ4")
			(pinfunction "R2.1")
			(pintype "passive")
		)
		(pad "3" smd roundrect
			(at 0.25 0.45)
			(size 0.25 0.5)
			(layers "F.Cu" "F.Mask" "F.Paste")
			(roundrect_rratio 0.25)
			(net 131 "/SODIMM/LPDDR5_IN_B.DQ6")
			(pinfunction "R3.1")
			(pintype "passive")
		)
		(pad "4" smd roundrect
			(at 0.8875 0.45)
			(size 0.525 0.5)
			(layers "F.Cu" "F.Mask" "F.Paste")
			(roundrect_rratio 0.25)
			(net 132 "/SODIMM/LPDDR5_IN_B.DQ7")
			(pinfunction "R4.1")
			(pintype "passive")
		)
		(pad "5" smd roundrect
			(at 0.8875 -0.45)
			(size 0.525 0.5)
			(layers "F.Cu" "F.Mask" "F.Paste")
			(roundrect_rratio 0.25)
			(net 217 "/LPDDR5/LPDDR5_B.DQ7")
			(pinfunction "R4.2")
			(pintype "passive")
		)
		(pad "6" smd roundrect
			(at 0.25 -0.45)
			(size 0.25 0.5)
			(layers "F.Cu" "F.Mask" "F.Paste")
			(roundrect_rratio 0.25)
			(net 218 "/LPDDR5/LPDDR5_B.DQ6")
			(pinfunction "R3.2")
			(pintype "passive")
		)
		(pad "7" smd roundrect
			(at -0.25 -0.45)
			(size 0.25 0.5)
			(layers "F.Cu" "F.Mask" "F.Paste")
			(roundrect_rratio 0.25)
			(net 220 "/LPDDR5/LPDDR5_B.DQ4")
			(pinfunction "R2.2")
			(pintype "passive")
		)
		(pad "8" smd roundrect
			(at -0.8875 -0.45)
			(size 0.525 0.5)
			(layers "F.Cu" "F.Mask" "F.Paste")
			(roundrect_rratio 0.25)
			(net 219 "/LPDDR5/LPDDR5_B.DQ5")
			(pinfunction "R1.2")
			(pintype "passive")
		)
	)
	(footprint "antmicro-footprints:R_Array_4x0402_Panasonic_EXB28V"
		(layer "F.Cu")
		(at 152.2 93.8)
		(property "Reference" "R62"
			(at -1.301 -1.45 0)
			(unlocked yes)
			(layer "F.SilkS")
			(effects
				(font
					(size 0.7 0.7)
					(thickness 0.15)
				)
				(justify left bottom)
			)
		)
		(property "Value" "R_4x100R_0402_array"
			(at -1.5 2 0)
			(layer "F.Fab")
			(effects
				(font
					(size 0.7 0.7)
					(thickness 0.15)
				)
				(justify left bottom)
			)
		)
		(property "Author" "Antmicro"
			(at 0 0 0)
			(layer "F.Fab")
			(hide yes)
			(effects
				(font
					(size 1 1)
					(thickness 0.15)
				)
			)
		)
		(property "License" "Apache-2.0"
			(at 0 0 0)
			(layer "F.Fab")
			(hide yes)
			(effects
				(font
					(size 1 1)
					(thickness 0.15)
				)
			)
		)
		(property "MPN" "EXB-28V101JX"
			(at 0 0 0)
			(layer "F.Fab")
			(hide yes)
			(effects
				(font
					(size 1 1)
					(thickness 0.15)
				)
			)
		)
		(property "Manufacturer" "Panasonic"
			(at 0 0 0)
			(layer "F.Fab")
			(hide yes)
			(effects
				(font
					(size 1 1)
					(thickness 0.15)
				)
			)
		)
		(property "Val" "R_4x100R_0402"
			(at 0 0 0)
			(layer "F.Fab")
			(hide yes)
			(effects
				(font
					(size 1 1)
					(thickness 0.15)
				)
			)
		)
		(sheetname "Translators1")
		(sheetfile "translators.kicad_sch")
		(attr smd)
		(fp_line
			(start -1.25 -0.5)
			(end -1.25 0.498)
			(stroke
				(width 0.15)
				(type solid)
			)
			(layer "F.SilkS")
		)
		(fp_line
			(start 1.25 0.499)
			(end 1.25 -0.499)
			(stroke
				(width 0.15)
				(type solid)
			)
			(layer "F.SilkS")
		)
		(fp_rect
			(start -1.25 -0.8)
			(end 1.25 0.8)
			(stroke
				(width 0.05)
				(type solid)
			)
			(fill no)
			(layer "F.CrtYd")
		)
		(fp_line
			(start -1 -0.5)
			(end 0.998 -0.5)
			(stroke
				(width 0.15)
				(type solid)
			)
			(layer "F.Fab")
		)
		(fp_line
			(start -1 0.498)
			(end -1 -0.5)
			(stroke
				(width 0.15)
				(type solid)
			)
			(layer "F.Fab")
		)
		(fp_line
			(start 0.998 -0.5)
			(end 0.998 0.498)
			(stroke
				(width 0.15)
				(type solid)
			)
			(layer "F.Fab")
		)
		(fp_line
			(start 0.998 0.498)
			(end -1 0.498)
			(stroke
				(width 0.15)
				(type solid)
			)
			(layer "F.Fab")
		)
		(pad "1" smd roundrect
			(at -0.8875 0.45)
			(size 0.525 0.5)
			(layers "F.Cu" "F.Mask" "F.Paste")
			(roundrect_rratio 0.25)
			(net 143 "/SODIMM/LPDDR5_IN_B.DQ8")
			(pinfunction "R1.1")
			(pintype "passive")
		)
		(pad "2" smd roundrect
			(at -0.25 0.45)
			(size 0.25 0.5)
			(layers "F.Cu" "F.Mask" "F.Paste")
			(roundrect_rratio 0.25)
			(net 141 "/SODIMM/LPDDR5_IN_B.DQ10")
			(pinfunction "R2.1")
			(pintype "passive")
		)
		(pad "3" smd roundrect
			(at 0.25 0.45)
			(size 0.25 0.5)
			(layers "F.Cu" "F.Mask" "F.Paste")
			(roundrect_rratio 0.25)
			(net 142 "/SODIMM/LPDDR5_IN_B.DQ9")
			(pinfunction "R3.1")
			(pintype "passive")
		)
		(pad "4" smd roundrect
			(at 0.8875 0.45)
			(size 0.525 0.5)
			(layers "F.Cu" "F.Mask" "F.Paste")
			(roundrect_rratio 0.25)
			(net 140 "/SODIMM/LPDDR5_IN_B.DQ11")
			(pinfunction "R4.1")
			(pintype "passive")
		)
		(pad "5" smd roundrect
			(at 0.8875 -0.45)
			(size 0.525 0.5)
			(layers "F.Cu" "F.Mask" "F.Paste")
			(roundrect_rratio 0.25)
			(net 209 "/LPDDR5/LPDDR5_B.DQ11")
			(pinfunction "R4.2")
			(pintype "passive")
		)
		(pad "6" smd roundrect
			(at 0.25 -0.45)
			(size 0.25 0.5)
			(layers "F.Cu" "F.Mask" "F.Paste")
			(roundrect_rratio 0.25)
			(net 207 "/LPDDR5/LPDDR5_B.DQ9")
			(pinfunction "R3.2")
			(pintype "passive")
		)
		(pad "7" smd roundrect
			(at -0.25 -0.45)
			(size 0.25 0.5)
			(layers "F.Cu" "F.Mask" "F.Paste")
			(roundrect_rratio 0.25)
			(net 208 "/LPDDR5/LPDDR5_B.DQ10")
			(pinfunction "R2.2")
			(pintype "passive")
		)
		(pad "8" smd roundrect
			(at -0.8875 -0.45)
			(size 0.525 0.5)
			(layers "F.Cu" "F.Mask" "F.Paste")
			(roundrect_rratio 0.25)
			(net 206 "/LPDDR5/LPDDR5_B.DQ8")
			(pinfunction "R1.2")
			(pintype "passive")
		)
	)
	(footprint "antmicro-footprints:TP_SMD_1mm"
		(layer "F.Cu")
		(at 120.75 65.4 90)
		(property "Reference" "TP3"
			(at 0.6 0.35 90)
			(unlocked yes)
			(layer "F.SilkS")
			(effects
				(font
					(size 0.7 0.7)
					(thickness 0.15)
				)
				(justify left bottom)
			)
		)
		(property "Value" "TP_1mm_SMD"
			(at 0 1.4 90)
			(layer "F.Fab")
			(effects
				(font
					(size 0.7 0.7)
					(thickness 0.15)
				)
				(justify left bottom)
			)
		)
		(property "Author" "Antmicro"
			(at 186.15 -55.35 0)
			(layer "F.Fab")
			(hide yes)
			(effects
				(font
					(size 1 1)
					(thickness 0.15)
				)
			)
		)
		(property "License" "Apache-2.0"
			(at 186.15 -55.35 0)
			(layer "F.Fab")
			(hide yes)
			(effects
				(font
					(size 1 1)
					(thickness 0.15)
				)
			)
		)
		(property "MPN" ""
			(at 186.15 -55.35 0)
			(layer "F.Fab")
			(hide yes)
			(effects
				(font
					(size 1 1)
					(thickness 0.15)
				)
			)
		)
		(property "Manufacturer" ""
			(at 186.15 -55.35 0)
			(layer "F.Fab")
			(hide yes)
			(effects
				(font
					(size 1 1)
					(thickness 0.15)
				)
			)
		)
		(sheetname "Power supply")
		(sheetfile "power_supply.kicad_sch")
		(attr exclude_from_pos_files)
		(pad "1" smd circle
			(at 0 0 90)
			(size 1 1)
			(layers "F.Cu" "F.Mask")
			(net 39 "/Power supply/I2C.SCL")
			(pinfunction "1")
			(pintype "passive")
		)
	)
	(footprint "antmicro-footprints:C_0603_1608Metric"
		(layer "F.Cu")
		(at 108.025 61.075)
		(descr "Capacitor SMD 0603")
		(tags "capacitor 0603")
		(property "Reference" "C15"
			(at 1.025 1.35 0)
			(unlocked yes)
			(layer "F.SilkS")
			(effects
				(font
					(size 0.7 0.7)
					(thickness 0.15)
				)
				(justify left bottom)
			)
		)
		(property "Value" "C_22u_0603"
			(at -1.42757 1.770288 0)
			(layer "F.Fab")
			(effects
				(font
					(size 0.7 0.7)
					(thickness 0.15)
				)
				(justify left bottom)
			)
		)
		(property "Author" "Antmicro"
			(at 0 0 0)
			(layer "F.Fab")
			(hide yes)
			(effects
				(font
					(size 1 1)
					(thickness 0.15)
				)
			)
		)
		(property "Dielectric" ""
			(at 0 0 0)
			(layer "F.Fab")
			(hide yes)
			(effects
				(font
					(size 1 1)
					(thickness 0.15)
				)
			)
		)
		(property "License" "Apache-2.0"
			(at 0 0 0)
			(layer "F.Fab")
			(hide yes)
			(effects
				(font
					(size 1 1)
					(thickness 0.15)
				)
			)
		)
		(property "MPN" "GRM188R60J226MEA0D"
			(at 0 0 0)
			(layer "F.Fab")
			(hide yes)
			(effects
				(font
					(size 1 1)
					(thickness 0.15)
				)
			)
		)
		(property "Manufacturer" "Murata"
			(at 0 0 0)
			(layer "F.Fab")
			(hide yes)
			(effects
				(font
					(size 1 1)
					(thickness 0.15)
				)
			)
		)
		(property "Val" "22u"
			(at 0 0 0)
			(layer "F.Fab")
			(hide yes)
			(effects
				(font
					(size 1 1)
					(thickness 0.15)
				)
			)
		)
		(property "Voltage" ""
			(at 0 0 0)
			(layer "F.Fab")
			(hide yes)
			(effects
				(font
					(size 1 1)
					(thickness 0.15)
				)
			)
		)
		(sheetname "Power supply")
		(sheetfile "power_supply.kicad_sch")
		(attr smd)
		(fp_line
			(start -0.3 -0.3)
			(end 0.3 -0.3)
			(stroke
				(width 0.15)
				(type solid)
			)
			(layer "F.SilkS")
		)
		(fp_line
			(start -0.3 0.3)
			(end 0.3 0.3)
			(stroke
				(width 0.15)
				(type solid)
			)
			(layer "F.SilkS")
		)
		(fp_rect
			(start -1.24 -0.7)
			(end 1.24 0.7)
			(stroke
				(width 0.05)
				(type solid)
			)
			(fill no)
			(layer "F.CrtYd")
		)
		(fp_rect
			(start -0.8 -0.4)
			(end 0.8 0.4)
			(stroke
				(width 0.15)
				(type solid)
			)
			(fill no)
			(layer "F.Fab")
		)
		(pad "1" smd roundrect
			(at -0.7 0)
			(size 0.6 0.8)
			(layers "F.Cu" "F.Mask" "F.Paste")
			(roundrect_rratio 0.2)
			(net 14 "GND")
			(pintype "passive")
		)
		(pad "2" smd roundrect
			(at 0.7 0)
			(size 0.6 0.8)
			(layers "F.Cu" "F.Mask" "F.Paste")
			(roundrect_rratio 0.2)
			(net 8 "/Power supply/VOUT2")
			(pintype "passive")
		)
	)
	(footprint "antmicro-footprints:R_Array_4x0402_Panasonic_EXB28V"
		(layer "F.Cu")
		(at 105.375 93.8)
		(property "Reference" "R9"
			(at -1.301 -1.45 0)
			(unlocked yes)
			(layer "F.SilkS")
			(effects
				(font
					(size 0.7 0.7)
					(thickness 0.15)
				)
				(justify left bottom)
			)
		)
		(property "Value" "R_4x100R_0402_array"
			(at -1.5 2 0)
			(layer "F.Fab")
			(effects
				(font
					(size 0.7 0.7)
					(thickness 0.15)
				)
				(justify left bottom)
			)
		)
		(property "Author" "Antmicro"
			(at 0 0 0)
			(layer "F.Fab")
			(hide yes)
			(effects
				(font
					(size 1 1)
					(thickness 0.15)
				)
			)
		)
		(property "License" "Apache-2.0"
			(at 0 0 0)
			(layer "F.Fab")
			(hide yes)
			(effects
				(font
					(size 1 1)
					(thickness 0.15)
				)
			)
		)
		(property "MPN" "EXB-28V101JX"
			(at 0 0 0)
			(layer "F.Fab")
			(hide yes)
			(effects
				(font
					(size 1 1)
					(thickness 0.15)
				)
			)
		)
		(property "Manufacturer" "Panasonic"
			(at 0 0 0)
			(layer "F.Fab")
			(hide yes)
			(effects
				(font
					(size 1 1)
					(thickness 0.15)
				)
			)
		)
		(property "Val" "R_4x100R_0402"
			(at 0 0 0)
			(layer "F.Fab")
			(hide yes)
			(effects
				(font
					(size 1 1)
					(thickness 0.15)
				)
			)
		)
		(sheetname "Translators")
		(sheetfile "translators.kicad_sch")
		(attr smd)
		(fp_line
			(start -1.25 -0.5)
			(end -1.25 0.498)
			(stroke
				(width 0.15)
				(type solid)
			)
			(layer "F.SilkS")
		)
		(fp_line
			(start 1.25 0.499)
			(end 1.25 -0.499)
			(stroke
				(width 0.15)
				(type solid)
			)
			(layer "F.SilkS")
		)
		(fp_rect
			(start -1.25 -0.8)
			(end 1.25 0.8)
			(stroke
				(width 0.05)
				(type solid)
			)
			(fill no)
			(layer "F.CrtYd")
		)
		(fp_line
			(start -1 -0.5)
			(end 0.998 -0.5)
			(stroke
				(width 0.15)
				(type solid)
			)
			(layer "F.Fab")
		)
		(fp_line
			(start -1 0.498)
			(end -1 -0.5)
			(stroke
				(width 0.15)
				(type solid)
			)
			(layer "F.Fab")
		)
		(fp_line
			(start 0.998 -0.5)
			(end 0.998 0.498)
			(stroke
				(width 0.15)
				(type solid)
			)
			(layer "F.Fab")
		)
		(fp_line
			(start 0.998 0.498)
			(end -1 0.498)
			(stroke
				(width 0.15)
				(type solid)
			)
			(layer "F.Fab")
		)
		(pad "1" smd roundrect
			(at -0.8875 0.45)
			(size 0.525 0.5)
			(layers "F.Cu" "F.Mask" "F.Paste")
			(roundrect_rratio 0.25)
			(net 187 "/SODIMM/LPDDR5_IN_A.DQ8")
			(pinfunction "R1.1")
			(pintype "passive")
		)
		(pad "2" smd roundrect
			(at -0.25 0.45)
			(size 0.25 0.5)
			(layers "F.Cu" "F.Mask" "F.Paste")
			(roundrect_rratio 0.25)
			(net 185 "/SODIMM/LPDDR5_IN_A.DQ10")
			(pinfunction "R2.1")
			(pintype "passive")
		)
		(pad "3" smd roundrect
			(at 0.25 0.45)
			(size 0.25 0.5)
			(layers "F.Cu" "F.Mask" "F.Paste")
			(roundrect_rratio 0.25)
			(net 186 "/SODIMM/LPDDR5_IN_A.DQ9")
			(pinfunction "R3.1")
			(pintype "passive")
		)
		(pad "4" smd roundrect
			(at 0.8875 0.45)
			(size 0.525 0.5)
			(layers "F.Cu" "F.Mask" "F.Paste")
			(roundrect_rratio 0.25)
			(net 184 "/SODIMM/LPDDR5_IN_A.DQ11")
			(pinfunction "R4.1")
			(pintype "passive")
		)
		(pad "5" smd roundrect
			(at 0.8875 -0.45)
			(size 0.525 0.5)
			(layers "F.Cu" "F.Mask" "F.Paste")
			(roundrect_rratio 0.25)
			(net 183 "/LPDDR5/LPDDR5_A.DQ11")
			(pinfunction "R4.2")
			(pintype "passive")
		)
		(pad "6" smd roundrect
			(at 0.25 -0.45)
			(size 0.25 0.5)
			(layers "F.Cu" "F.Mask" "F.Paste")
			(roundrect_rratio 0.25)
			(net 172 "/LPDDR5/LPDDR5_A.DQ9")
			(pinfunction "R3.2")
			(pintype "passive")
		)
		(pad "7" smd roundrect
			(at -0.25 -0.45)
			(size 0.25 0.5)
			(layers "F.Cu" "F.Mask" "F.Paste")
			(roundrect_rratio 0.25)
			(net 139 "/LPDDR5/LPDDR5_A.DQ10")
			(pinfunction "R2.2")
			(pintype "passive")
		)
		(pad "8" smd roundrect
			(at -0.8875 -0.45)
			(size 0.525 0.5)
			(layers "F.Cu" "F.Mask" "F.Paste")
			(roundrect_rratio 0.25)
			(net 128 "/LPDDR5/LPDDR5_A.DQ8")
			(pinfunction "R1.2")
			(pintype "passive")
		)
	)
	(footprint "antmicro-footprints:R_0603_1608Metric"
		(layer "F.Cu")
		(at 110.6 61.075 180)
		(descr "Resistor SMD 0603")
		(tags "resistor SMD 0603")
		(property "Reference" "R44"
			(at -3.4 -0.625 0)
			(unlocked yes)
			(layer "F.SilkS")
			(effects
				(font
					(size 0.7 0.7)
					(thickness 0.15)
				)
				(justify right bottom)
			)
		)
		(property "Value" "R_0R_22.4A_0603"
			(at 0 1.6 0)
			(layer "F.Fab")
			(effects
				(font
					(size 0.7 0.7)
					(thickness 0.15)
				)
				(justify right bottom)
			)
		)
		(property "Author" "Antmicro"
			(at 221.2 122.15 0)
			(layer "F.Fab")
			(hide yes)
			(effects
				(font
					(size 1 1)
					(thickness 0.15)
				)
			)
		)
		(property "License" "Apache-2.0"
			(at 221.2 122.15 0)
			(layer "F.Fab")
			(hide yes)
			(effects
				(font
					(size 1 1)
					(thickness 0.15)
				)
			)
		)
		(property "MPN" "PMR03EZPJ000"
			(at 221.2 122.15 0)
			(layer "F.Fab")
			(hide yes)
			(effects
				(font
					(size 1 1)
					(thickness 0.15)
				)
			)
		)
		(property "Manufacturer" "ROHM Semiconductor"
			(at 221.2 122.15 0)
			(layer "F.Fab")
			(hide yes)
			(effects
				(font
					(size 1 1)
					(thickness 0.15)
				)
			)
		)
		(property "Max. Curr." "22.4A"
			(at 221.2 122.15 0)
			(layer "F.Fab")
			(hide yes)
			(effects
				(font
					(size 1 1)
					(thickness 0.15)
				)
			)
		)
		(property "Tolerance" "template_tolerance"
			(at 221.2 122.15 0)
			(layer "F.Fab")
			(hide yes)
			(effects
				(font
					(size 1 1)
					(thickness 0.15)
				)
			)
		)
		(property "Val" "0R"
			(at 221.2 122.15 0)
			(layer "F.Fab")
			(hide yes)
			(effects
				(font
					(size 1 1)
					(thickness 0.15)
				)
			)
		)
		(sheetname "Power supply")
		(sheetfile "power_supply.kicad_sch")
		(attr smd)
		(fp_line
			(start -0.3 0.3)
			(end 0.3 0.3)
			(stroke
				(width 0.15)
				(type solid)
			)
			(layer "F.SilkS")
		)
		(fp_line
			(start -0.3 -0.3)
			(end 0.3 -0.3)
			(stroke
				(width 0.15)
				(type solid)
			)
			(layer "F.SilkS")
		)
		(fp_rect
			(start -1.25 -0.7)
			(end 1.25 0.7)
			(stroke
				(width 0.05)
				(type solid)
			)
			(fill no)
			(layer "F.CrtYd")
		)
		(fp_rect
			(start -0.8 -0.4)
			(end 0.8 0.4)
			(stroke
				(width 0.15)
				(type solid)
			)
			(fill no)
			(layer "F.Fab")
		)
		(pad "1" smd roundrect
			(at -0.7 0 180)
			(size 0.6 0.8)
			(layers "F.Cu" "F.Mask" "F.Paste")
			(roundrect_rratio 0.2)
			(net 12 "+0V9")
			(pintype "passive")
		)
		(pad "2" smd roundrect
			(at 0.7 0 180)
			(size 0.6 0.8)
			(layers "F.Cu" "F.Mask" "F.Paste")
			(roundrect_rratio 0.2)
			(net 8 "/Power supply/VOUT2")
			(pintype "passive")
		)
	)
	(footprint "antmicro-footprints:R_0402_1005Metric"
		(layer "F.Cu")
		(at 164.675 64.35 180)
		(descr "Resistor SMD 0402")
		(tags "resistor SMD 0402")
		(property "Reference" "R47"
			(at 4.975 -0.65 0)
			(unlocked yes)
			(layer "F.SilkS")
			(effects
				(font
					(size 0.7 0.7)
					(thickness 0.15)
				)
				(justify right bottom)
			)
		)
		(property "Value" "R_0R_0402"
			(at -1.011843 1.772047 0)
			(layer "F.Fab")
			(effects
				(font
					(size 0.7 0.7)
					(thickness 0.15)
				)
				(justify right bottom)
			)
		)
		(property "Author" "Antmicro"
			(at 329.35 128.7 0)
			(layer "F.Fab")
			(hide yes)
			(effects
				(font
					(size 1 1)
					(thickness 0.15)
				)
			)
		)
		(property "Current" "1A"
			(at 329.35 128.7 0)
			(layer "F.Fab")
			(hide yes)
			(effects
				(font
					(size 1 1)
					(thickness 0.15)
				)
			)
		)
		(property "License" "Apache-2.0"
			(at 329.35 128.7 0)
			(layer "F.Fab")
			(hide yes)
			(effects
				(font
					(size 1 1)
					(thickness 0.15)
				)
			)
		)
		(property "MPN" "ERJ2GE0R00X"
			(at 329.35 128.7 0)
			(layer "F.Fab")
			(hide yes)
			(effects
				(font
					(size 1 1)
					(thickness 0.15)
				)
			)
		)
		(property "Manufacturer" "Panasonic"
			(at 329.35 128.7 0)
			(layer "F.Fab")
			(hide yes)
			(effects
				(font
					(size 1 1)
					(thickness 0.15)
				)
			)
		)
		(property "Tolerance" ""
			(at 329.35 128.7 0)
			(layer "F.Fab")
			(hide yes)
			(effects
				(font
					(size 1 1)
					(thickness 0.15)
				)
			)
		)
		(property "Val" "0R"
			(at 329.35 128.7 0)
			(layer "F.Fab")
			(hide yes)
			(effects
				(font
					(size 1 1)
					(thickness 0.15)
				)
			)
		)
		(sheetname "Power supply")
		(sheetfile "power_supply.kicad_sch")
		(attr smd exclude_from_pos_files exclude_from_bom dnp)
		(fp_rect
			(start -0.93 -0.47)
			(end 0.93 0.47)
			(stroke
				(width 0.05)
				(type solid)
			)
			(fill no)
			(layer "F.CrtYd")
		)
		(fp_rect
			(start -0.5 -0.25)
			(end 0.5 0.25)
			(stroke
				(width 0.15)
				(type solid)
			)
			(fill no)
			(layer "F.Fab")
		)
		(pad "1" smd roundrect
			(at -0.485 0 180)
			(size 0.59 0.64)
			(layers "F.Cu" "F.Mask" "F.Paste")
			(roundrect_rratio 0.25)
			(net 52 "Net-(POT1-Pad2)")
			(pintype "passive")
		)
		(pad "2" smd roundrect
			(at 0.485 0 180)
			(size 0.59 0.64)
			(layers "F.Cu" "F.Mask" "F.Paste")
			(roundrect_rratio 0.25)
			(net 53 "Net-(POT1-Pad3)")
			(pintype "passive")
		)
	)
	(footprint "antmicro-footprints:Trimpot_3.8mmx3.6mm_TC33X-2-103E"
		(layer "F.Cu")
		(at 164.575 62.75 -90)
		(property "Reference" "POT1"
			(at -1.15 -1.725 0)
			(unlocked yes)
			(layer "F.SilkS")
			(effects
				(font
					(size 0.7 0.7)
					(thickness 0.15)
				)
				(justify right bottom)
			)
		)
		(property "Value" "TC33X-2-203E"
			(at 0 3.3 90)
			(layer "F.Fab")
			(effects
				(font
					(size 0.7 0.7)
					(thickness 0.15)
				)
				(justify right bottom)
			)
		)
		(property "Author" "Antmicro"
			(at 101.825 227.325 0)
			(layer "F.Fab")
			(hide yes)
			(effects
				(font
					(size 1 1)
					(thickness 0.15)
				)
			)
		)
		(property "License" "Apache-2.0"
			(at 101.825 227.325 0)
			(layer "F.Fab")
			(hide yes)
			(effects
				(font
					(size 1 1)
					(thickness 0.15)
				)
			)
		)
		(property "MPN" "TC33X-2-203E"
			(at 101.825 227.325 0)
			(layer "F.Fab")
			(hide yes)
			(effects
				(font
					(size 1 1)
					(thickness 0.15)
				)
			)
		)
		(property "Manufacturer" "Bourns"
			(at 101.825 227.325 0)
			(layer "F.Fab")
			(hide yes)
			(effects
				(font
					(size 1 1)
					(thickness 0.15)
				)
			)
		)
		(sheetname "Power supply")
		(sheetfile "power_supply.kicad_sch")
		(attr smd)
		(fp_line
			(start -1.901 1.9)
			(end -1.7 1.9)
			(stroke
				(width 0.15)
				(type solid)
			)
			(layer "F.SilkS")
		)
		(fp_line
			(start 1.898 1.9)
			(end 1.699 1.9)
			(stroke
				(width 0.15)
				(type solid)
			)
			(layer "F.SilkS")
		)
		(fp_line
			(start 1.898 1.9)
			(end 1.898 1.65)
			(stroke
				(width 0.15)
				(type solid)
			)
			(layer "F.SilkS")
		)
		(fp_line
			(start -1.901 1.65)
			(end -1.901 1.9)
			(stroke
				(width 0.15)
				(type solid)
			)
			(layer "F.SilkS")
		)
		(fp_line
			(start -1.901 -2.1)
			(end -1.901 -1.85)
			(stroke
				(width 0.15)
				(type solid)
			)
			(layer "F.SilkS")
		)
		(fp_line
			(start -1.901 -2.1)
			(end -1.651 -2.1)
			(stroke
				(width 0.15)
				(type solid)
			)
			(layer "F.SilkS")
		)
		(fp_line
			(start 1.898 -2.1)
			(end 1.898 -1.85)
			(stroke
				(width 0.15)
				(type solid)
			)
			(layer "F.SilkS")
		)
		(fp_line
			(start 1.898 -2.1)
			(end 1.648 -2.1)
			(stroke
				(width 0.15)
				(type solid)
			)
			(layer "F.SilkS")
		)
		(fp_circle
			(center -1.9 2.2)
			(end -1.85 2.2)
			(stroke
				(width 0.15)
				(type solid)
			)
			(fill yes)
			(layer "F.SilkS")
		)
		(fp_rect
			(start -2.1 -2.4)
			(end 2.1 2.4)
			(stroke
				(width 0.05)
				(type solid)
			)
			(fill no)
			(layer "F.CrtYd")
		)
		(fp_line
			(start -1.801 1.799)
			(end 1.8 1.799)
			(stroke
				(width 0.15)
				(type solid)
			)
			(layer "F.Fab")
		)
		(fp_line
			(start 1.8 1.799)
			(end 1.8 -2.001)
			(stroke
				(width 0.15)
				(type solid)
			)
			(layer "F.Fab")
		)
		(fp_line
			(start -1.801 -2.001)
			(end -1.801 1.799)
			(stroke
				(width 0.15)
				(type solid)
			)
			(layer "F.Fab")
		)
		(fp_line
			(start -1.801 -2.001)
			(end 1.8 -2.001)
			(stroke
				(width 0.15)
				(type solid)
			)
			(layer "F.Fab")
		)
		(pad "1" smd rect
			(at -1 1.7 270)
			(size 1.2 1.2)
			(layers "F.Cu" "F.Mask" "F.Paste")
			(net 51 "unconnected-(POT1-Pad1)")
			(pinfunction "1")
			(pintype "passive+no_connect")
		)
		(pad "2" smd rect
			(at 0 -1.551 270)
			(size 1.6 1.5)
			(layers "F.Cu" "F.Mask" "F.Paste")
			(net 52 "Net-(POT1-Pad2)")
			(pinfunction "2")
			(pintype "passive")
		)
		(pad "3" smd rect
			(at 0.998 1.7 270)
			(size 1.2 1.2)
			(layers "F.Cu" "F.Mask" "F.Paste")
			(net 53 "Net-(POT1-Pad3)")
			(pinfunction "3")
			(pintype "passive")
		)
	)
	(footprint "antmicro-footprints:QFN-20-4EP_3x4x0.75mm_P0.5mm_Layout4x6_LT3033"
		(layer "F.Cu")
		(at 164.075 67.95 90)
		(property "Reference" "U9"
			(at -1.05 -4.075 0)
			(unlocked yes)
			(layer "F.SilkS")
			(effects
				(font
					(size 0.7 0.7)
					(thickness 0.15)
				)
				(justify left bottom)
			)
		)
		(property "Value" "LT3033EUDC_QFN"
			(at 0 3.4 90)
			(unlocked yes)
			(layer "F.Fab")
			(effects
				(font
					(size 0.7 0.7)
					(thickness 0.15)
				)
				(justify left bottom)
			)
		)
		(property "Author" "Antmicro"
			(at 232.025 -96.125 0)
			(layer "F.Fab")
			(hide yes)
			(effects
				(font
					(size 1 1)
					(thickness 0.15)
				)
			)
		)
		(property "License" "Apache-2.0"
			(at 232.025 -96.125 0)
			(layer "F.Fab")
			(hide yes)
			(effects
				(font
					(size 1 1)
					(thickness 0.15)
				)
			)
		)
		(property "MPN" "LT3033EUDC#PBF"
			(at 232.025 -96.125 0)
			(layer "F.Fab")
			(hide yes)
			(effects
				(font
					(size 1 1)
					(thickness 0.15)
				)
			)
		)
		(property "Manufacturer" "Analog Devices"
			(at 232.025 -96.125 0)
			(layer "F.Fab")
			(hide yes)
			(effects
				(font
					(size 1 1)
					(thickness 0.15)
				)
			)
		)
		(sheetname "Power supply")
		(sheetfile "power_supply.kicad_sch")
		(attr smd)
		(fp_line
			(start 1.6 -2.1)
			(end 1 -2.1)
			(stroke
				(width 0.15)
				(type solid)
			)
			(layer "F.SilkS")
		)
		(fp_line
			(start 1.6 -2.1)
			(end 1.6 -1.7)
			(stroke
				(width 0.15)
				(type solid)
			)
			(layer "F.SilkS")
		)
		(fp_line
			(start -1 -2.1)
			(end -1.6 -2.1)
			(stroke
				(width 0.15)
				(type solid)
			)
			(layer "F.SilkS")
		)
		(fp_line
			(start -1.6 -2.1)
			(end -1.6 -1.7)
			(stroke
				(width 0.15)
				(type solid)
			)
			(layer "F.SilkS")
		)
		(fp_line
			(start 1.6 2.1)
			(end 1.6 1.7)
			(stroke
				(width 0.15)
				(type solid)
			)
			(layer "F.SilkS")
		)
		(fp_line
			(start 1 2.1)
			(end 1.6 2.1)
			(stroke
				(width 0.15)
				(type solid)
			)
			(layer "F.SilkS")
		)
		(fp_line
			(start -1.6 2.1)
			(end -1.6 1.7)
			(stroke
				(width 0.15)
				(type solid)
			)
			(layer "F.SilkS")
		)
		(fp_line
			(start -1.6 2.1)
			(end -1 2.1)
			(stroke
				(width 0.15)
				(type solid)
			)
			(layer "F.SilkS")
		)
		(fp_circle
			(center -1.75 -1.55)
			(end -1.7 -1.55)
			(stroke
				(width 0.15)
				(type solid)
			)
			(fill yes)
			(layer "F.SilkS")
		)
		(fp_rect
			(start -2 -2.5)
			(end 2 2.5)
			(stroke
				(width 0.05)
				(type solid)
			)
			(fill no)
			(layer "F.CrtYd")
		)
		(fp_line
			(start 1.5 -2)
			(end -1 -2)
			(stroke
				(width 0.15)
				(type solid)
			)
			(layer "F.Fab")
		)
		(fp_line
			(start -1 -2)
			(end -1.5 -1.5)
			(stroke
				(width 0.15)
				(type solid)
			)
			(layer "F.Fab")
		)
		(fp_line
			(start -1.5 -1.5)
			(end -1.5 2)
			(stroke
				(width 0.15)
				(type solid)
			)
			(layer "F.Fab")
		)
		(fp_line
			(start 1.5 2)
			(end 1.5 -2)
			(stroke
				(width 0.15)
				(type solid)
			)
			(layer "F.Fab")
		)
		(fp_line
			(start -1.5 2)
			(end 1.5 2)
			(stroke
				(width 0.15)
				(type solid)
			)
			(layer "F.Fab")
		)
		(pad "1" smd roundrect
			(at -1.4 -1.25 180)
			(size 0.25 0.7)
			(layers "F.Cu" "F.Mask" "F.Paste")
			(roundrect_rratio 0.25)
			(net 1 "+1V1")
			(pinfunction "IN")
			(pintype "power_in")
		)
		(pad "2" smd roundrect
			(at -1.4 -0.75 180)
			(size 0.25 0.7)
			(layers "F.Cu" "F.Mask" "F.Paste")
			(roundrect_rratio 0.25)
			(net 1 "+1V1")
			(pinfunction "IN")
			(pintype "passive")
		)
		(pad "3" smd roundrect
			(at -1.4 -0.25 180)
			(size 0.25 0.7)
			(layers "F.Cu" "F.Mask" "F.Paste")
			(roundrect_rratio 0.25)
			(net 11 "/Power supply/VOUT")
			(pinfunction "OUT")
			(pintype "passive")
		)
		(pad "4" smd roundrect
			(at -1.4 0.25 180)
			(size 0.25 0.7)
			(layers "F.Cu" "F.Mask" "F.Paste")
			(roundrect_rratio 0.25)
			(net 11 "/Power supply/VOUT")
			(pinfunction "OUT")
			(pintype "passive")
		)
		(pad "5" smd roundrect
			(at -1.4 0.75 180)
			(size 0.25 0.7)
			(layers "F.Cu" "F.Mask" "F.Paste")
			(roundrect_rratio 0.25)
			(net 14 "GND")
			(pinfunction "GND")
			(pintype "power_in")
		)
		(pad "6" smd roundrect
			(at -1.4 1.25 180)
			(size 0.25 0.7)
			(layers "F.Cu" "F.Mask" "F.Paste")
			(roundrect_rratio 0.25)
			(net 14 "GND")
			(pinfunction "GND")
			(pintype "passive")
		)
		(pad "7" smd roundrect
			(at -0.75 1.9 270)
			(size 0.25 0.7)
			(layers "F.Cu" "F.Mask" "F.Paste")
			(roundrect_rratio 0.25)
			(net 14 "GND")
			(pinfunction "ILIM")
			(pintype "passive")
		)
		(pad "8" smd roundrect
			(at -0.25 1.9 270)
			(size 0.25 0.7)
			(layers "F.Cu" "F.Mask" "F.Paste")
			(roundrect_rratio 0.25)
			(net 69 "Net-(R32-Pad2)")
			(pinfunction "IMON")
			(pintype "output")
		)
		(pad "9" smd roundrect
			(at 0.25 1.9 270)
			(size 0.25 0.7)
			(layers "F.Cu" "F.Mask" "F.Paste")
			(roundrect_rratio 0.25)
			(net 6 "Net-(C13-Pad2)")
			(pinfunction "REF/BYP")
			(pintype "passive")
		)
		(pad "10" smd roundrect
			(at 0.75 1.9 270)
			(size 0.25 0.7)
			(layers "F.Cu" "F.Mask" "F.Paste")
			(roundrect_rratio 0.25)
			(net 52 "Net-(POT1-Pad2)")
			(pinfunction "ADJ")
			(pintype "input")
		)
		(pad "11" smd roundrect
			(at 1.4 1.25 180)
			(size 0.25 0.7)
			(layers "F.Cu" "F.Mask" "F.Paste")
			(roundrect_rratio 0.25)
			(net 41 "/Power supply/PWRGD")
			(pinfunction "PWRGD")
			(pintype "open_collector")
		)
		(pad "12" smd roundrect
			(at 1.4 0.75 180)
			(size 0.25 0.7)
			(layers "F.Cu" "F.Mask" "F.Paste")
			(roundrect_rratio 0.25)
			(net 61 "Net-(R29-Pad2)")
			(pinfunction "~{SHDN}")
			(pintype "input")
		)
		(pad "13" smd roundrect
			(at 1.4 0.25 180)
			(size 0.25 0.7)
			(layers "F.Cu" "F.Mask" "F.Paste")
			(roundrect_rratio 0.25)
			(net 11 "/Power supply/VOUT")
			(pinfunction "OUT")
			(pintype "power_out")
		)
		(pad "14" smd roundrect
			(at 1.4 -0.25 180)
			(size 0.25 0.7)
			(layers "F.Cu" "F.Mask" "F.Paste")
			(roundrect_rratio 0.25)
			(net 11 "/Power supply/VOUT")
			(pinfunction "OUT")
			(pintype "passive")
		)
		(pad "15" smd roundrect
			(at 1.4 -0.75 180)
			(size 0.25 0.7)
			(layers "F.Cu" "F.Mask" "F.Paste")
			(roundrect_rratio 0.25)
			(net 1 "+1V1")
			(pinfunction "IN")
			(pintype "passive")
		)
		(pad "16" smd roundrect
			(at 1.4 -1.25 180)
			(size 0.25 0.7)
			(layers "F.Cu" "F.Mask" "F.Paste")
			(roundrect_rratio 0.25)
			(net 1 "+1V1")
			(pinfunction "IN")
			(pintype "passive")
		)
		(pad "17" smd roundrect
			(at 0.75 -1.9 270)
			(size 0.25 0.7)
			(layers "F.Cu" "F.Mask" "F.Paste")
			(roundrect_rratio 0.25)
			(net 11 "/Power supply/VOUT")
			(pinfunction "OUT")
			(pintype "passive")
		)
		(pad "18" smd roundrect
			(at 0.25 -1.9 270)
			(size 0.25 0.7)
			(layers "F.Cu" "F.Mask" "F.Paste")
			(roundrect_rratio 0.25)
			(net 11 "/Power supply/VOUT")
			(pinfunction "OUT")
			(pintype "passive")
		)
		(pad "19" smd roundrect
			(at -0.25 -1.9 270)
			(size 0.25 0.7)
			(layers "F.Cu" "F.Mask" "F.Paste")
			(roundrect_rratio 0.25)
			(net 11 "/Power supply/VOUT")
			(pinfunction "OUT")
			(pintype "passive")
		)
		(pad "20" smd roundrect
			(at -0.75 -1.9 270)
			(size 0.25 0.7)
			(layers "F.Cu" "F.Mask" "F.Paste")
			(roundrect_rratio 0.25)
			(net 11 "/Power supply/VOUT")
			(pinfunction "OUT")
			(pintype "passive")
		)
		(pad "21" smd roundrect
			(at -0.61 -1.12 270)
			(size 0.41 0.25)
			(layers "F.Cu" "F.Mask" "F.Paste")
			(roundrect_rratio 0.25)
			(net 1 "+1V1")
			(pinfunction "IN")
			(pintype "passive")
		)
		(pad "22" smd roundrect
			(at 0.61 -1.12 270)
			(size 0.41 0.25)
			(layers "F.Cu" "F.Mask" "F.Paste")
			(roundrect_rratio 0.25)
			(net 1 "+1V1")
			(pinfunction "IN")
			(pintype "passive")
		)
		(pad "23" smd roundrect
			(at -0.61 -0.02 270)
			(size 0.41 0.25)
			(layers "F.Cu" "F.Mask" "F.Paste")
			(roundrect_rratio 0.25)
			(net 11 "/Power supply/VOUT")
			(pinfunction "OUT")
			(pintype "passive")
		)
		(pad "24" smd roundrect
			(at 0.61 -0.02 270)
			(size 0.41 0.25)
			(layers "F.Cu" "F.Mask" "F.Paste")
			(roundrect_rratio 0.25)
			(net 11 "/Power supply/VOUT")
			(pinfunction "OUT")
			(pintype "passive")
		)
	)
	(footprint "antmicro-footprints:R_Array_4x0402_Panasonic_EXB28V"
		(layer "F.Cu")
		(at 115.875 93.8)
		(property "Reference" "R5"
			(at -1.301 -1.45 0)
			(unlocked yes)
			(layer "F.SilkS")
			(effects
				(font
					(size 0.7 0.7)
					(thickness 0.15)
				)
				(justify left bottom)
			)
		)
		(property "Value" "R_4x100R_0402_array"
			(at -1.5 2 0)
			(layer "F.Fab")
			(effects
				(font
					(size 0.7 0.7)
					(thickness 0.15)
				)
				(justify left bottom)
			)
		)
		(property "Author" "Antmicro"
			(at 0 0 0)
			(layer "F.Fab")
			(hide yes)
			(effects
				(font
					(size 1 1)
					(thickness 0.15)
				)
			)
		)
		(property "License" "Apache-2.0"
			(at 0 0 0)
			(layer "F.Fab")
			(hide yes)
			(effects
				(font
					(size 1 1)
					(thickness 0.15)
				)
			)
		)
		(property "MPN" "EXB-28V101JX"
			(at 0 0 0)
			(layer "F.Fab")
			(hide yes)
			(effects
				(font
					(size 1 1)
					(thickness 0.15)
				)
			)
		)
		(property "Manufacturer" "Panasonic"
			(at 0 0 0)
			(layer "F.Fab")
			(hide yes)
			(effects
				(font
					(size 1 1)
					(thickness 0.15)
				)
			)
		)
		(property "Val" "R_4x100R_0402"
			(at 0 0 0)
			(layer "F.Fab")
			(hide yes)
			(effects
				(font
					(size 1 1)
					(thickness 0.15)
				)
			)
		)
		(sheetname "Translators")
		(sheetfile "translators.kicad_sch")
		(attr smd)
		(fp_line
			(start -1.25 -0.5)
			(end -1.25 0.498)
			(stroke
				(width 0.15)
				(type solid)
			)
			(layer "F.SilkS")
		)
		(fp_line
			(start 1.25 0.499)
			(end 1.25 -0.499)
			(stroke
				(width 0.15)
				(type solid)
			)
			(layer "F.SilkS")
		)
		(fp_rect
			(start -1.25 -0.8)
			(end 1.25 0.8)
			(stroke
				(width 0.05)
				(type solid)
			)
			(fill no)
			(layer "F.CrtYd")
		)
		(fp_line
			(start -1 -0.5)
			(end 0.998 -0.5)
			(stroke
				(width 0.15)
				(type solid)
			)
			(layer "F.Fab")
		)
		(fp_line
			(start -1 0.498)
			(end -1 -0.5)
			(stroke
				(width 0.15)
				(type solid)
			)
			(layer "F.Fab")
		)
		(fp_line
			(start 0.998 -0.5)
			(end 0.998 0.498)
			(stroke
				(width 0.15)
				(type solid)
			)
			(layer "F.Fab")
		)
		(fp_line
			(start 0.998 0.498)
			(end -1 0.498)
			(stroke
				(width 0.15)
				(type solid)
			)
			(layer "F.Fab")
		)
		(pad "1" smd roundrect
			(at -0.8875 0.45)
			(size 0.525 0.5)
			(layers "F.Cu" "F.Mask" "F.Paste")
			(roundrect_rratio 0.25)
			(net 176 "/SODIMM/LPDDR5_IN_A.DQ5")
			(pinfunction "R1.1")
			(pintype "passive")
		)
		(pad "2" smd roundrect
			(at -0.25 0.45)
			(size 0.25 0.5)
			(layers "F.Cu" "F.Mask" "F.Paste")
			(roundrect_rratio 0.25)
			(net 175 "/SODIMM/LPDDR5_IN_A.DQ4")
			(pinfunction "R2.1")
			(pintype "passive")
		)
		(pad "3" smd roundrect
			(at 0.25 0.45)
			(size 0.25 0.5)
			(layers "F.Cu" "F.Mask" "F.Paste")
			(roundrect_rratio 0.25)
			(net 174 "/SODIMM/LPDDR5_IN_A.DQ6")
			(pinfunction "R3.1")
			(pintype "passive")
		)
		(pad "4" smd roundrect
			(at 0.8875 0.45)
			(size 0.525 0.5)
			(layers "F.Cu" "F.Mask" "F.Paste")
			(roundrect_rratio 0.25)
			(net 173 "/SODIMM/LPDDR5_IN_A.DQ7")
			(pinfunction "R4.1")
			(pintype "passive")
		)
		(pad "5" smd roundrect
			(at 0.8875 -0.45)
			(size 0.525 0.5)
			(layers "F.Cu" "F.Mask" "F.Paste")
			(roundrect_rratio 0.25)
			(net 195 "/LPDDR5/LPDDR5_A.DQ7")
			(pinfunction "R4.2")
			(pintype "passive")
		)
		(pad "6" smd roundrect
			(at 0.25 -0.45)
			(size 0.25 0.5)
			(layers "F.Cu" "F.Mask" "F.Paste")
			(roundrect_rratio 0.25)
			(net 196 "/LPDDR5/LPDDR5_A.DQ6")
			(pinfunction "R3.2")
			(pintype "passive")
		)
		(pad "7" smd roundrect
			(at -0.25 -0.45)
			(size 0.25 0.5)
			(layers "F.Cu" "F.Mask" "F.Paste")
			(roundrect_rratio 0.25)
			(net 198 "/LPDDR5/LPDDR5_A.DQ4")
			(pinfunction "R2.2")
			(pintype "passive")
		)
		(pad "8" smd roundrect
			(at -0.8875 -0.45)
			(size 0.525 0.5)
			(layers "F.Cu" "F.Mask" "F.Paste")
			(roundrect_rratio 0.25)
			(net 197 "/LPDDR5/LPDDR5_A.DQ5")
			(pinfunction "R1.2")
			(pintype "passive")
		)
	)
	(footprint "antmicro-footprints:R_0402_1005Metric"
		(layer "F.Cu")
		(at 137.65 93.85 90)
		(descr "Resistor SMD 0402")
		(tags "resistor SMD 0402")
		(property "Reference" "R68"
			(at -1.15 1.35 90)
			(unlocked yes)
			(layer "F.SilkS")
			(effects
				(font
					(size 0.7 0.7)
					(thickness 0.15)
				)
				(justify left bottom)
			)
		)
		(property "Value" "R_100R_0402"
			(at -1.011843 1.772047 90)
			(layer "F.Fab")
			(effects
				(font
					(size 0.7 0.7)
					(thickness 0.15)
				)
				(justify left bottom)
			)
		)
		(property "Author" "Antmicro"
			(at 231.5 -43.8 0)
			(layer "F.Fab")
			(hide yes)
			(effects
				(font
					(size 1 1)
					(thickness 0.15)
				)
			)
		)
		(property "License" "Apache-2.0"
			(at 231.5 -43.8 0)
			(layer "F.Fab")
			(hide yes)
			(effects
				(font
					(size 1 1)
					(thickness 0.15)
				)
			)
		)
		(property "MPN" "CR0402-FX-1000GLF"
			(at 231.5 -43.8 0)
			(layer "F.Fab")
			(hide yes)
			(effects
				(font
					(size 1 1)
					(thickness 0.15)
				)
			)
		)
		(property "Manufacturer" "Bourns"
			(at 231.5 -43.8 0)
			(layer "F.Fab")
			(hide yes)
			(effects
				(font
					(size 1 1)
					(thickness 0.15)
				)
			)
		)
		(property "Tolerance" "1%"
			(at 231.5 -43.8 0)
			(layer "F.Fab")
			(hide yes)
			(effects
				(font
					(size 1 1)
					(thickness 0.15)
				)
			)
		)
		(property "Val" "100R"
			(at 231.5 -43.8 0)
			(layer "F.Fab")
			(hide yes)
			(effects
				(font
					(size 1 1)
					(thickness 0.15)
				)
			)
		)
		(sheetname "Translators1")
		(sheetfile "translators.kicad_sch")
		(attr smd)
		(fp_rect
			(start -0.93 -0.47)
			(end 0.93 0.47)
			(stroke
				(width 0.05)
				(type solid)
			)
			(fill no)
			(layer "F.CrtYd")
		)
		(fp_rect
			(start -0.5 -0.25)
			(end 0.5 0.25)
			(stroke
				(width 0.15)
				(type solid)
			)
			(fill no)
			(layer "F.Fab")
		)
		(pad "1" smd roundrect
			(at -0.485 0 90)
			(size 0.59 0.64)
			(layers "F.Cu" "F.Mask" "F.Paste")
			(roundrect_rratio 0.25)
			(net 153 "/SODIMM/LPDDR5_IN_B.CK_N")
			(pintype "passive")
		)
		(pad "2" smd roundrect
			(at 0.485 0 90)
			(size 0.59 0.64)
			(layers "F.Cu" "F.Mask" "F.Paste")
			(roundrect_rratio 0.25)
			(net 113 "/LPDDR5/LPDDR5_B.CK_N")
			(pintype "passive")
		)
	)
	(footprint "antmicro-footprints:TP_SMD_0.75mm"
		(layer "F.Cu")
		(at 109.775 62.95)
		(property "Reference" "TP5"
			(at 0.7 0.4 0)
			(unlocked yes)
			(layer "F.SilkS")
			(effects
				(font
					(size 0.7 0.7)
					(thickness 0.15)
				)
				(justify left bottom)
			)
		)
		(property "Value" "TP_0.75mm_SMD"
			(at 0 1.2 0)
			(layer "F.Fab")
			(effects
				(font
					(size 0.7 0.7)
					(thickness 0.15)
				)
				(justify left bottom)
			)
		)
		(property "Author" "Antmicro"
			(at 0 0 0)
			(layer "F.Fab")
			(hide yes)
			(effects
				(font
					(size 1 1)
					(thickness 0.15)
				)
			)
		)
		(property "License" "Apache-2.0"
			(at 0 0 0)
			(layer "F.Fab")
			(hide yes)
			(effects
				(font
					(size 1 1)
					(thickness 0.15)
				)
			)
		)
		(property "MPN" ""
			(at 0 0 0)
			(layer "F.Fab")
			(hide yes)
			(effects
				(font
					(size 1 1)
					(thickness 0.15)
				)
			)
		)
		(property "Manufacturer" ""
			(at 0 0 0)
			(layer "F.Fab")
			(hide yes)
			(effects
				(font
					(size 1 1)
					(thickness 0.15)
				)
			)
		)
		(sheetname "Power supply")
		(sheetfile "power_supply.kicad_sch")
		(attr exclude_from_pos_files)
		(pad "1" smd circle
			(at 0 0)
			(size 0.75 0.75)
			(layers "F.Cu" "F.Mask")
			(net 8 "/Power supply/VOUT2")
			(pinfunction "1")
			(pintype "passive")
		)
	)
	(footprint "antmicro-footprints:R_0402_1005Metric"
		(layer "F.Cu")
		(at 164.45 93.8 90)
		(descr "Resistor SMD 0402")
		(tags "resistor SMD 0402")
		(property "Reference" "R95"
			(at -1.8 -1.05 0)
			(unlocked yes)
			(layer "F.SilkS")
			(effects
				(font
					(size 0.7 0.7)
					(thickness 0.15)
				)
				(justify left bottom)
			)
		)
		(property "Value" "R_100R_0402"
			(at -1.011843 1.772047 90)
			(layer "F.Fab")
			(effects
				(font
					(size 0.7 0.7)
					(thickness 0.15)
				)
				(justify left bottom)
			)
		)
		(property "Author" "Antmicro"
			(at 258.25 -70.65 0)
			(layer "F.Fab")
			(hide yes)
			(effects
				(font
					(size 1 1)
					(thickness 0.15)
				)
			)
		)
		(property "License" "Apache-2.0"
			(at 258.25 -70.65 0)
			(layer "F.Fab")
			(hide yes)
			(effects
				(font
					(size 1 1)
					(thickness 0.15)
				)
			)
		)
		(property "MPN" "CR0402-FX-1000GLF"
			(at 258.25 -70.65 0)
			(layer "F.Fab")
			(hide yes)
			(effects
				(font
					(size 1 1)
					(thickness 0.15)
				)
			)
		)
		(property "Manufacturer" "Bourns"
			(at 258.25 -70.65 0)
			(layer "F.Fab")
			(hide yes)
			(effects
				(font
					(size 1 1)
					(thickness 0.15)
				)
			)
		)
		(property "Tolerance" "1%"
			(at 258.25 -70.65 0)
			(layer "F.Fab")
			(hide yes)
			(effects
				(font
					(size 1 1)
					(thickness 0.15)
				)
			)
		)
		(property "Val" "100R"
			(at 258.25 -70.65 0)
			(layer "F.Fab")
			(hide yes)
			(effects
				(font
					(size 1 1)
					(thickness 0.15)
				)
			)
		)
		(sheetname "Translators1")
		(sheetfile "translators.kicad_sch")
		(attr smd)
		(fp_rect
			(start -0.93 -0.47)
			(end 0.93 0.47)
			(stroke
				(width 0.05)
				(type solid)
			)
			(fill no)
			(layer "F.CrtYd")
		)
		(fp_rect
			(start -0.5 -0.25)
			(end 0.5 0.25)
			(stroke
				(width 0.15)
				(type solid)
			)
			(fill no)
			(layer "F.Fab")
		)
		(pad "1" smd roundrect
			(at -0.485 0 90)
			(size 0.59 0.64)
			(layers "F.Cu" "F.Mask" "F.Paste")
			(roundrect_rratio 0.25)
			(net 120 "/SODIMM/LPDDR5_IN_B.DMI0")
			(pintype "passive")
		)
		(pad "2" smd roundrect
			(at 0.485 0 90)
			(size 0.59 0.64)
			(layers "F.Cu" "F.Mask" "F.Paste")
			(roundrect_rratio 0.25)
			(net 212 "/LPDDR5/LPDDR5_B.DMI0")
			(pintype "passive")
		)
	)
	(footprint "antmicro-footprints:C_0805_2012Metric"
		(layer "F.Cu")
		(at 106.4875 75.225)
		(descr "Capacitor SMD 0805")
		(tags "capacitor SMD 0805")
		(property "Reference" "C11"
			(at -1.0875 1.975 0)
			(unlocked yes)
			(layer "F.SilkS")
			(effects
				(font
					(size 0.7 0.7)
					(thickness 0.15)
				)
				(justify left bottom)
			)
		)
		(property "Value" "C_22u_25V_0805"
			(at -2.055717 1.963152 0)
			(layer "F.Fab")
			(effects
				(font
					(size 0.7 0.7)
					(thickness 0.15)
				)
				(justify left bottom)
			)
		)
		(property "Author" "Antmicro"
			(at 0 0 0)
			(layer "F.Fab")
			(hide yes)
			(effects
				(font
					(size 1 1)
					(thickness 0.15)
				)
			)
		)
		(property "Dielectric" ""
			(at 0 0 0)
			(layer "F.Fab")
			(hide yes)
			(effects
				(font
					(size 1 1)
					(thickness 0.15)
				)
			)
		)
		(property "License" "Apache-2.0"
			(at 0 0 0)
			(layer "F.Fab")
			(hide yes)
			(effects
				(font
					(size 1 1)
					(thickness 0.15)
				)
			)
		)
		(property "MPN" "CL21A226MAYNNNE"
			(at 0 0 0)
			(layer "F.Fab")
			(hide yes)
			(effects
				(font
					(size 1 1)
					(thickness 0.15)
				)
			)
		)
		(property "Manufacturer" "Samsung Electro-Mechanics"
			(at 0 0 0)
			(layer "F.Fab")
			(hide yes)
			(effects
				(font
					(size 1 1)
					(thickness 0.15)
				)
			)
		)
		(property "Val" "22u_25V"
			(at 0 0 0)
			(layer "F.Fab")
			(hide yes)
			(effects
				(font
					(size 1 1)
					(thickness 0.15)
				)
			)
		)
		(property "Voltage" ""
			(at 0 0 0)
			(layer "F.Fab")
			(hide yes)
			(effects
				(font
					(size 1 1)
					(thickness 0.15)
				)
			)
		)
		(sheetname "Power supply")
		(sheetfile "power_supply.kicad_sch")
		(attr smd)
		(fp_line
			(start -0.3 -0.8)
			(end 0.3 -0.8)
			(stroke
				(width 0.15)
				(type solid)
			)
			(layer "F.SilkS")
		)
		(fp_line
			(start -0.3 0.8)
			(end 0.3 0.8)
			(stroke
				(width 0.15)
				(type solid)
			)
			(layer "F.SilkS")
		)
		(fp_rect
			(start -1.9 -0.93)
			(end 1.9 0.93)
			(stroke
				(width 0.05)
				(type solid)
			)
			(fill no)
			(layer "F.CrtYd")
		)
		(fp_rect
			(start -0.95 -0.675)
			(end 0.95 0.675)
			(stroke
				(width 0.15)
				(type solid)
			)
			(fill no)
			(layer "F.Fab")
		)
		(pad "1" smd rect
			(at -1.05 0)
			(size 1.2 1.2)
			(layers "F.Cu" "F.Mask" "F.Paste")
			(net 14 "GND")
			(pintype "passive")
		)
		(pad "2" smd rect
			(at 1.05 0)
			(size 1.2 1.2)
			(layers "F.Cu" "F.Mask" "F.Paste")
			(net 5 "+5V")
			(pintype "passive")
		)
	)
	(footprint "antmicro-footprints:C_0603_1608Metric"
		(layer "F.Cu")
		(at 105.425 61.075 180)
		(descr "Capacitor SMD 0603")
		(tags "capacitor 0603")
		(property "Reference" "C14"
			(at 1 -1.35 0)
			(unlocked yes)
			(layer "F.SilkS")
			(effects
				(font
					(size 0.7 0.7)
					(thickness 0.15)
				)
				(justify right bottom)
			)
		)
		(property "Value" "C_22u_0603"
			(at -1.42757 1.770288 0)
			(layer "F.Fab")
			(effects
				(font
					(size 0.7 0.7)
					(thickness 0.15)
				)
				(justify right bottom)
			)
		)
		(property "Author" "Antmicro"
			(at 210.85 122.15 0)
			(layer "F.Fab")
			(hide yes)
			(effects
				(font
					(size 1 1)
					(thickness 0.15)
				)
			)
		)
		(property "Dielectric" ""
			(at 210.85 122.15 0)
			(layer "F.Fab")
			(hide yes)
			(effects
				(font
					(size 1 1)
					(thickness 0.15)
				)
			)
		)
		(property "License" "Apache-2.0"
			(at 210.85 122.15 0)
			(layer "F.Fab")
			(hide yes)
			(effects
				(font
					(size 1 1)
					(thickness 0.15)
				)
			)
		)
		(property "MPN" "GRM188R60J226MEA0D"
			(at 210.85 122.15 0)
			(layer "F.Fab")
			(hide yes)
			(effects
				(font
					(size 1 1)
					(thickness 0.15)
				)
			)
		)
		(property "Manufacturer" "Murata"
			(at 210.85 122.15 0)
			(layer "F.Fab")
			(hide yes)
			(effects
				(font
					(size 1 1)
					(thickness 0.15)
				)
			)
		)
		(property "Val" "22u"
			(at 210.85 122.15 0)
			(layer "F.Fab")
			(hide yes)
			(effects
				(font
					(size 1 1)
					(thickness 0.15)
				)
			)
		)
		(property "Voltage" ""
			(at 210.85 122.15 0)
			(layer "F.Fab")
			(hide yes)
			(effects
				(font
					(size 1 1)
					(thickness 0.15)
				)
			)
		)
		(sheetname "Power supply")
		(sheetfile "power_supply.kicad_sch")
		(attr smd)
		(fp_line
			(start -0.3 0.3)
			(end 0.3 0.3)
			(stroke
				(width 0.15)
				(type solid)
			)
			(layer "F.SilkS")
		)
		(fp_line
			(start -0.3 -0.3)
			(end 0.3 -0.3)
			(stroke
				(width 0.15)
				(type solid)
			)
			(layer "F.SilkS")
		)
		(fp_rect
			(start -1.24 -0.7)
			(end 1.24 0.7)
			(stroke
				(width 0.05)
				(type solid)
			)
			(fill no)
			(layer "F.CrtYd")
		)
		(fp_rect
			(start -0.8 -0.4)
			(end 0.8 0.4)
			(stroke
				(width 0.15)
				(type solid)
			)
			(fill no)
			(layer "F.Fab")
		)
		(pad "1" smd roundrect
			(at -0.7 0 180)
			(size 0.6 0.8)
			(layers "F.Cu" "F.Mask" "F.Paste")
			(roundrect_rratio 0.2)
			(net 14 "GND")
			(pintype "passive")
		)
		(pad "2" smd roundrect
			(at 0.7 0 180)
			(size 0.6 0.8)
			(layers "F.Cu" "F.Mask" "F.Paste")
			(roundrect_rratio 0.2)
			(net 7 "/Power supply/VOUT1")
			(pintype "passive")
		)
	)
	(footprint "antmicro-footprints:R_0402_1005Metric"
		(layer "F.Cu")
		(at 135.15 91.35 90)
		(descr "Resistor SMD 0402")
		(tags "resistor SMD 0402")
		(property "Reference" "R16"
			(at -1.122484 -0.772697 90)
			(unlocked yes)
			(layer "F.SilkS")
			(effects
				(font
					(size 0.7 0.7)
					(thickness 0.15)
				)
				(justify left bottom)
			)
		)
		(property "Value" "R_100R_0402"
			(at -1.011843 1.772047 90)
			(layer "F.Fab")
			(effects
				(font
					(size 0.7 0.7)
					(thickness 0.15)
				)
				(justify left bottom)
			)
		)
		(property "Author" "Antmicro"
			(at 226.5 -43.8 0)
			(layer "F.Fab")
			(hide yes)
			(effects
				(font
					(size 1 1)
					(thickness 0.15)
				)
			)
		)
		(property "License" "Apache-2.0"
			(at 226.5 -43.8 0)
			(layer "F.Fab")
			(hide yes)
			(effects
				(font
					(size 1 1)
					(thickness 0.15)
				)
			)
		)
		(property "MPN" "CR0402-FX-1000GLF"
			(at 226.5 -43.8 0)
			(layer "F.Fab")
			(hide yes)
			(effects
				(font
					(size 1 1)
					(thickness 0.15)
				)
			)
		)
		(property "Manufacturer" "Bourns"
			(at 226.5 -43.8 0)
			(layer "F.Fab")
			(hide yes)
			(effects
				(font
					(size 1 1)
					(thickness 0.15)
				)
			)
		)
		(property "Tolerance" "1%"
			(at 226.5 -43.8 0)
			(layer "F.Fab")
			(hide yes)
			(effects
				(font
					(size 1 1)
					(thickness 0.15)
				)
			)
		)
		(property "Val" "100R"
			(at 226.5 -43.8 0)
			(layer "F.Fab")
			(hide yes)
			(effects
				(font
					(size 1 1)
					(thickness 0.15)
				)
			)
		)
		(sheetname "Translators")
		(sheetfile "translators.kicad_sch")
		(attr smd)
		(fp_rect
			(start -0.93 -0.47)
			(end 0.93 0.47)
			(stroke
				(width 0.05)
				(type solid)
			)
			(fill no)
			(layer "F.CrtYd")
		)
		(fp_rect
			(start -0.5 -0.25)
			(end 0.5 0.25)
			(stroke
				(width 0.15)
				(type solid)
			)
			(fill no)
			(layer "F.Fab")
		)
		(pad "1" smd roundrect
			(at -0.485 0 90)
			(size 0.59 0.64)
			(layers "F.Cu" "F.Mask" "F.Paste")
			(roundrect_rratio 0.25)
			(net 156 "/SODIMM/LPDDR5_IN_A.CK_P")
			(pintype "passive")
		)
		(pad "2" smd roundrect
			(at 0.485 0 90)
			(size 0.59 0.64)
			(layers "F.Cu" "F.Mask" "F.Paste")
			(roundrect_rratio 0.25)
			(net 49 "/LPDDR5/LPDDR5_A.CK_P")
			(pintype "passive")
		)
	)
	(footprint "antmicro-footprints:R_0402_1005Metric"
		(layer "F.Cu")
		(at 103.2875 72.725 180)
		(descr "Resistor SMD 0402")
		(tags "resistor SMD 0402")
		(property "Reference" "R39"
			(at -0.9125 -2.475 0)
			(unlocked yes)
			(layer "F.SilkS")
			(effects
				(font
					(size 0.7 0.7)
					(thickness 0.15)
				)
				(justify right bottom)
			)
		)
		(property "Value" "R_100k_0402"
			(at -1.011843 1.772047 0)
			(layer "F.Fab")
			(effects
				(font
					(size 0.7 0.7)
					(thickness 0.15)
				)
				(justify right bottom)
			)
		)
		(property "Author" "Antmicro"
			(at 206.575 145.45 0)
			(layer "F.Fab")
			(hide yes)
			(effects
				(font
					(size 1 1)
					(thickness 0.15)
				)
			)
		)
		(property "License" "Apache-2.0"
			(at 206.575 145.45 0)
			(layer "F.Fab")
			(hide yes)
			(effects
				(font
					(size 1 1)
					(thickness 0.15)
				)
			)
		)
		(property "MPN" "CR0402-FX-1003GLF"
			(at 206.575 145.45 0)
			(layer "F.Fab")
			(hide yes)
			(effects
				(font
					(size 1 1)
					(thickness 0.15)
				)
			)
		)
		(property "Manufacturer" "Bourns"
			(at 206.575 145.45 0)
			(layer "F.Fab")
			(hide yes)
			(effects
				(font
					(size 1 1)
					(thickness 0.15)
				)
			)
		)
		(property "Tolerance" "1%"
			(at 206.575 145.45 0)
			(layer "F.Fab")
			(hide yes)
			(effects
				(font
					(size 1 1)
					(thickness 0.15)
				)
			)
		)
		(property "Val" "100k"
			(at 206.575 145.45 0)
			(layer "F.Fab")
			(hide yes)
			(effects
				(font
					(size 1 1)
					(thickness 0.15)
				)
			)
		)
		(sheetname "Power supply")
		(sheetfile "power_supply.kicad_sch")
		(attr smd)
		(fp_rect
			(start -0.93 -0.47)
			(end 0.93 0.47)
			(stroke
				(width 0.05)
				(type solid)
			)
			(fill no)
			(layer "F.CrtYd")
		)
		(fp_rect
			(start -0.5 -0.25)
			(end 0.5 0.25)
			(stroke
				(width 0.15)
				(type solid)
			)
			(fill no)
			(layer "F.Fab")
		)
		(pad "1" smd roundrect
			(at -0.485 0 180)
			(size 0.59 0.64)
			(layers "F.Cu" "F.Mask" "F.Paste")
			(roundrect_rratio 0.25)
			(net 73 "/Power supply/FB4")
			(pintype "passive")
		)
		(pad "2" smd roundrect
			(at 0.485 0 180)
			(size 0.59 0.64)
			(layers "F.Cu" "F.Mask" "F.Paste")
			(roundrect_rratio 0.25)
			(net 10 "/Power supply/VOUT4")
			(pintype "passive")
		)
	)
	(footprint "antmicro-footprints:R_0402_1005Metric"
		(layer "F.Cu")
		(at 167.575 66.45 180)
		(descr "Resistor SMD 0402")
		(tags "resistor SMD 0402")
		(property "Reference" "R50"
			(at -1.125 -9.05 0)
			(unlocked yes)
			(layer "F.SilkS")
			(effects
				(font
					(size 0.7 0.7)
					(thickness 0.15)
				)
				(justify right bottom)
			)
		)
		(property "Value" "R_3k9_0402"
			(at -1.011843 1.772047 0)
			(layer "F.Fab")
			(effects
				(font
					(size 0.7 0.7)
					(thickness 0.15)
				)
				(justify right bottom)
			)
		)
		(property "Author" "Antmicro"
			(at 335.15 132.9 0)
			(layer "F.Fab")
			(hide yes)
			(effects
				(font
					(size 1 1)
					(thickness 0.15)
				)
			)
		)
		(property "License" "Apache-2.0"
			(at 335.15 132.9 0)
			(layer "F.Fab")
			(hide yes)
			(effects
				(font
					(size 1 1)
					(thickness 0.15)
				)
			)
		)
		(property "MPN" "CR0402-FX-3901GLF"
			(at 335.15 132.9 0)
			(layer "F.Fab")
			(hide yes)
			(effects
				(font
					(size 1 1)
					(thickness 0.15)
				)
			)
		)
		(property "Manufacturer" "Bourns"
			(at 335.15 132.9 0)
			(layer "F.Fab")
			(hide yes)
			(effects
				(font
					(size 1 1)
					(thickness 0.15)
				)
			)
		)
		(property "Tolerance" "1%"
			(at 335.15 132.9 0)
			(layer "F.Fab")
			(hide yes)
			(effects
				(font
					(size 1 1)
					(thickness 0.15)
				)
			)
		)
		(property "Val" "3k9"
			(at 335.15 132.9 0)
			(layer "F.Fab")
			(hide yes)
			(effects
				(font
					(size 1 1)
					(thickness 0.15)
				)
			)
		)
		(sheetname "Power supply")
		(sheetfile "power_supply.kicad_sch")
		(attr smd)
		(fp_rect
			(start -0.93 -0.47)
			(end 0.93 0.47)
			(stroke
				(width 0.05)
				(type solid)
			)
			(fill no)
			(layer "F.CrtYd")
		)
		(fp_rect
			(start -0.5 -0.25)
			(end 0.5 0.25)
			(stroke
				(width 0.15)
				(type solid)
			)
			(fill no)
			(layer "F.Fab")
		)
		(pad "1" smd roundrect
			(at -0.485 0 180)
			(size 0.59 0.64)
			(layers "F.Cu" "F.Mask" "F.Paste")
			(roundrect_rratio 0.25)
			(net 14 "GND")
			(pintype "passive")
		)
		(pad "2" smd roundrect
			(at 0.485 0 180)
			(size 0.59 0.64)
			(layers "F.Cu" "F.Mask" "F.Paste")
			(roundrect_rratio 0.25)
			(net 52 "Net-(POT1-Pad2)")
			(pintype "passive")
		)
	)
	(footprint "antmicro-footprints:R_0402_1005Metric"
		(layer "F.Cu")
		(at 101.7875 66.225 90)
		(descr "Resistor SMD 0402")
		(tags "resistor SMD 0402")
		(property "Reference" "R34"
			(at 0.825 0.4125 90)
			(unlocked yes)
			(layer "F.SilkS")
			(effects
				(font
					(size 0.7 0.7)
					(thickness 0.15)
				)
				(justify left bottom)
			)
		)
		(property "Value" "R_49k9_0402"
			(at -1.011843 1.772047 90)
			(layer "F.Fab")
			(effects
				(font
					(size 0.7 0.7)
					(thickness 0.15)
				)
				(justify left bottom)
			)
		)
		(property "Author" "Antmicro"
			(at 168.0125 -35.5625 0)
			(layer "F.Fab")
			(hide yes)
			(effects
				(font
					(size 1 1)
					(thickness 0.15)
				)
			)
		)
		(property "License" "Apache-2.0"
			(at 168.0125 -35.5625 0)
			(layer "F.Fab")
			(hide yes)
			(effects
				(font
					(size 1 1)
					(thickness 0.15)
				)
			)
		)
		(property "MPN" "CR0402-FX-4992GLF"
			(at 168.0125 -35.5625 0)
			(layer "F.Fab")
			(hide yes)
			(effects
				(font
					(size 1 1)
					(thickness 0.15)
				)
			)
		)
		(property "Manufacturer" "Bourns"
			(at 168.0125 -35.5625 0)
			(layer "F.Fab")
			(hide yes)
			(effects
				(font
					(size 1 1)
					(thickness 0.15)
				)
			)
		)
		(property "Tolerance" "1%"
			(at 168.0125 -35.5625 0)
			(layer "F.Fab")
			(hide yes)
			(effects
				(font
					(size 1 1)
					(thickness 0.15)
				)
			)
		)
		(property "Val" "49k9"
			(at 168.0125 -35.5625 0)
			(layer "F.Fab")
			(hide yes)
			(effects
				(font
					(size 1 1)
					(thickness 0.15)
				)
			)
		)
		(sheetname "Power supply")
		(sheetfile "power_supply.kicad_sch")
		(attr smd)
		(fp_rect
			(start -0.93 -0.47)
			(end 0.93 0.47)
			(stroke
				(width 0.05)
				(type solid)
			)
			(fill no)
			(layer "F.CrtYd")
		)
		(fp_rect
			(start -0.5 -0.25)
			(end 0.5 0.25)
			(stroke
				(width 0.15)
				(type solid)
			)
			(fill no)
			(layer "F.Fab")
		)
		(pad "1" smd roundrect
			(at -0.485 0 90)
			(size 0.59 0.64)
			(layers "F.Cu" "F.Mask" "F.Paste")
			(roundrect_rratio 0.25)
			(net 70 "/Power supply/FB1")
			(pintype "passive")
		)
		(pad "2" smd roundrect
			(at 0.485 0 90)
			(size 0.59 0.64)
			(layers "F.Cu" "F.Mask" "F.Paste")
			(roundrect_rratio 0.25)
			(net 14 "GND")
			(pintype "passive")
		)
	)
	(footprint "antmicro-footprints:R_0402_1005Metric"
		(layer "F.Cu")
		(at 146.05 93.8 90)
		(descr "Resistor SMD 0402")
		(tags "resistor SMD 0402")
		(property "Reference" "R1"
			(at -0.975 1.4 90)
			(layer "F.SilkS")
			(effects
				(font
					(size 0.7 0.7)
					(thickness 0.15)
				)
				(justify left bottom)
			)
		)
		(property "Value" "R_0R_0402"
			(at -1.011843 1.772047 90)
			(layer "F.Fab")
			(effects
				(font
					(size 0.7 0.7)
					(thickness 0.15)
				)
				(justify left bottom)
			)
		)
		(property "Author" "Antmicro"
			(at 239.85 -52.25 0)
			(layer "F.Fab")
			(hide yes)
			(effects
				(font
					(size 1 1)
					(thickness 0.15)
				)
			)
		)
		(property "Current" "1A"
			(at 239.85 -52.25 0)
			(layer "F.Fab")
			(hide yes)
			(effects
				(font
					(size 1 1)
					(thickness 0.15)
				)
			)
		)
		(property "License" "Apache-2.0"
			(at 239.85 -52.25 0)
			(layer "F.Fab")
			(hide yes)
			(effects
				(font
					(size 1 1)
					(thickness 0.15)
				)
			)
		)
		(property "MPN" "ERJ2GE0R00X"
			(at 239.85 -52.25 0)
			(layer "F.Fab")
			(hide yes)
			(effects
				(font
					(size 1 1)
					(thickness 0.15)
				)
			)
		)
		(property "Manufacturer" "Panasonic"
			(at 239.85 -52.25 0)
			(layer "F.Fab")
			(hide yes)
			(effects
				(font
					(size 1 1)
					(thickness 0.15)
				)
			)
		)
		(property "Tolerance" ""
			(at 239.85 -52.25 0)
			(layer "F.Fab")
			(hide yes)
			(effects
				(font
					(size 1 1)
					(thickness 0.15)
				)
			)
		)
		(property "Val" "0R"
			(at 239.85 -52.25 0)
			(layer "F.Fab")
			(hide yes)
			(effects
				(font
					(size 1 1)
					(thickness 0.15)
				)
			)
		)
		(sheetfile "lpddr5-testbed.kicad_sch")
		(attr smd)
		(fp_rect
			(start -0.93 -0.47)
			(end 0.93 0.47)
			(stroke
				(width 0.05)
				(type solid)
			)
			(fill no)
			(layer "F.CrtYd")
		)
		(fp_rect
			(start -0.5 -0.25)
			(end 0.5 0.25)
			(stroke
				(width 0.15)
				(type solid)
			)
			(fill no)
			(layer "F.Fab")
		)
		(pad "1" smd roundrect
			(at -0.485 0 90)
			(size 0.59 0.64)
			(layers "F.Cu" "F.Mask" "F.Paste")
			(roundrect_rratio 0.25)
			(net 34 "/SODIMM/~{RESET}")
			(pintype "passive")
		)
		(pad "2" smd roundrect
			(at 0.485 0 90)
			(size 0.59 0.64)
			(layers "F.Cu" "F.Mask" "F.Paste")
			(roundrect_rratio 0.25)
			(net 40 "/LPDDR5/~{RESET}")
			(pintype "passive")
		)
	)
	(footprint "antmicro-footprints:C_0402_1005Metric"
		(layer "F.Cu")
		(at 135.875 72.25 180)
		(descr "Capacitor SMD 0402")
		(tags "capacitor SMD 0402")
		(property "Reference" "C65"
			(at -3.125 -0.45 0)
			(unlocked yes)
			(layer "F.SilkS")
			(effects
				(font
					(size 0.7 0.7)
					(thickness 0.15)
				)
				(justify right bottom)
			)
		)
		(property "Value" "C_4u7_0402"
			(at -1.022927 2.155213 0)
			(layer "F.Fab")
			(effects
				(font
					(size 0.7 0.7)
					(thickness 0.15)
				)
				(justify right bottom)
			)
		)
		(property "Author" "Antmicro"
			(at 271.75 144.5 0)
			(layer "F.Fab")
			(hide yes)
			(effects
				(font
					(size 1 1)
					(thickness 0.15)
				)
			)
		)
		(property "Dielectric" ""
			(at 271.75 144.5 0)
			(layer "F.Fab")
			(hide yes)
			(effects
				(font
					(size 1 1)
					(thickness 0.15)
				)
			)
		)
		(property "License" "Apache-2.0"
			(at 271.75 144.5 0)
			(layer "F.Fab")
			(hide yes)
			(effects
				(font
					(size 1 1)
					(thickness 0.15)
				)
			)
		)
		(property "MPN" "GRM155R61A475MEAAD"
			(at 271.75 144.5 0)
			(layer "F.Fab")
			(hide yes)
			(effects
				(font
					(size 1 1)
					(thickness 0.15)
				)
			)
		)
		(property "Manufacturer" "Murata"
			(at 271.75 144.5 0)
			(layer "F.Fab")
			(hide yes)
			(effects
				(font
					(size 1 1)
					(thickness 0.15)
				)
			)
		)
		(property "Val" "4u7"
			(at 271.75 144.5 0)
			(layer "F.Fab")
			(hide yes)
			(effects
				(font
					(size 1 1)
					(thickness 0.15)
				)
			)
		)
		(property "Voltage" ""
			(at 271.75 144.5 0)
			(layer "F.Fab")
			(hide yes)
			(effects
				(font
					(size 1 1)
					(thickness 0.15)
				)
			)
		)
		(sheetname "LPDDR5")
		(sheetfile "lpddr5.kicad_sch")
		(attr smd)
		(fp_rect
			(start -0.9659 -0.481258)
			(end 0.9649 0.458742)
			(stroke
				(width 0.05)
				(type solid)
			)
			(fill no)
			(layer "F.CrtYd")
		)
		(fp_line
			(start 0.499 0.248)
			(end -0.499 0.248)
			(stroke
				(width 0.15)
				(type solid)
			)
			(layer "F.Fab")
		)
		(fp_line
			(start 0.499 -0.25)
			(end 0.499 0.248)
			(stroke
				(width 0.15)
				(type solid)
			)
			(layer "F.Fab")
		)
		(fp_line
			(start -0.499 0.248)
			(end -0.499 -0.25)
			(stroke
				(width 0.15)
				(type solid)
			)
			(layer "F.Fab")
		)
		(fp_line
			(start -0.499 -0.25)
			(end 0.499 -0.25)
			(stroke
				(width 0.15)
				(type solid)
			)
			(layer "F.Fab")
		)
		(pad "1" smd roundrect
			(at -0.484 0 180)
			(size 0.59 0.64)
			(layers "F.Cu" "F.Mask" "F.Paste")
			(roundrect_rratio 0.25)
			(net 14 "GND")
			(pintype "passive")
		)
		(pad "2" smd roundrect
			(at 0.484 0 180)
			(size 0.59 0.64)
			(layers "F.Cu" "F.Mask" "F.Paste")
			(roundrect_rratio 0.25)
			(net 13 "+1V05")
			(pintype "passive")
		)
	)
	(footprint "antmicro-footprints:LGA-33_7x7mm_P0.65mm"
		(layer "F.Cu")
		(at 106.6375 67.85 180)
		(property "Reference" "U8"
			(at -4.1625 3.55 0)
			(unlocked yes)
			(layer "F.SilkS")
			(effects
				(font
					(size 0.7 0.7)
					(thickness 0.15)
				)
				(justify left bottom)
			)
		)
		(property "Value" "MPM54304GMN-0001"
			(at 0 5 180)
			(layer "F.Fab")
			(effects
				(font
					(size 0.7 0.7)
					(thickness 0.15)
				)
				(justify left bottom)
			)
		)
		(property "Author" "Antmicro"
			(at 213.275 135.7 0)
			(layer "F.Fab")
			(hide yes)
			(effects
				(font
					(size 1 1)
					(thickness 0.15)
				)
			)
		)
		(property "License" "Apache-2.0"
			(at 213.275 135.7 0)
			(layer "F.Fab")
			(hide yes)
			(effects
				(font
					(size 1 1)
					(thickness 0.15)
				)
			)
		)
		(property "MPN" "MPM54304GMN-0001"
			(at 213.275 135.7 0)
			(layer "F.Fab")
			(hide yes)
			(effects
				(font
					(size 1 1)
					(thickness 0.15)
				)
			)
		)
		(property "Manufacturer" "Monolithic Power Systems"
			(at 213.275 135.7 0)
			(layer "F.Fab")
			(hide yes)
			(effects
				(font
					(size 1 1)
					(thickness 0.15)
				)
			)
		)
		(sheetname "Power supply")
		(sheetfile "power_supply.kicad_sch")
		(solder_paste_margin_ratio -0.1)
		(attr smd)
		(fp_line
			(start 3.648 3.648)
			(end 3.648 2.922)
			(stroke
				(width 0.15)
				(type solid)
			)
			(layer "F.SilkS")
		)
		(fp_line
			(start 3.648 -3.65)
			(end 3.648 -2.926)
			(stroke
				(width 0.15)
				(type solid)
			)
			(layer "F.SilkS")
		)
		(fp_line
			(start 2.922 3.648)
			(end 3.648 3.648)
			(stroke
				(width 0.15)
				(type solid)
			)
			(layer "F.SilkS")
		)
		(fp_line
			(start 2.922 -3.65)
			(end 3.648 -3.65)
			(stroke
				(width 0.15)
				(type solid)
			)
			(layer "F.SilkS")
		)
		(fp_line
			(start -2.926 3.648)
			(end -3.65 3.648)
			(stroke
				(width 0.15)
				(type solid)
			)
			(layer "F.SilkS")
		)
		(fp_line
			(start -3.65 3.648)
			(end -3.65 2.922)
			(stroke
				(width 0.15)
				(type solid)
			)
			(layer "F.SilkS")
		)
		(fp_line
			(start -3.665 -2.928)
			(end -3.665 -3.653)
			(stroke
				(width 0.15)
				(type solid)
			)
			(layer "F.SilkS")
		)
		(fp_line
			(start -3.665 -3.653)
			(end -2.94 -3.653)
			(stroke
				(width 0.15)
				(type solid)
			)
			(layer "F.SilkS")
		)
		(fp_circle
			(center -3.8 -1.925)
			(end -3.75 -1.925)
			(stroke
				(width 0.15)
				(type solid)
			)
			(fill yes)
			(layer "F.SilkS")
		)
		(fp_rect
			(start -4 -4)
			(end 3.999 3.999)
			(stroke
				(width 0.05)
				(type solid)
			)
			(fill no)
			(layer "F.CrtYd")
		)
		(fp_line
			(start 3.499 3.499)
			(end 3.499 -3.5)
			(stroke
				(width 0.15)
				(type solid)
			)
			(layer "F.Fab")
		)
		(fp_line
			(start 3.499 -3.5)
			(end -3.5 -3.5)
			(stroke
				(width 0.15)
				(type solid)
			)
			(layer "F.Fab")
		)
		(fp_line
			(start -3.101 -3.5)
			(end -3.5 -3.101)
			(stroke
				(width 0.15)
				(type solid)
			)
			(layer "F.Fab")
		)
		(fp_line
			(start -3.5 3.499)
			(end 3.499 3.499)
			(stroke
				(width 0.15)
				(type solid)
			)
			(layer "F.Fab")
		)
		(fp_line
			(start -3.5 -3.5)
			(end -3.5 3.499)
			(stroke
				(width 0.15)
				(type solid)
			)
			(layer "F.Fab")
		)
		(pad "1" smd rect
			(at -3.138 -1.625 270)
			(size 0.3 1.125)
			(layers "F.Cu" "F.Mask" "F.Paste")
			(net 9 "/Power supply/VOUT3")
			(pinfunction "VOUT3")
			(pintype "power_out")
		)
		(pad "2" smd rect
			(at -3.138 -0.975 270)
			(size 0.3 1.125)
			(layers "F.Cu" "F.Mask" "F.Paste")
			(net 14 "GND")
			(pinfunction "GND")
			(pintype "passive")
		)
		(pad "3" smd rect
			(at -3.138 -0.328 270)
			(size 0.3 1.125)
			(layers "F.Cu" "F.Mask" "F.Paste")
			(net 38 "/Power supply/I2C.SDA")
			(pinfunction "SDA")
			(pintype "bidirectional")
		)
		(pad "4" smd rect
			(at -3.138 0.325 270)
			(size 0.3 1.125)
			(layers "F.Cu" "F.Mask" "F.Paste")
			(net 39 "/Power supply/I2C.SCL")
			(pinfunction "SCL")
			(pintype "input")
		)
		(pad "5" smd rect
			(at -3.138 0.972 270)
			(size 0.3 1.125)
			(layers "F.Cu" "F.Mask" "F.Paste")
			(net 14 "GND")
			(pinfunction "GND")
			(pintype "passive")
		)
		(pad "6" smd rect
			(at -3.138 1.624 270)
			(size 0.3 1.125)
			(layers "F.Cu" "F.Mask" "F.Paste")
			(net 71 "/Power supply/FB2")
			(pinfunction "FB2")
			(pintype "input")
		)
		(pad "7" smd rect
			(at -2.926 3.136)
			(size 0.3 1.125)
			(layers "F.Cu" "F.Mask" "F.Paste")
			(net 14 "GND")
			(pinfunction "GND")
			(pintype "passive")
		)
		(pad "8" smd rect
			(at -2.275 3.136)
			(size 0.3 1.125)
			(layers "F.Cu" "F.Mask" "F.Paste")
			(net 8 "/Power supply/VOUT2")
			(pinfunction "VOUT2")
			(pintype "power_out")
		)
		(pad "9" smd rect
			(at -1.625 3.136 180)
			(size 0.3 1.125)
			(layers "F.Cu" "F.Mask" "F.Paste")
			(net 8 "/Power supply/VOUT2")
			(pinfunction "VOUT2")
			(pintype "passive")
		)
		(pad "10" smd rect
			(at -0.975 3.136 180)
			(size 0.3 1.125)
			(layers "F.Cu" "F.Mask" "F.Paste")
			(net 14 "GND")
			(pinfunction "GND")
			(pintype "passive")
		)
		(pad "11" smd rect
			(at -0.328 3.136 180)
			(size 0.3 1.125)
			(layers "F.Cu" "F.Mask" "F.Paste")
			(net 114 "unconnected-(U8-Pad11)")
			(pinfunction "SW2")
			(pintype "power_out+no_connect")
		)
		(pad "12" smd rect
			(at 0.325 3.136 180)
			(size 0.3 1.125)
			(layers "F.Cu" "F.Mask" "F.Paste")
			(net 115 "unconnected-(U8-Pad12)")
			(pinfunction "SW1")
			(pintype "power_out+no_connect")
		)
		(pad "13" smd rect
			(at 0.972 3.136 180)
			(size 0.3 1.125)
			(layers "F.Cu" "F.Mask" "F.Paste")
			(net 14 "GND")
			(pinfunction "GND")
			(pintype "passive")
		)
		(pad "14" smd rect
			(at 1.624 3.136 180)
			(size 0.3 1.125)
			(layers "F.Cu" "F.Mask" "F.Paste")
			(net 7 "/Power supply/VOUT1")
			(pinfunction "VOUT1")
			(pintype "power_out")
		)
		(pad "15" smd rect
			(at 2.273 3.136 180)
			(size 0.3 1.125)
			(layers "F.Cu" "F.Mask" "F.Paste")
			(net 7 "/Power supply/VOUT1")
			(pinfunction "VOUT1")
			(pintype "passive")
		)
		(pad "16" smd rect
			(at 2.922 3.136 180)
			(size 0.3 1.125)
			(layers "F.Cu" "F.Mask" "F.Paste")
			(net 14 "GND")
			(pinfunction "GND")
			(pintype "passive")
		)
		(pad "17" smd rect
			(at 3.136 1.624 270)
			(size 0.3 1.125)
			(layers "F.Cu" "F.Mask" "F.Paste")
			(net 14 "GND")
			(pinfunction "SGND1")
			(pintype "power_out")
		)
		(pad "18" smd rect
			(at 3.136 0.972 270)
			(size 0.3 1.125)
			(layers "F.Cu" "F.Mask" "F.Paste")
			(net 70 "/Power supply/FB1")
			(pinfunction "FB1")
			(pintype "input")
		)
		(pad "19" smd rect
			(at 3.136 0.325 270)
			(size 0.3 1.125)
			(layers "F.Cu" "F.Mask" "F.Paste")
			(net 20 "/Power supply/PWR_EN")
			(pinfunction "EN/SYNCI")
			(pintype "input")
		)
		(pad "20" smd rect
			(at 3.136 -0.328 270)
			(size 0.3 1.125)
			(layers "F.Cu" "F.Mask" "F.Paste")
			(net 14 "GND")
			(pinfunction "GND")
			(pintype "passive")
		)
		(pad "21" smd rect
			(at 3.136 -0.975 270)
			(size 0.3 1.125)
			(layers "F.Cu" "F.Mask" "F.Paste")
			(net 14 "GND")
			(pinfunction "GND")
			(pintype "passive")
		)
		(pad "22" smd rect
			(at 3.136 -1.625 270)
			(size 0.3 1.125)
			(layers "F.Cu" "F.Mask" "F.Paste")
			(net 10 "/Power supply/VOUT4")
			(pinfunction "VOUT4")
			(pintype "power_out")
		)
		(pad "23" smd rect
			(at 2.922 -3.138)
			(size 0.3 1.125)
			(layers "F.Cu" "F.Mask" "F.Paste")
			(net 10 "/Power supply/VOUT4")
			(pinfunction "VOUT4")
			(pintype "passive")
		)
		(pad "24" smd rect
			(at 2.273 -3.138)
			(size 0.3 1.125)
			(layers "F.Cu" "F.Mask" "F.Paste")
			(net 73 "/Power supply/FB4")
			(pinfunction "FB4")
			(pintype "input")
		)
		(pad "25" smd rect
			(at 1.624 -3.138 180)
			(size 0.3 1.125)
			(layers "F.Cu" "F.Mask" "F.Paste")
			(net 117 "Net-(C12-Pad2)")
			(pinfunction "VCC")
			(pintype "input")
		)
		(pad "26" smd rect
			(at 0.972 -3.138 180)
			(size 0.3 1.125)
			(layers "F.Cu" "F.Mask" "F.Paste")
			(net 228 "/Power supply/DCDC_PWRGD")
			(pinfunction "GPIO")
			(pintype "input")
		)
		(pad "27" smd rect
			(at 0.325 -3.138 180)
			(size 0.3 1.125)
			(layers "F.Cu" "F.Mask" "F.Paste")
			(net 14 "GND")
			(pinfunction "GND")
			(pintype "passive")
		)
		(pad "28" smd rect
			(at -0.328 -3.138 180)
			(size 0.3 1.125)
			(layers "F.Cu" "F.Mask" "F.Paste")
			(net 5 "+5V")
			(pinfunction "VIN")
			(pintype "input")
		)
		(pad "29" smd rect
			(at -0.975 -3.138 180)
			(size 0.3 1.125)
			(layers "F.Cu" "F.Mask" "F.Paste")
			(net 5 "+5V")
			(pinfunction "VIN")
			(pintype "passive")
		)
		(pad "30" smd rect
			(at -1.625 -3.138 180)
			(size 0.3 1.125)
			(layers "F.Cu" "F.Mask" "F.Paste")
			(net 14 "GND")
			(pinfunction "SGND2")
			(pintype "power_out")
		)
		(pad "31" smd rect
			(at -2.275 -3.138 180)
			(size 0.3 1.125)
			(layers "F.Cu" "F.Mask" "F.Paste")
			(net 72 "/Power supply/FB3")
			(pinfunction "FB3")
			(pintype "input")
		)
		(pad "32" smd rect
			(at -2.926 -3.138 180)
			(size 0.3 1.125)
			(layers "F.Cu" "F.Mask" "F.Paste")
			(net 9 "/Power supply/VOUT3")
			(pinfunction "VOUT3")
			(pintype "passive")
		)
		(pad "33" smd rect
			(at -0.863 -0.863 180)
			(size 1.725 1.725)
			(layers "F.Cu" "F.Mask" "F.Paste")
			(net 14 "GND")
			(pinfunction "GND")
			(pintype "passive")
			(solder_paste_margin -0.1)
		)
		(pad "33" smd rect
			(at -0.863 0.86 180)
			(size 1.725 1.725)
			(layers "F.Cu" "F.Mask" "F.Paste")
			(net 14 "GND")
			(pinfunction "GND")
			(pintype "passive")
			(solder_paste_margin -0.1)
		)
		(pad "33" smd rect
			(at 0.86 -0.863 180)
			(size 1.725 1.725)
			(layers "F.Cu" "F.Mask" "F.Paste")
			(net 14 "GND")
			(pinfunction "GND")
			(pintype "passive")
			(solder_paste_margin -0.1)
		)
		(pad "33" smd rect
			(at 0.86 0.86 180)
			(size 1.725 1.725)
			(layers "F.Cu" "F.Mask" "F.Paste")
			(net 14 "GND")
			(pinfunction "GND")
			(pintype "passive")
			(solder_paste_margin -0.1)
		)
	)
	(footprint "antmicro-footprints:R_0603_1608Metric"
		(layer "F.Cu")
		(at 160.175 67.35)
		(descr "Resistor SMD 0603")
		(tags "resistor SMD 0603")
		(property "Reference" "R52"
			(at -3.575 0.45 0)
			(unlocked yes)
			(layer "F.SilkS")
			(effects
				(font
					(size 0.7 0.7)
					(thickness 0.15)
				)
				(justify left bottom)
			)
		)
		(property "Value" "R_0R_22.4A_0603"
			(at 0 1.6 0)
			(layer "F.Fab")
			(effects
				(font
					(size 0.7 0.7)
					(thickness 0.15)
				)
				(justify left bottom)
			)
		)
		(property "Author" "Antmicro"
			(at 0 0 0)
			(layer "F.Fab")
			(hide yes)
			(effects
				(font
					(size 1 1)
					(thickness 0.15)
				)
			)
		)
		(property "License" "Apache-2.0"
			(at 0 0 0)
			(layer "F.Fab")
			(hide yes)
			(effects
				(font
					(size 1 1)
					(thickness 0.15)
				)
			)
		)
		(property "MPN" "PMR03EZPJ000"
			(at 0 0 0)
			(layer "F.Fab")
			(hide yes)
			(effects
				(font
					(size 1 1)
					(thickness 0.15)
				)
			)
		)
		(property "Manufacturer" "ROHM Semiconductor"
			(at 0 0 0)
			(layer "F.Fab")
			(hide yes)
			(effects
				(font
					(size 1 1)
					(thickness 0.15)
				)
			)
		)
		(property "Max. Curr." "22.4A"
			(at 0 0 0)
			(layer "F.Fab")
			(hide yes)
			(effects
				(font
					(size 1 1)
					(thickness 0.15)
				)
			)
		)
		(property "Tolerance" "template_tolerance"
			(at 0 0 0)
			(layer "F.Fab")
			(hide yes)
			(effects
				(font
					(size 1 1)
					(thickness 0.15)
				)
			)
		)
		(property "Val" "0R"
			(at 0 0 0)
			(layer "F.Fab")
			(hide yes)
			(effects
				(font
					(size 1 1)
					(thickness 0.15)
				)
			)
		)
		(sheetname "Power supply")
		(sheetfile "power_supply.kicad_sch")
		(attr smd)
		(fp_line
			(start -0.3 -0.3)
			(end 0.3 -0.3)
			(stroke
				(width 0.15)
				(type solid)
			)
			(layer "F.SilkS")
		)
		(fp_line
			(start -0.3 0.3)
			(end 0.3 0.3)
			(stroke
				(width 0.15)
				(type solid)
			)
			(layer "F.SilkS")
		)
		(fp_rect
			(start -1.25 -0.7)
			(end 1.25 0.7)
			(stroke
				(width 0.05)
				(type solid)
			)
			(fill no)
			(layer "F.CrtYd")
		)
		(fp_rect
			(start -0.8 -0.4)
			(end 0.8 0.4)
			(stroke
				(width 0.15)
				(type solid)
			)
			(fill no)
			(layer "F.Fab")
		)
		(pad "1" smd roundrect
			(at -0.7 0)
			(size 0.6 0.8)
			(layers "F.Cu" "F.Mask" "F.Paste")
			(roundrect_rratio 0.2)
			(net 4 "+0V5")
			(pintype "passive")
		)
		(pad "2" smd roundrect
			(at 0.7 0)
			(size 0.6 0.8)
			(layers "F.Cu" "F.Mask" "F.Paste")
			(roundrect_rratio 0.2)
			(net 11 "/Power supply/VOUT")
			(pintype "passive")
		)
	)
	(footprint "antmicro-footprints:R_Array_4x0402_Panasonic_EXB28V"
		(layer "F.Cu")
		(at 108.85 93.8)
		(property "Reference" "R10"
			(at -1.301 -1.45 0)
			(unlocked yes)
			(layer "F.SilkS")
			(effects
				(font
					(size 0.7 0.7)
					(thickness 0.15)
				)
				(justify left bottom)
			)
		)
		(property "Value" "R_4x100R_0402_array"
			(at -1.5 2 0)
			(layer "F.Fab")
			(effects
				(font
					(size 0.7 0.7)
					(thickness 0.15)
				)
				(justify left bottom)
			)
		)
		(property "Author" "Antmicro"
			(at 0 0 0)
			(layer "F.Fab")
			(hide yes)
			(effects
				(font
					(size 1 1)
					(thickness 0.15)
				)
			)
		)
		(property "License" "Apache-2.0"
			(at 0 0 0)
			(layer "F.Fab")
			(hide yes)
			(effects
				(font
					(size 1 1)
					(thickness 0.15)
				)
			)
		)
		(property "MPN" "EXB-28V101JX"
			(at 0 0 0)
			(layer "F.Fab")
			(hide yes)
			(effects
				(font
					(size 1 1)
					(thickness 0.15)
				)
			)
		)
		(property "Manufacturer" "Panasonic"
			(at 0 0 0)
			(layer "F.Fab")
			(hide yes)
			(effects
				(font
					(size 1 1)
					(thickness 0.15)
				)
			)
		)
		(property "Val" "R_4x100R_0402"
			(at 0 0 0)
			(layer "F.Fab")
			(hide yes)
			(effects
				(font
					(size 1 1)
					(thickness 0.15)
				)
			)
		)
		(sheetname "Translators")
		(sheetfile "translators.kicad_sch")
		(attr smd)
		(fp_line
			(start -1.25 -0.5)
			(end -1.25 0.498)
			(stroke
				(width 0.15)
				(type solid)
			)
			(layer "F.SilkS")
		)
		(fp_line
			(start 1.25 0.499)
			(end 1.25 -0.499)
			(stroke
				(width 0.15)
				(type solid)
			)
			(layer "F.SilkS")
		)
		(fp_rect
			(start -1.25 -0.8)
			(end 1.25 0.8)
			(stroke
				(width 0.05)
				(type solid)
			)
			(fill no)
			(layer "F.CrtYd")
		)
		(fp_line
			(start -1 -0.5)
			(end 0.998 -0.5)
			(stroke
				(width 0.15)
				(type solid)
			)
			(layer "F.Fab")
		)
		(fp_line
			(start -1 0.498)
			(end -1 -0.5)
			(stroke
				(width 0.15)
				(type solid)
			)
			(layer "F.Fab")
		)
		(fp_line
			(start 0.998 -0.5)
			(end 0.998 0.498)
			(stroke
				(width 0.15)
				(type solid)
			)
			(layer "F.Fab")
		)
		(fp_line
			(start 0.998 0.498)
			(end -1 0.498)
			(stroke
				(width 0.15)
				(type solid)
			)
			(layer "F.Fab")
		)
		(pad "1" smd roundrect
			(at -0.8875 0.45)
			(size 0.525 0.5)
			(layers "F.Cu" "F.Mask" "F.Paste")
			(roundrect_rratio 0.25)
			(net 177 "/SODIMM/LPDDR5_IN_A.DQ15")
			(pinfunction "R1.1")
			(pintype "passive")
		)
		(pad "2" smd roundrect
			(at -0.25 0.45)
			(size 0.25 0.5)
			(layers "F.Cu" "F.Mask" "F.Paste")
			(roundrect_rratio 0.25)
			(net 180 "/SODIMM/LPDDR5_IN_A.DQ14")
			(pinfunction "R2.1")
			(pintype "passive")
		)
		(pad "3" smd roundrect
			(at 0.25 0.45)
			(size 0.25 0.5)
			(layers "F.Cu" "F.Mask" "F.Paste")
			(roundrect_rratio 0.25)
			(net 178 "/SODIMM/LPDDR5_IN_A.DQ12")
			(pinfunction "R3.1")
			(pintype "passive")
		)
		(pad "4" smd roundrect
			(at 0.8875 0.45)
			(size 0.525 0.5)
			(layers "F.Cu" "F.Mask" "F.Paste")
			(roundrect_rratio 0.25)
			(net 179 "/SODIMM/LPDDR5_IN_A.DQ13")
			(pinfunction "R4.1")
			(pintype "passive")
		)
		(pad "5" smd roundrect
			(at 0.8875 -0.45)
			(size 0.525 0.5)
			(layers "F.Cu" "F.Mask" "F.Paste")
			(roundrect_rratio 0.25)
			(net 194 "/LPDDR5/LPDDR5_A.DQ13")
			(pinfunction "R4.2")
			(pintype "passive")
		)
		(pad "6" smd roundrect
			(at 0.25 -0.45)
			(size 0.25 0.5)
			(layers "F.Cu" "F.Mask" "F.Paste")
			(roundrect_rratio 0.25)
			(net 193 "/LPDDR5/LPDDR5_A.DQ12")
			(pinfunction "R3.2")
			(pintype "passive")
		)
		(pad "7" smd roundrect
			(at -0.25 -0.45)
			(size 0.25 0.5)
			(layers "F.Cu" "F.Mask" "F.Paste")
			(roundrect_rratio 0.25)
			(net 192 "/LPDDR5/LPDDR5_A.DQ14")
			(pinfunction "R2.2")
			(pintype "passive")
		)
		(pad "8" smd roundrect
			(at -0.8875 -0.45)
			(size 0.525 0.5)
			(layers "F.Cu" "F.Mask" "F.Paste")
			(roundrect_rratio 0.25)
			(net 191 "/LPDDR5/LPDDR5_A.DQ15")
			(pinfunction "R1.2")
			(pintype "passive")
		)
	)
	(footprint "antmicro-footprints:TP_SMD_0.75mm"
		(layer "F.Cu")
		(at 112.1 71.7)
		(property "Reference" "TP6"
			(at 2.5 2.5 0)
			(unlocked yes)
			(layer "F.SilkS")
			(effects
				(font
					(size 0.7 0.7)
					(thickness 0.15)
				)
				(justify left bottom)
			)
		)
		(property "Value" "TP_0.75mm_SMD"
			(at 0 1.2 0)
			(layer "F.Fab")
			(effects
				(font
					(size 0.7 0.7)
					(thickness 0.15)
				)
				(justify left bottom)
			)
		)
		(property "Author" "Antmicro"
			(at 0 0 0)
			(layer "F.Fab")
			(hide yes)
			(effects
				(font
					(size 1 1)
					(thickness 0.15)
				)
			)
		)
		(property "License" "Apache-2.0"
			(at 0 0 0)
			(layer "F.Fab")
			(hide yes)
			(effects
				(font
					(size 1 1)
					(thickness 0.15)
				)
			)
		)
		(property "MPN" ""
			(at 0 0 0)
			(layer "F.Fab")
			(hide yes)
			(effects
				(font
					(size 1 1)
					(thickness 0.15)
				)
			)
		)
		(property "Manufacturer" ""
			(at 0 0 0)
			(layer "F.Fab")
			(hide yes)
			(effects
				(font
					(size 1 1)
					(thickness 0.15)
				)
			)
		)
		(sheetname "Power supply")
		(sheetfile "power_supply.kicad_sch")
		(attr exclude_from_pos_files)
		(pad "1" smd circle
			(at 0 0)
			(size 0.75 0.75)
			(layers "F.Cu" "F.Mask")
			(net 9 "/Power supply/VOUT3")
			(pinfunction "1")
			(pintype "passive")
		)
	)
	(footprint "antmicro-footprints:C_0603_1608Metric"
		(layer "F.Cu")
		(at 101.4875 69.725 -90)
		(descr "Capacitor SMD 0603")
		(tags "capacitor 0603")
		(property "Reference" "C19"
			(at -1.325 -0.8125 0)
			(unlocked yes)
			(layer "F.SilkS")
			(effects
				(font
					(size 0.7 0.7)
					(thickness 0.15)
				)
				(justify right bottom)
			)
		)
		(property "Value" "C_22u_0603"
			(at -1.42757 1.770288 90)
			(layer "F.Fab")
			(effects
				(font
					(size 0.7 0.7)
					(thickness 0.15)
				)
				(justify right bottom)
			)
		)
		(property "Author" "Antmicro"
			(at 31.7625 171.2125 0)
			(layer "F.Fab")
			(hide yes)
			(effects
				(font
					(size 1 1)
					(thickness 0.15)
				)
			)
		)
		(property "Dielectric" ""
			(at 31.7625 171.2125 0)
			(layer "F.Fab")
			(hide yes)
			(effects
				(font
					(size 1 1)
					(thickness 0.15)
				)
			)
		)
		(property "License" "Apache-2.0"
			(at 31.7625 171.2125 0)
			(layer "F.Fab")
			(hide yes)
			(effects
				(font
					(size 1 1)
					(thickness 0.15)
				)
			)
		)
		(property "MPN" "GRM188R60J226MEA0D"
			(at 31.7625 171.2125 0)
			(layer "F.Fab")
			(hide yes)
			(effects
				(font
					(size 1 1)
					(thickness 0.15)
				)
			)
		)
		(property "Manufacturer" "Murata"
			(at 31.7625 171.2125 0)
			(layer "F.Fab")
			(hide yes)
			(effects
				(font
					(size 1 1)
					(thickness 0.15)
				)
			)
		)
		(property "Val" "22u"
			(at 31.7625 171.2125 0)
			(layer "F.Fab")
			(hide yes)
			(effects
				(font
					(size 1 1)
					(thickness 0.15)
				)
			)
		)
		(property "Voltage" ""
			(at 31.7625 171.2125 0)
			(layer "F.Fab")
			(hide yes)
			(effects
				(font
					(size 1 1)
					(thickness 0.15)
				)
			)
		)
		(sheetname "Power supply")
		(sheetfile "power_supply.kicad_sch")
		(attr smd)
		(fp_line
			(start -0.3 0.3)
			(end 0.3 0.3)
			(stroke
				(width 0.15)
				(type solid)
			)
			(layer "F.SilkS")
		)
		(fp_line
			(start -0.3 -0.3)
			(end 0.3 -0.3)
			(stroke
				(width 0.15)
				(type solid)
			)
			(layer "F.SilkS")
		)
		(fp_rect
			(start -1.24 -0.7)
			(end 1.24 0.7)
			(stroke
				(width 0.05)
				(type solid)
			)
			(fill no)
			(layer "F.CrtYd")
		)
		(fp_rect
			(start -0.8 -0.4)
			(end 0.8 0.4)
			(stroke
				(width 0.15)
				(type solid)
			)
			(fill no)
			(layer "F.Fab")
		)
		(pad "1" smd roundrect
			(at -0.7 0 270)
			(size 0.6 0.8)
			(layers "F.Cu" "F.Mask" "F.Paste")
			(roundrect_rratio 0.2)
			(net 14 "GND")
			(pintype "passive")
		)
		(pad "2" smd roundrect
			(at 0.7 0 270)
			(size 0.6 0.8)
			(layers "F.Cu" "F.Mask" "F.Paste")
			(roundrect_rratio 0.2)
			(net 10 "/Power supply/VOUT4")
			(pintype "passive")
		)
	)
	(footprint "antmicro-footprints:R_0402_1005Metric"
		(layer "F.Cu")
		(at 167.125 69 90)
		(descr "Resistor SMD 0402")
		(tags "resistor SMD 0402")
		(property "Reference" "R32"
			(at -9.7 0.275 90)
			(unlocked yes)
			(layer "F.SilkS")
			(effects
				(font
					(size 0.7 0.7)
					(thickness 0.15)
				)
				(justify left bottom)
			)
		)
		(property "Value" "R_25k5_0402"
			(at -1.011843 1.772047 90)
			(layer "F.Fab")
			(effects
				(font
					(size 0.7 0.7)
					(thickness 0.15)
				)
				(justify left bottom)
			)
		)
		(property "Author" "Antmicro"
			(at 236.125 -98.125 0)
			(layer "F.Fab")
			(hide yes)
			(effects
				(font
					(size 1 1)
					(thickness 0.15)
				)
			)
		)
		(property "License" "Apache-2.0"
			(at 236.125 -98.125 0)
			(layer "F.Fab")
			(hide yes)
			(effects
				(font
					(size 1 1)
					(thickness 0.15)
				)
			)
		)
		(property "MPN" "CR0402-FX-2552GLF"
			(at 236.125 -98.125 0)
			(layer "F.Fab")
			(hide yes)
			(effects
				(font
					(size 1 1)
					(thickness 0.15)
				)
			)
		)
		(property "Manufacturer" "Bourns"
			(at 236.125 -98.125 0)
			(layer "F.Fab")
			(hide yes)
			(effects
				(font
					(size 1 1)
					(thickness 0.15)
				)
			)
		)
		(property "Tolerance" "1%"
			(at 236.125 -98.125 0)
			(layer "F.Fab")
			(hide yes)
			(effects
				(font
					(size 1 1)
					(thickness 0.15)
				)
			)
		)
		(property "Val" "25k5"
			(at 236.125 -98.125 0)
			(layer "F.Fab")
			(hide yes)
			(effects
				(font
					(size 1 1)
					(thickness 0.15)
				)
			)
		)
		(sheetname "Power supply")
		(sheetfile "power_supply.kicad_sch")
		(attr smd)
		(fp_rect
			(start -0.93 -0.47)
			(end 0.93 0.47)
			(stroke
				(width 0.05)
				(type solid)
			)
			(fill no)
			(layer "F.CrtYd")
		)
		(fp_rect
			(start -0.5 -0.25)
			(end 0.5 0.25)
			(stroke
				(width 0.15)
				(type solid)
			)
			(fill no)
			(layer "F.Fab")
		)
		(pad "1" smd roundrect
			(at -0.485 0 90)
			(size 0.59 0.64)
			(layers "F.Cu" "F.Mask" "F.Paste")
			(roundrect_rratio 0.25)
			(net 14 "GND")
			(pintype "passive")
		)
		(pad "2" smd roundrect
			(at 0.485 0 90)
			(size 0.59 0.64)
			(layers "F.Cu" "F.Mask" "F.Paste")
			(roundrect_rratio 0.25)
			(net 69 "Net-(R32-Pad2)")
			(pintype "passive")
		)
	)
	(footprint "antmicro-footprints:R_0402_1005Metric"
		(layer "F.Cu")
		(at 131.675 72.275 180)
		(descr "Resistor SMD 0402")
		(tags "resistor SMD 0402")
		(property "Reference" "R69"
			(at 0.99 -0.475 0)
			(unlocked yes)
			(layer "F.SilkS")
			(effects
				(font
					(size 0.7 0.7)
					(thickness 0.15)
				)
				(justify right bottom)
			)
		)
		(property "Value" "R_240R_0402"
			(at -1.011843 1.772047 0)
			(layer "F.Fab")
			(effects
				(font
					(size 0.7 0.7)
					(thickness 0.15)
				)
				(justify right bottom)
			)
		)
		(property "Author" "Antmicro"
			(at 263.35 144.55 0)
			(layer "F.Fab")
			(hide yes)
			(effects
				(font
					(size 1 1)
					(thickness 0.15)
				)
			)
		)
		(property "License" "Apache-2.0"
			(at 263.35 144.55 0)
			(layer "F.Fab")
			(hide yes)
			(effects
				(font
					(size 1 1)
					(thickness 0.15)
				)
			)
		)
		(property "MPN" "CR0402-FX-2400GLF"
			(at 263.35 144.55 0)
			(layer "F.Fab")
			(hide yes)
			(effects
				(font
					(size 1 1)
					(thickness 0.15)
				)
			)
		)
		(property "Manufacturer" "Bourns"
			(at 263.35 144.55 0)
			(layer "F.Fab")
			(hide yes)
			(effects
				(font
					(size 1 1)
					(thickness 0.15)
				)
			)
		)
		(property "Tolerance" "1%"
			(at 263.35 144.55 0)
			(layer "F.Fab")
			(hide yes)
			(effects
				(font
					(size 1 1)
					(thickness 0.15)
				)
			)
		)
		(property "Val" "240R"
			(at 263.35 144.55 0)
			(layer "F.Fab")
			(hide yes)
			(effects
				(font
					(size 1 1)
					(thickness 0.15)
				)
			)
		)
		(sheetname "LPDDR5")
		(sheetfile "lpddr5.kicad_sch")
		(attr smd)
		(fp_rect
			(start -0.93 -0.47)
			(end 0.93 0.47)
			(stroke
				(width 0.05)
				(type solid)
			)
			(fill no)
			(layer "F.CrtYd")
		)
		(fp_rect
			(start -0.5 -0.25)
			(end 0.5 0.25)
			(stroke
				(width 0.15)
				(type solid)
			)
			(fill no)
			(layer "F.Fab")
		)
		(pad "1" smd roundrect
			(at -0.485 0 180)
			(size 0.59 0.64)
			(layers "F.Cu" "F.Mask" "F.Paste")
			(roundrect_rratio 0.25)
			(net 14 "GND")
			(pintype "passive")
		)
		(pad "2" smd roundrect
			(at 0.485 0 180)
			(size 0.59 0.64)
			(layers "F.Cu" "F.Mask" "F.Paste")
			(roundrect_rratio 0.25)
			(net 92 "Net-(R69-Pad2)")
			(pintype "passive")
		)
	)
	(footprint "antmicro-footprints:R_Array_4x0402_Panasonic_EXB28V"
		(layer "F.Cu")
		(at 144.2 93.8 180)
		(property "Reference" "R75"
			(at -1 1.4 0)
			(unlocked yes)
			(layer "F.SilkS")
			(effects
				(font
					(size 0.7 0.7)
					(thickness 0.15)
				)
				(justify right bottom)
			)
		)
		(property "Value" "R_4x100R_0402_array"
			(at -1.5 2 0)
			(layer "F.Fab")
			(effects
				(font
					(size 0.7 0.7)
					(thickness 0.15)
				)
				(justify right bottom)
			)
		)
		(property "Author" "Antmicro"
			(at 288.4 187.6 0)
			(layer "F.Fab")
			(hide yes)
			(effects
				(font
					(size 1 1)
					(thickness 0.15)
				)
			)
		)
		(property "License" "Apache-2.0"
			(at 288.4 187.6 0)
			(layer "F.Fab")
			(hide yes)
			(effects
				(font
					(size 1 1)
					(thickness 0.15)
				)
			)
		)
		(property "MPN" "EXB-28V101JX"
			(at 288.4 187.6 0)
			(layer "F.Fab")
			(hide yes)
			(effects
				(font
					(size 1 1)
					(thickness 0.15)
				)
			)
		)
		(property "Manufacturer" "Panasonic"
			(at 288.4 187.6 0)
			(layer "F.Fab")
			(hide yes)
			(effects
				(font
					(size 1 1)
					(thickness 0.15)
				)
			)
		)
		(property "Val" "R_4x100R_0402"
			(at 288.4 187.6 0)
			(layer "F.Fab")
			(hide yes)
			(effects
				(font
					(size 1 1)
					(thickness 0.15)
				)
			)
		)
		(sheetname "Translators1")
		(sheetfile "translators.kicad_sch")
		(attr smd)
		(fp_line
			(start 1.25 0.499)
			(end 1.25 -0.499)
			(stroke
				(width 0.15)
				(type solid)
			)
			(layer "F.SilkS")
		)
		(fp_line
			(start -1.25 -0.5)
			(end -1.25 0.498)
			(stroke
				(width 0.15)
				(type solid)
			)
			(layer "F.SilkS")
		)
		(fp_rect
			(start -1.25 -0.8)
			(end 1.25 0.8)
			(stroke
				(width 0.05)
				(type solid)
			)
			(fill no)
			(layer "F.CrtYd")
		)
		(fp_line
			(start 0.998 0.498)
			(end -1 0.498)
			(stroke
				(width 0.15)
				(type solid)
			)
			(layer "F.Fab")
		)
		(fp_line
			(start 0.998 -0.5)
			(end 0.998 0.498)
			(stroke
				(width 0.15)
				(type solid)
			)
			(layer "F.Fab")
		)
		(fp_line
			(start -1 0.498)
			(end -1 -0.5)
			(stroke
				(width 0.15)
				(type solid)
			)
			(layer "F.Fab")
		)
		(fp_line
			(start -1 -0.5)
			(end 0.998 -0.5)
			(stroke
				(width 0.15)
				(type solid)
			)
			(layer "F.Fab")
		)
		(pad "1" smd roundrect
			(at -0.8875 0.45 180)
			(size 0.525 0.5)
			(layers "F.Cu" "F.Mask" "F.Paste")
			(roundrect_rratio 0.25)
			(net 106 "/LPDDR5/LPDDR5_B.CS0")
			(pinfunction "R1.1")
			(pintype "passive")
		)
		(pad "2" smd roundrect
			(at -0.25 0.45 180)
			(size 0.25 0.5)
			(layers "F.Cu" "F.Mask" "F.Paste")
			(roundrect_rratio 0.25)
			(net 107 "/LPDDR5/LPDDR5_B.CS1")
			(pinfunction "R2.1")
			(pintype "passive")
		)
		(pad "3" smd roundrect
			(at 0.25 0.45 180)
			(size 0.25 0.5)
			(layers "F.Cu" "F.Mask" "F.Paste")
			(roundrect_rratio 0.25)
			(net 102 "/LPDDR5/LPDDR5_B.CA0")
			(pinfunction "R3.1")
			(pintype "passive")
		)
		(pad "4" smd roundrect
			(at 0.8875 0.45 180)
			(size 0.525 0.5)
			(layers "F.Cu" "F.Mask" "F.Paste")
			(roundrect_rratio 0.25)
			(net 103 "/LPDDR5/LPDDR5_B.CA1")
			(pinfunction "R4.1")
			(pintype "passive")
		)
		(pad "5" smd roundrect
			(at 0.8875 -0.45 180)
			(size 0.525 0.5)
			(layers "F.Cu" "F.Mask" "F.Paste")
			(roundrect_rratio 0.25)
			(net 14 "GND")
			(pinfunction "R4.2")
			(pintype "passive")
		)
		(pad "6" smd roundrect
			(at 0.25 -0.45 180)
			(size 0.25 0.5)
			(layers "F.Cu" "F.Mask" "F.Paste")
			(roundrect_rratio 0.25)
			(net 14 "GND")
			(pinfunction "R3.2")
			(pintype "passive")
		)
		(pad "7" smd roundrect
			(at -0.25 -0.45 180)
			(size 0.25 0.5)
			(layers "F.Cu" "F.Mask" "F.Paste")
			(roundrect_rratio 0.25)
			(net 14 "GND")
			(pinfunction "R2.2")
			(pintype "passive")
		)
		(pad "8" smd roundrect
			(at -0.8875 -0.45 180)
			(size 0.525 0.5)
			(layers "F.Cu" "F.Mask" "F.Paste")
			(roundrect_rratio 0.25)
			(net 14 "GND")
			(pinfunction "R1.2")
			(pintype "passive")
		)
	)
	(footprint "antmicro-footprints:C_0402_1005Metric"
		(layer "F.Cu")
		(at 164.475 70.65 180)
		(descr "Capacitor SMD 0402")
		(tags "capacitor SMD 0402")
		(property "Reference" "C20"
			(at -1.125 -2.45 0)
			(unlocked yes)
			(layer "F.SilkS")
			(effects
				(font
					(size 0.7 0.7)
					(thickness 0.15)
				)
				(justify right bottom)
			)
		)
		(property "Value" "C_4u7_0402"
			(at -1.022927 2.155213 0)
			(layer "F.Fab")
			(effects
				(font
					(size 0.7 0.7)
					(thickness 0.15)
				)
				(justify right bottom)
			)
		)
		(property "Author" "Antmicro"
			(at 328.95 141.3 0)
			(layer "F.Fab")
			(hide yes)
			(effects
				(font
					(size 1 1)
					(thickness 0.15)
				)
			)
		)
		(property "Dielectric" ""
			(at 328.95 141.3 0)
			(layer "F.Fab")
			(hide yes)
			(effects
				(font
					(size 1 1)
					(thickness 0.15)
				)
			)
		)
		(property "License" "Apache-2.0"
			(at 328.95 141.3 0)
			(layer "F.Fab")
			(hide yes)
			(effects
				(font
					(size 1 1)
					(thickness 0.15)
				)
			)
		)
		(property "MPN" "GRM155R61A475MEAAD"
			(at 328.95 141.3 0)
			(layer "F.Fab")
			(hide yes)
			(effects
				(font
					(size 1 1)
					(thickness 0.15)
				)
			)
		)
		(property "Manufacturer" "Murata"
			(at 328.95 141.3 0)
			(layer "F.Fab")
			(hide yes)
			(effects
				(font
					(size 1 1)
					(thickness 0.15)
				)
			)
		)
		(property "Val" "4u7"
			(at 328.95 141.3 0)
			(layer "F.Fab")
			(hide yes)
			(effects
				(font
					(size 1 1)
					(thickness 0.15)
				)
			)
		)
		(property "Voltage" ""
			(at 328.95 141.3 0)
			(layer "F.Fab")
			(hide yes)
			(effects
				(font
					(size 1 1)
					(thickness 0.15)
				)
			)
		)
		(sheetname "Power supply")
		(sheetfile "power_supply.kicad_sch")
		(attr smd)
		(fp_rect
			(start -0.9659 -0.481258)
			(end 0.9649 0.458742)
			(stroke
				(width 0.05)
				(type solid)
			)
			(fill no)
			(layer "F.CrtYd")
		)
		(fp_line
			(start 0.499 0.248)
			(end -0.499 0.248)
			(stroke
				(width 0.15)
				(type solid)
			)
			(layer "F.Fab")
		)
		(fp_line
			(start 0.499 -0.25)
			(end 0.499 0.248)
			(stroke
				(width 0.15)
				(type solid)
			)
			(layer "F.Fab")
		)
		(fp_line
			(start -0.499 0.248)
			(end -0.499 -0.25)
			(stroke
				(width 0.15)
				(type solid)
			)
			(layer "F.Fab")
		)
		(fp_line
			(start -0.499 -0.25)
			(end 0.499 -0.25)
			(stroke
				(width 0.15)
				(type solid)
			)
			(layer "F.Fab")
		)
		(pad "1" smd roundrect
			(at -0.484 0 180)
			(size 0.59 0.64)
			(layers "F.Cu" "F.Mask" "F.Paste")
			(roundrect_rratio 0.25)
			(net 14 "GND")
			(pintype "passive")
		)
		(pad "2" smd roundrect
			(at 0.484 0 180)
			(size 0.59 0.64)
			(layers "F.Cu" "F.Mask" "F.Paste")
			(roundrect_rratio 0.25)
			(net 11 "/Power supply/VOUT")
			(pintype "passive")
		)
	)
	(footprint "antmicro-footprints:C_0402_1005Metric"
		(layer "F.Cu")
		(at 135.875 88.275 180)
		(descr "Capacitor SMD 0402")
		(tags "capacitor SMD 0402")
		(property "Reference" "C67"
			(at -3.325 -0.25 0)
			(unlocked yes)
			(layer "F.SilkS")
			(effects
				(font
					(size 0.7 0.7)
					(thickness 0.15)
				)
				(justify right bottom)
			)
		)
		(property "Value" "C_4u7_0402"
			(at -1.022927 2.155213 0)
			(layer "F.Fab")
			(effects
				(font
					(size 0.7 0.7)
					(thickness 0.15)
				)
				(justify right bottom)
			)
		)
		(property "Author" "Antmicro"
			(at 271.75 176.55 0)
			(layer "F.Fab")
			(hide yes)
			(effects
				(font
					(size 1 1)
					(thickness 0.15)
				)
			)
		)
		(property "Dielectric" ""
			(at 271.75 176.55 0)
			(layer "F.Fab")
			(hide yes)
			(effects
				(font
					(size 1 1)
					(thickness 0.15)
				)
			)
		)
		(property "License" "Apache-2.0"
			(at 271.75 176.55 0)
			(layer "F.Fab")
			(hide yes)
			(effects
				(font
					(size 1 1)
					(thickness 0.15)
				)
			)
		)
		(property "MPN" "GRM155R61A475MEAAD"
			(at 271.75 176.55 0)
			(layer "F.Fab")
			(hide yes)
			(effects
				(font
					(size 1 1)
					(thickness 0.15)
				)
			)
		)
		(property "Manufacturer" "Murata"
			(at 271.75 176.55 0)
			(layer "F.Fab")
			(hide yes)
			(effects
				(font
					(size 1 1)
					(thickness 0.15)
				)
			)
		)
		(property "Val" "4u7"
			(at 271.75 176.55 0)
			(layer "F.Fab")
			(hide yes)
			(effects
				(font
					(size 1 1)
					(thickness 0.15)
				)
			)
		)
		(property "Voltage" ""
			(at 271.75 176.55 0)
			(layer "F.Fab")
			(hide yes)
			(effects
				(font
					(size 1 1)
					(thickness 0.15)
				)
			)
		)
		(sheetname "LPDDR5")
		(sheetfile "lpddr5.kicad_sch")
		(attr smd)
		(fp_rect
			(start -0.9659 -0.481258)
			(end 0.9649 0.458742)
			(stroke
				(width 0.05)
				(type solid)
			)
			(fill no)
			(layer "F.CrtYd")
		)
		(fp_line
			(start 0.499 0.248)
			(end -0.499 0.248)
			(stroke
				(width 0.15)
				(type solid)
			)
			(layer "F.Fab")
		)
		(fp_line
			(start 0.499 -0.25)
			(end 0.499 0.248)
			(stroke
				(width 0.15)
				(type solid)
			)
			(layer "F.Fab")
		)
		(fp_line
			(start -0.499 0.248)
			(end -0.499 -0.25)
			(stroke
				(width 0.15)
				(type solid)
			)
			(layer "F.Fab")
		)
		(fp_line
			(start -0.499 -0.25)
			(end 0.499 -0.25)
			(stroke
				(width 0.15)
				(type solid)
			)
			(layer "F.Fab")
		)
		(pad "1" smd roundrect
			(at -0.484 0 180)
			(size 0.59 0.64)
			(layers "F.Cu" "F.Mask" "F.Paste")
			(roundrect_rratio 0.25)
			(net 14 "GND")
			(pintype "passive")
		)
		(pad "2" smd roundrect
			(at 0.484 0 180)
			(size 0.59 0.64)
			(layers "F.Cu" "F.Mask" "F.Paste")
			(roundrect_rratio 0.25)
			(net 13 "+1V05")
			(pintype "passive")
		)
	)
	(footprint "antmicro-footprints:TP_SMD_0.75mm"
		(layer "F.Cu")
		(at 168.068 68.457 90)
		(property "Reference" "TP1"
			(at -1.443 1.332 90)
			(unlocked yes)
			(layer "F.SilkS")
			(effects
				(font
					(size 0.7 0.7)
					(thickness 0.15)
				)
				(justify left bottom)
			)
		)
		(property "Value" "TP_0.75mm_SMD"
			(at 0 1.2 90)
			(layer "F.Fab")
			(effects
				(font
					(size 0.7 0.7)
					(thickness 0.15)
				)
				(justify left bottom)
			)
		)
		(property "Author" "Antmicro"
			(at 236.525 -99.611 0)
			(layer "F.Fab")
			(hide yes)
			(effects
				(font
					(size 1 1)
					(thickness 0.15)
				)
			)
		)
		(property "License" "Apache-2.0"
			(at 236.525 -99.611 0)
			(layer "F.Fab")
			(hide yes)
			(effects
				(font
					(size 1 1)
					(thickness 0.15)
				)
			)
		)
		(property "MPN" ""
			(at 236.525 -99.611 0)
			(layer "F.Fab")
			(hide yes)
			(effects
				(font
					(size 1 1)
					(thickness 0.15)
				)
			)
		)
		(property "Manufacturer" ""
			(at 236.525 -99.611 0)
			(layer "F.Fab")
			(hide yes)
			(effects
				(font
					(size 1 1)
					(thickness 0.15)
				)
			)
		)
		(sheetname "Power supply")
		(sheetfile "power_supply.kicad_sch")
		(attr exclude_from_pos_files)
		(pad "1" smd circle
			(at 0 0 90)
			(size 0.75 0.75)
			(layers "F.Cu" "F.Mask")
			(net 69 "Net-(R32-Pad2)")
			(pinfunction "1")
			(pintype "passive")
		)
	)
	(footprint "antmicro-footprints:R_0402_1005Metric"
		(layer "F.Cu")
		(at 100.775 66.225 90)
		(descr "Resistor SMD 0402")
		(tags "resistor SMD 0402")
		(property "Reference" "R33"
			(at 0.825 0.425 90)
			(unlocked yes)
			(layer "F.SilkS")
			(effects
				(font
					(size 0.7 0.7)
					(thickness 0.15)
				)
				(justify left bottom)
			)
		)
		(property "Value" "R_100k_0402"
			(at -1.011843 1.772047 90)
			(layer "F.Fab")
			(effects
				(font
					(size 0.7 0.7)
					(thickness 0.15)
				)
				(justify left bottom)
			)
		)
		(property "Author" "Antmicro"
			(at 167 -34.55 0)
			(layer "F.Fab")
			(hide yes)
			(effects
				(font
					(size 1 1)
					(thickness 0.15)
				)
			)
		)
		(property "License" "Apache-2.0"
			(at 167 -34.55 0)
			(layer "F.Fab")
			(hide yes)
			(effects
				(font
					(size 1 1)
					(thickness 0.15)
				)
			)
		)
		(property "MPN" "CR0402-FX-1003GLF"
			(at 167 -34.55 0)
			(layer "F.Fab")
			(hide yes)
			(effects
				(font
					(size 1 1)
					(thickness 0.15)
				)
			)
		)
		(property "Manufacturer" "Bourns"
			(at 167 -34.55 0)
			(layer "F.Fab")
			(hide yes)
			(effects
				(font
					(size 1 1)
					(thickness 0.15)
				)
			)
		)
		(property "Tolerance" "1%"
			(at 167 -34.55 0)
			(layer "F.Fab")
			(hide yes)
			(effects
				(font
					(size 1 1)
					(thickness 0.15)
				)
			)
		)
		(property "Val" "100k"
			(at 167 -34.55 0)
			(layer "F.Fab")
			(hide yes)
			(effects
				(font
					(size 1 1)
					(thickness 0.15)
				)
			)
		)
		(sheetname "Power supply")
		(sheetfile "power_supply.kicad_sch")
		(attr smd)
		(fp_rect
			(start -0.93 -0.47)
			(end 0.93 0.47)
			(stroke
				(width 0.05)
				(type solid)
			)
			(fill no)
			(layer "F.CrtYd")
		)
		(fp_rect
			(start -0.5 -0.25)
			(end 0.5 0.25)
			(stroke
				(width 0.15)
				(type solid)
			)
			(fill no)
			(layer "F.Fab")
		)
		(pad "1" smd roundrect
			(at -0.485 0 90)
			(size 0.59 0.64)
			(layers "F.Cu" "F.Mask" "F.Paste")
			(roundrect_rratio 0.25)
			(net 70 "/Power supply/FB1")
			(pintype "passive")
		)
		(pad "2" smd roundrect
			(at 0.485 0 90)
			(size 0.59 0.64)
			(layers "F.Cu" "F.Mask" "F.Paste")
			(roundrect_rratio 0.25)
			(net 7 "/Power supply/VOUT1")
			(pintype "passive")
		)
	)
	(footprint "antmicro-footprints:R_0402_1005Metric"
		(layer "F.Cu")
		(at 107.125 93.775 90)
		(descr "Resistor SMD 0402")
		(tags "resistor SMD 0402")
		(property "Reference" "R20"
			(at -3.025 0.375 90)
			(unlocked yes)
			(layer "F.SilkS")
			(effects
				(font
					(size 0.7 0.7)
					(thickness 0.15)
				)
				(justify left bottom)
			)
		)
		(property "Value" "R_100R_0402"
			(at -1.011843 1.772047 90)
			(layer "F.Fab")
			(effects
				(font
					(size 0.7 0.7)
					(thickness 0.15)
				)
				(justify left bottom)
			)
		)
		(property "Author" "Antmicro"
			(at 200.9 -13.35 0)
			(layer "F.Fab")
			(hide yes)
			(effects
				(font
					(size 1 1)
					(thickness 0.15)
				)
			)
		)
		(property "License" "Apache-2.0"
			(at 200.9 -13.35 0)
			(layer "F.Fab")
			(hide yes)
			(effects
				(font
					(size 1 1)
					(thickness 0.15)
				)
			)
		)
		(property "MPN" "CR0402-FX-1000GLF"
			(at 200.9 -13.35 0)
			(layer "F.Fab")
			(hide yes)
			(effects
				(font
					(size 1 1)
					(thickness 0.15)
				)
			)
		)
		(property "Manufacturer" "Bourns"
			(at 200.9 -13.35 0)
			(layer "F.Fab")
			(hide yes)
			(effects
				(font
					(size 1 1)
					(thickness 0.15)
				)
			)
		)
		(property "Tolerance" "1%"
			(at 200.9 -13.35 0)
			(layer "F.Fab")
			(hide yes)
			(effects
				(font
					(size 1 1)
					(thickness 0.15)
				)
			)
		)
		(property "Val" "100R"
			(at 200.9 -13.35 0)
			(layer "F.Fab")
			(hide yes)
			(effects
				(font
					(size 1 1)
					(thickness 0.15)
				)
			)
		)
		(sheetname "Translators")
		(sheetfile "translators.kicad_sch")
		(attr smd)
		(fp_rect
			(start -0.93 -0.47)
			(end 0.93 0.47)
			(stroke
				(width 0.05)
				(type solid)
			)
			(fill no)
			(layer "F.CrtYd")
		)
		(fp_rect
			(start -0.5 -0.25)
			(end 0.5 0.25)
			(stroke
				(width 0.15)
				(type solid)
			)
			(fill no)
			(layer "F.Fab")
		)
		(pad "1" smd roundrect
			(at -0.485 0 90)
			(size 0.59 0.64)
			(layers "F.Cu" "F.Mask" "F.Paste")
			(roundrect_rratio 0.25)
			(net 118 "/SODIMM/LPDDR5_IN_A.DMI1")
			(pintype "passive")
		)
		(pad "2" smd roundrect
			(at 0.485 0 90)
			(size 0.59 0.64)
			(layers "F.Cu" "F.Mask" "F.Paste")
			(roundrect_rratio 0.25)
			(net 190 "/LPDDR5/LPDDR5_A.DMI1")
			(pintype "passive")
		)
	)
	(footprint "antmicro-footprints:R_0402_1005Metric"
		(layer "F.Cu")
		(at 139.75 93.85 90)
		(descr "Resistor SMD 0402")
		(tags "resistor SMD 0402")
		(property "Reference" "R89"
			(at 1.25 0.25 90)
			(unlocked yes)
			(layer "F.SilkS")
			(effects
				(font
					(size 0.7 0.7)
					(thickness 0.15)
				)
				(justify left bottom)
			)
		)
		(property "Value" "R_100R_0402"
			(at -1.011843 1.772047 90)
			(layer "F.Fab")
			(effects
				(font
					(size 0.7 0.7)
					(thickness 0.15)
				)
				(justify left bottom)
			)
		)
		(property "Author" "Antmicro"
			(at 233.6 -45.9 0)
			(layer "F.Fab")
			(hide yes)
			(effects
				(font
					(size 1 1)
					(thickness 0.15)
				)
			)
		)
		(property "License" "Apache-2.0"
			(at 233.6 -45.9 0)
			(layer "F.Fab")
			(hide yes)
			(effects
				(font
					(size 1 1)
					(thickness 0.15)
				)
			)
		)
		(property "MPN" "CR0402-FX-1000GLF"
			(at 233.6 -45.9 0)
			(layer "F.Fab")
			(hide yes)
			(effects
				(font
					(size 1 1)
					(thickness 0.15)
				)
			)
		)
		(property "Manufacturer" "Bourns"
			(at 233.6 -45.9 0)
			(layer "F.Fab")
			(hide yes)
			(effects
				(font
					(size 1 1)
					(thickness 0.15)
				)
			)
		)
		(property "Tolerance" "1%"
			(at 233.6 -45.9 0)
			(layer "F.Fab")
			(hide yes)
			(effects
				(font
					(size 1 1)
					(thickness 0.15)
				)
			)
		)
		(property "Val" "100R"
			(at 233.6 -45.9 0)
			(layer "F.Fab")
			(hide yes)
			(effects
				(font
					(size 1 1)
					(thickness 0.15)
				)
			)
		)
		(sheetname "Translators1")
		(sheetfile "translators.kicad_sch")
		(attr smd)
		(fp_rect
			(start -0.93 -0.47)
			(end 0.93 0.47)
			(stroke
				(width 0.05)
				(type solid)
			)
			(fill no)
			(layer "F.CrtYd")
		)
		(fp_rect
			(start -0.5 -0.25)
			(end 0.5 0.25)
			(stroke
				(width 0.15)
				(type solid)
			)
			(fill no)
			(layer "F.Fab")
		)
		(pad "1" smd roundrect
			(at -0.485 0 90)
			(size 0.59 0.64)
			(layers "F.Cu" "F.Mask" "F.Paste")
			(roundrect_rratio 0.25)
			(net 152 "/SODIMM/LPDDR5_IN_B.CA6")
			(pintype "passive")
		)
		(pad "2" smd roundrect
			(at 0.485 0 90)
			(size 0.59 0.64)
			(layers "F.Cu" "F.Mask" "F.Paste")
			(roundrect_rratio 0.25)
			(net 100 "/LPDDR5/LPDDR5_B.CA6")
			(pintype "passive")
		)
	)
	(footprint "antmicro-footprints:R_0402_1005Metric"
		(layer "F.Cu")
		(at 112.525 65.625 90)
		(descr "Resistor SMD 0402")
		(tags "resistor SMD 0402")
		(property "Reference" "R35"
			(at -3.075 0.375 90)
			(unlocked yes)
			(layer "F.SilkS")
			(effects
				(font
					(size 0.7 0.7)
					(thickness 0.15)
				)
				(justify left bottom)
			)
		)
		(property "Value" "R_100k_0402"
			(at -1.011843 1.772047 90)
			(layer "F.Fab")
			(effects
				(font
					(size 0.7 0.7)
					(thickness 0.15)
				)
				(justify left bottom)
			)
		)
		(property "Author" "Antmicro"
			(at 178.15 -46.9 0)
			(layer "F.Fab")
			(hide yes)
			(effects
				(font
					(size 1 1)
					(thickness 0.15)
				)
			)
		)
		(property "License" "Apache-2.0"
			(at 178.15 -46.9 0)
			(layer "F.Fab")
			(hide yes)
			(effects
				(font
					(size 1 1)
					(thickness 0.15)
				)
			)
		)
		(property "MPN" "CR0402-FX-1003GLF"
			(at 178.15 -46.9 0)
			(layer "F.Fab")
			(hide yes)
			(effects
				(font
					(size 1 1)
					(thickness 0.15)
				)
			)
		)
		(property "Manufacturer" "Bourns"
			(at 178.15 -46.9 0)
			(layer "F.Fab")
			(hide yes)
			(effects
				(font
					(size 1 1)
					(thickness 0.15)
				)
			)
		)
		(property "Tolerance" "1%"
			(at 178.15 -46.9 0)
			(layer "F.Fab")
			(hide yes)
			(effects
				(font
					(size 1 1)
					(thickness 0.15)
				)
			)
		)
		(property "Val" "100k"
			(at 178.15 -46.9 0)
			(layer "F.Fab")
			(hide yes)
			(effects
				(font
					(size 1 1)
					(thickness 0.15)
				)
			)
		)
		(sheetname "Power supply")
		(sheetfile "power_supply.kicad_sch")
		(attr smd)
		(fp_rect
			(start -0.93 -0.47)
			(end 0.93 0.47)
			(stroke
				(width 0.05)
				(type solid)
			)
			(fill no)
			(layer "F.CrtYd")
		)
		(fp_rect
			(start -0.5 -0.25)
			(end 0.5 0.25)
			(stroke
				(width 0.15)
				(type solid)
			)
			(fill no)
			(layer "F.Fab")
		)
		(pad "1" smd roundrect
			(at -0.485 0 90)
			(size 0.59 0.64)
			(layers "F.Cu" "F.Mask" "F.Paste")
			(roundrect_rratio 0.25)
			(net 71 "/Power supply/FB2")
			(pintype "passive")
		)
		(pad "2" smd roundrect
			(at 0.485 0 90)
			(size 0.59 0.64)
			(layers "F.Cu" "F.Mask" "F.Paste")
			(roundrect_rratio 0.25)
			(net 8 "/Power supply/VOUT2")
			(pintype "passive")
		)
	)
	(footprint "antmicro-footprints:R_0603_1608Metric"
		(layer "F.Cu")
		(at 101.5 72.275 90)
		(descr "Resistor SMD 0603")
		(tags "resistor SMD 0603")
		(property "Reference" "R46"
			(at -3.425 0 90)
			(unlocked yes)
			(layer "F.SilkS")
			(effects
				(font
					(size 0.7 0.7)
					(thickness 0.15)
				)
				(justify left bottom)
			)
		)
		(property "Value" "R_0R_22.4A_0603"
			(at 0 1.6 90)
			(layer "F.Fab")
			(effects
				(font
					(size 0.7 0.7)
					(thickness 0.15)
				)
				(justify left bottom)
			)
		)
		(property "Author" "Antmicro"
			(at 173.775 -29.225 0)
			(layer "F.Fab")
			(hide yes)
			(effects
				(font
					(size 1 1)
					(thickness 0.15)
				)
			)
		)
		(property "License" "Apache-2.0"
			(at 173.775 -29.225 0)
			(layer "F.Fab")
			(hide yes)
			(effects
				(font
					(size 1 1)
					(thickness 0.15)
				)
			)
		)
		(property "MPN" "PMR03EZPJ000"
			(at 173.775 -29.225 0)
			(layer "F.Fab")
			(hide yes)
			(effects
				(font
					(size 1 1)
					(thickness 0.15)
				)
			)
		)
		(property "Manufacturer" "ROHM Semiconductor"
			(at 173.775 -29.225 0)
			(layer "F.Fab")
			(hide yes)
			(effects
				(font
					(size 1 1)
					(thickness 0.15)
				)
			)
		)
		(property "Max. Curr." "22.4A"
			(at 173.775 -29.225 0)
			(layer "F.Fab")
			(hide yes)
			(effects
				(font
					(size 1 1)
					(thickness 0.15)
				)
			)
		)
		(property "Tolerance" "template_tolerance"
			(at 173.775 -29.225 0)
			(layer "F.Fab")
			(hide yes)
			(effects
				(font
					(size 1 1)
					(thickness 0.15)
				)
			)
		)
		(property "Val" "0R"
			(at 173.775 -29.225 0)
			(layer "F.Fab")
			(hide yes)
			(effects
				(font
					(size 1 1)
					(thickness 0.15)
				)
			)
		)
		(sheetname "Power supply")
		(sheetfile "power_supply.kicad_sch")
		(attr smd)
		(fp_line
			(start -0.3 -0.3)
			(end 0.3 -0.3)
			(stroke
				(width 0.15)
				(type solid)
			)
			(layer "F.SilkS")
		)
		(fp_line
			(start -0.3 0.3)
			(end 0.3 0.3)
			(stroke
				(width 0.15)
				(type solid)
			)
			(layer "F.SilkS")
		)
		(fp_rect
			(start -1.25 -0.7)
			(end 1.25 0.7)
			(stroke
				(width 0.05)
				(type solid)
			)
			(fill no)
			(layer "F.CrtYd")
		)
		(fp_rect
			(start -0.8 -0.4)
			(end 0.8 0.4)
			(stroke
				(width 0.15)
				(type solid)
			)
			(fill no)
			(layer "F.Fab")
		)
		(pad "1" smd roundrect
			(at -0.7 0 90)
			(size 0.6 0.8)
			(layers "F.Cu" "F.Mask" "F.Paste")
			(roundrect_rratio 0.2)
			(net 1 "+1V1")
			(pintype "passive")
		)
		(pad "2" smd roundrect
			(at 0.7 0 90)
			(size 0.6 0.8)
			(layers "F.Cu" "F.Mask" "F.Paste")
			(roundrect_rratio 0.2)
			(net 10 "/Power supply/VOUT4")
			(pintype "passive")
		)
	)
	(footprint "antmicro-footprints:R_0402_1005Metric"
		(layer "B.Cu")
		(at 115.68 92.02 180)
		(descr "Resistor SMD 0402")
		(tags "resistor SMD 0402")
		(property "Reference" "R94"
			(at 1.08 -0.38 0)
			(unlocked yes)
			(layer "B.SilkS")
			(effects
				(font
					(size 0.7 0.7)
					(thickness 0.15)
				)
				(justify left bottom mirror)
			)
		)
		(property "Value" "R_100R_0402"
			(at -1.011843 -1.772047 0)
			(layer "B.Fab")
			(effects
				(font
					(size 0.7 0.7)
					(thickness 0.15)
				)
				(justify left bottom mirror)
			)
		)
		(property "Author" "Antmicro"
			(at 231.36 184.04 0)
			(layer "B.Fab")
			(hide yes)
			(effects
				(font
					(size 1 1)
					(thickness 0.15)
				)
				(justify mirror)
			)
		)
		(property "License" "Apache-2.0"
			(at 231.36 184.04 0)
			(layer "B.Fab")
			(hide yes)
			(effects
				(font
					(size 1 1)
					(thickness 0.15)
				)
				(justify mirror)
			)
		)
		(property "MPN" "CR0402-FX-1000GLF"
			(at 231.36 184.04 0)
			(layer "B.Fab")
			(hide yes)
			(effects
				(font
					(size 1 1)
					(thickness 0.15)
				)
				(justify mirror)
			)
		)
		(property "Manufacturer" "Bourns"
			(at 231.36 184.04 0)
			(layer "B.Fab")
			(hide yes)
			(effects
				(font
					(size 1 1)
					(thickness 0.15)
				)
				(justify mirror)
			)
		)
		(property "Tolerance" "1%"
			(at 231.36 184.04 0)
			(layer "B.Fab")
			(hide yes)
			(effects
				(font
					(size 1 1)
					(thickness 0.15)
				)
				(justify mirror)
			)
		)
		(property "Val" "100R"
			(at 231.36 184.04 0)
			(layer "B.Fab")
			(hide yes)
			(effects
				(font
					(size 1 1)
					(thickness 0.15)
				)
				(justify mirror)
			)
		)
		(sheetname "Translators")
		(sheetfile "translators.kicad_sch")
		(attr smd)
		(fp_rect
			(start -0.93 0.47)
			(end 0.93 -0.47)
			(stroke
				(width 0.05)
				(type solid)
			)
			(fill no)
			(layer "B.CrtYd")
		)
		(fp_rect
			(start -0.5 0.25)
			(end 0.5 -0.25)
			(stroke
				(width 0.15)
				(type solid)
			)
			(fill no)
			(layer "B.Fab")
		)
		(pad "1" smd roundrect
			(at -0.485 0 180)
			(size 0.59 0.64)
			(layers "B.Cu" "B.Mask" "B.Paste")
			(roundrect_rratio 0.25)
			(net 201 "/LPDDR5/LPDDR5_A.DMI0")
			(pintype "passive")
		)
		(pad "2" smd roundrect
			(at 0.485 0 180)
			(size 0.59 0.64)
			(layers "B.Cu" "B.Mask" "B.Paste")
			(roundrect_rratio 0.25)
			(net 14 "GND")
			(pintype "passive")
		)
	)
	(footprint "antmicro-footprints:R_Array_4x0402_Panasonic_EXB28V"
		(layer "B.Cu")
		(at 130.3 93.8)
		(property "Reference" "R22"
			(at 1.1 -1.3 0)
			(unlocked yes)
			(layer "B.SilkS")
			(effects
				(font
					(size 0.7 0.7)
					(thickness 0.15)
				)
				(justify left bottom mirror)
			)
		)
		(property "Value" "R_4x100R_0402_array"
			(at -1.5 -2 180)
			(layer "B.Fab")
			(effects
				(font
					(size 0.7 0.7)
					(thickness 0.15)
				)
				(justify left bottom mirror)
			)
		)
		(property "Author" "Antmicro"
			(at 0 0 0)
			(layer "B.Fab")
			(hide yes)
			(effects
				(font
					(size 1 1)
					(thickness 0.15)
				)
				(justify mirror)
			)
		)
		(property "License" "Apache-2.0"
			(at 0 0 0)
			(layer "B.Fab")
			(hide yes)
			(effects
				(font
					(size 1 1)
					(thickness 0.15)
				)
				(justify mirror)
			)
		)
		(property "MPN" "EXB-28V101JX"
			(at 0 0 0)
			(layer "B.Fab")
			(hide yes)
			(effects
				(font
					(size 1 1)
					(thickness 0.15)
				)
				(justify mirror)
			)
		)
		(property "Manufacturer" "Panasonic"
			(at 0 0 0)
			(layer "B.Fab")
			(hide yes)
			(effects
				(font
					(size 1 1)
					(thickness 0.15)
				)
				(justify mirror)
			)
		)
		(property "Val" "R_4x100R_0402"
			(at 0 0 0)
			(layer "B.Fab")
			(hide yes)
			(effects
				(font
					(size 1 1)
					(thickness 0.15)
				)
				(justify mirror)
			)
		)
		(sheetname "Translators")
		(sheetfile "translators.kicad_sch")
		(attr smd)
		(fp_line
			(start -1.25 0.5)
			(end -1.25 -0.498)
			(stroke
				(width 0.15)
				(type solid)
			)
			(layer "B.SilkS")
		)
		(fp_line
			(start 1.25 -0.499)
			(end 1.25 0.499)
			(stroke
				(width 0.15)
				(type solid)
			)
			(layer "B.SilkS")
		)
		(fp_rect
			(start -1.25 0.8)
			(end 1.25 -0.8)
			(stroke
				(width 0.05)
				(type solid)
			)
			(fill no)
			(layer "B.CrtYd")
		)
		(fp_line
			(start -1 -0.498)
			(end -1 0.5)
			(stroke
				(width 0.15)
				(type solid)
			)
			(layer "B.Fab")
		)
		(fp_line
			(start -1 0.5)
			(end 0.998 0.5)
			(stroke
				(width 0.15)
				(type solid)
			)
			(layer "B.Fab")
		)
		(fp_line
			(start 0.998 -0.498)
			(end -1 -0.498)
			(stroke
				(width 0.15)
				(type solid)
			)
			(layer "B.Fab")
		)
		(fp_line
			(start 0.998 0.5)
			(end 0.998 -0.498)
			(stroke
				(width 0.15)
				(type solid)
			)
			(layer "B.Fab")
		)
		(pad "1" smd roundrect
			(at -0.8875 -0.45)
			(size 0.525 0.5)
			(layers "B.Cu" "B.Mask" "B.Paste")
			(roundrect_rratio 0.25)
			(net 59 "/LPDDR5/LPDDR5_A.CA2")
			(pinfunction "R1.1")
			(pintype "passive")
		)
		(pad "2" smd roundrect
			(at -0.25 -0.45)
			(size 0.25 0.5)
			(layers "B.Cu" "B.Mask" "B.Paste")
			(roundrect_rratio 0.25)
			(net 54 "/LPDDR5/LPDDR5_A.CA3")
			(pinfunction "R2.1")
			(pintype "passive")
		)
		(pad "3" smd roundrect
			(at 0.25 -0.45)
			(size 0.25 0.5)
			(layers "B.Cu" "B.Mask" "B.Paste")
			(roundrect_rratio 0.25)
			(net 60 "/LPDDR5/LPDDR5_A.CA4")
			(pinfunction "R3.1")
			(pintype "passive")
		)
		(pad "4" smd roundrect
			(at 0.8875 -0.45)
			(size 0.525 0.5)
			(layers "B.Cu" "B.Mask" "B.Paste")
			(roundrect_rratio 0.25)
			(net 56 "/LPDDR5/LPDDR5_A.CA5")
			(pinfunction "R4.1")
			(pintype "passive")
		)
		(pad "5" smd roundrect
			(at 0.8875 0.45)
			(size 0.525 0.5)
			(layers "B.Cu" "B.Mask" "B.Paste")
			(roundrect_rratio 0.25)
			(net 14 "GND")
			(pinfunction "R4.2")
			(pintype "passive")
		)
		(pad "6" smd roundrect
			(at 0.25 0.45)
			(size 0.25 0.5)
			(layers "B.Cu" "B.Mask" "B.Paste")
			(roundrect_rratio 0.25)
			(net 14 "GND")
			(pinfunction "R3.2")
			(pintype "passive")
		)
		(pad "7" smd roundrect
			(at -0.25 0.45)
			(size 0.25 0.5)
			(layers "B.Cu" "B.Mask" "B.Paste")
			(roundrect_rratio 0.25)
			(net 14 "GND")
			(pinfunction "R2.2")
			(pintype "passive")
		)
		(pad "8" smd roundrect
			(at -0.8875 0.45)
			(size 0.525 0.5)
			(layers "B.Cu" "B.Mask" "B.Paste")
			(roundrect_rratio 0.25)
			(net 14 "GND")
			(pinfunction "R1.2")
			(pintype "passive")
		)
	)
	(footprint "antmicro-footprints:C_0402_1005Metric"
		(layer "B.Cu")
		(at 138.775 81.45 180)
		(descr "Capacitor SMD 0402")
		(tags "capacitor SMD 0402")
		(property "Reference" "C69"
			(at -1.125 0.55 0)
			(unlocked yes)
			(layer "B.SilkS")
			(effects
				(font
					(size 0.7 0.7)
					(thickness 0.15)
				)
				(justify left bottom mirror)
			)
		)
		(property "Value" "C_4u7_0402"
			(at -1.022927 -2.155213 0)
			(layer "B.Fab")
			(effects
				(font
					(size 0.7 0.7)
					(thickness 0.15)
				)
				(justify left bottom mirror)
			)
		)
		(property "Author" "Antmicro"
			(at 277.55 162.9 0)
			(layer "B.Fab")
			(hide yes)
			(effects
				(font
					(size 1 1)
					(thickness 0.15)
				)
				(justify mirror)
			)
		)
		(property "Dielectric" ""
			(at 277.55 162.9 0)
			(layer "B.Fab")
			(hide yes)
			(effects
				(font
					(size 1 1)
					(thickness 0.15)
				)
				(justify mirror)
			)
		)
		(property "License" "Apache-2.0"
			(at 277.55 162.9 0)
			(layer "B.Fab")
			(hide yes)
			(effects
				(font
					(size 1 1)
					(thickness 0.15)
				)
				(justify mirror)
			)
		)
		(property "MPN" "GRM155R61A475MEAAD"
			(at 277.55 162.9 0)
			(layer "B.Fab")
			(hide yes)
			(effects
				(font
					(size 1 1)
					(thickness 0.15)
				)
				(justify mirror)
			)
		)
		(property "Manufacturer" "Murata"
			(at 277.55 162.9 0)
			(layer "B.Fab")
			(hide yes)
			(effects
				(font
					(size 1 1)
					(thickness 0.15)
				)
				(justify mirror)
			)
		)
		(property "Val" "4u7"
			(at 277.55 162.9 0)
			(layer "B.Fab")
			(hide yes)
			(effects
				(font
					(size 1 1)
					(thickness 0.15)
				)
				(justify mirror)
			)
		)
		(property "Voltage" ""
			(at 277.55 162.9 0)
			(layer "B.Fab")
			(hide yes)
			(effects
				(font
					(size 1 1)
					(thickness 0.15)
				)
				(justify mirror)
			)
		)
		(sheetname "LPDDR5")
		(sheetfile "lpddr5.kicad_sch")
		(attr smd)
		(fp_rect
			(start -0.9659 0.481258)
			(end 0.9649 -0.458742)
			(stroke
				(width 0.05)
				(type solid)
			)
			(fill no)
			(layer "B.CrtYd")
		)
		(fp_line
			(start 0.499 0.25)
			(end 0.499 -0.248)
			(stroke
				(width 0.15)
				(type solid)
			)
			(layer "B.Fab")
		)
		(fp_line
			(start 0.499 -0.248)
			(end -0.499 -0.248)
			(stroke
				(width 0.15)
				(type solid)
			)
			(layer "B.Fab")
		)
		(fp_line
			(start -0.499 0.25)
			(end 0.499 0.25)
			(stroke
				(width 0.15)
				(type solid)
			)
			(layer "B.Fab")
		)
		(fp_line
			(start -0.499 -0.248)
			(end -0.499 0.25)
			(stroke
				(width 0.15)
				(type solid)
			)
			(layer "B.Fab")
		)
		(pad "1" smd roundrect
			(at -0.484 0 180)
			(size 0.59 0.64)
			(layers "B.Cu" "B.Mask" "B.Paste")
			(roundrect_rratio 0.25)
			(net 14 "GND")
			(pintype "passive")
		)
		(pad "2" smd roundrect
			(at 0.484 0 180)
			(size 0.59 0.64)
			(layers "B.Cu" "B.Mask" "B.Paste")
			(roundrect_rratio 0.25)
			(net 13 "+1V05")
			(pintype "passive")
		)
	)
	(footprint "antmicro-footprints:R_0402_1005Metric"
		(layer "B.Cu")
		(at 106.63 90.97 90)
		(descr "Resistor SMD 0402")
		(tags "resistor SMD 0402")
		(property "Reference" "R13"
			(at -0.13 -2.63 0)
			(unlocked yes)
			(layer "B.SilkS")
			(effects
				(font
					(size 0.7 0.7)
					(thickness 0.15)
				)
				(justify right bottom mirror)
			)
		)
		(property "Value" "R_100R_0402"
			(at -1.011843 -1.772047 90)
			(layer "B.Fab")
			(effects
				(font
					(size 0.7 0.7)
					(thickness 0.15)
				)
				(justify right bottom mirror)
			)
		)
		(property "Author" "Antmicro"
			(at 197.6 -15.66 0)
			(layer "B.Fab")
			(hide yes)
			(effects
				(font
					(size 1 1)
					(thickness 0.15)
				)
				(justify mirror)
			)
		)
		(property "License" "Apache-2.0"
			(at 197.6 -15.66 0)
			(layer "B.Fab")
			(hide yes)
			(effects
				(font
					(size 1 1)
					(thickness 0.15)
				)
				(justify mirror)
			)
		)
		(property "MPN" "CR0402-FX-1000GLF"
			(at 197.6 -15.66 0)
			(layer "B.Fab")
			(hide yes)
			(effects
				(font
					(size 1 1)
					(thickness 0.15)
				)
				(justify mirror)
			)
		)
		(property "Manufacturer" "Bourns"
			(at 197.6 -15.66 0)
			(layer "B.Fab")
			(hide yes)
			(effects
				(font
					(size 1 1)
					(thickness 0.15)
				)
				(justify mirror)
			)
		)
		(property "Tolerance" "1%"
			(at 197.6 -15.66 0)
			(layer "B.Fab")
			(hide yes)
			(effects
				(font
					(size 1 1)
					(thickness 0.15)
				)
				(justify mirror)
			)
		)
		(property "Val" "100R"
			(at 197.6 -15.66 0)
			(layer "B.Fab")
			(hide yes)
			(effects
				(font
					(size 1 1)
					(thickness 0.15)
				)
				(justify mirror)
			)
		)
		(sheetname "Translators")
		(sheetfile "translators.kicad_sch")
		(attr smd)
		(fp_rect
			(start -0.93 0.47)
			(end 0.93 -0.47)
			(stroke
				(width 0.05)
				(type solid)
			)
			(fill no)
			(layer "B.CrtYd")
		)
		(fp_rect
			(start -0.5 0.25)
			(end 0.5 -0.25)
			(stroke
				(width 0.15)
				(type solid)
			)
			(fill no)
			(layer "B.Fab")
		)
		(pad "1" smd roundrect
			(at -0.485 0 90)
			(size 0.59 0.64)
			(layers "B.Cu" "B.Mask" "B.Paste")
			(roundrect_rratio 0.25)
			(net 182 "/SODIMM/LPDDR5_IN_A.WCK1_N")
			(pintype "passive")
		)
		(pad "2" smd roundrect
			(at 0.485 0 90)
			(size 0.59 0.64)
			(layers "B.Cu" "B.Mask" "B.Paste")
			(roundrect_rratio 0.25)
			(net 47 "/LPDDR5/LPDDR5_A.WCK1_N")
			(pintype "passive")
		)
	)
	(footprint "antmicro-footprints:C_0402_1005Metric"
		(layer "B.Cu")
		(at 140.375 84.95)
		(descr "Capacitor SMD 0402")
		(tags "capacitor SMD 0402")
		(property "Reference" "C43"
			(at 0.925 0.55 0)
			(unlocked yes)
			(layer "B.SilkS")
			(effects
				(font
					(size 0.7 0.7)
					(thickness 0.15)
				)
				(justify right bottom mirror)
			)
		)
		(property "Value" "C_4u7_0402"
			(at -1.022927 -2.155213 0)
			(layer "B.Fab")
			(effects
				(font
					(size 0.7 0.7)
					(thickness 0.15)
				)
				(justify right bottom mirror)
			)
		)
		(property "Author" "Antmicro"
			(at 0 0 0)
			(layer "B.Fab")
			(hide yes)
			(effects
				(font
					(size 1 1)
					(thickness 0.15)
				)
				(justify mirror)
			)
		)
		(property "Dielectric" ""
			(at 0 0 0)
			(layer "B.Fab")
			(hide yes)
			(effects
				(font
					(size 1 1)
					(thickness 0.15)
				)
				(justify mirror)
			)
		)
		(property "License" "Apache-2.0"
			(at 0 0 0)
			(layer "B.Fab")
			(hide yes)
			(effects
				(font
					(size 1 1)
					(thickness 0.15)
				)
				(justify mirror)
			)
		)
		(property "MPN" "GRM155R61A475MEAAD"
			(at 0 0 0)
			(layer "B.Fab")
			(hide yes)
			(effects
				(font
					(size 1 1)
					(thickness 0.15)
				)
				(justify mirror)
			)
		)
		(property "Manufacturer" "Murata"
			(at 0 0 0)
			(layer "B.Fab")
			(hide yes)
			(effects
				(font
					(size 1 1)
					(thickness 0.15)
				)
				(justify mirror)
			)
		)
		(property "Val" "4u7"
			(at 0 0 0)
			(layer "B.Fab")
			(hide yes)
			(effects
				(font
					(size 1 1)
					(thickness 0.15)
				)
				(justify mirror)
			)
		)
		(property "Voltage" ""
			(at 0 0 0)
			(layer "B.Fab")
			(hide yes)
			(effects
				(font
					(size 1 1)
					(thickness 0.15)
				)
				(justify mirror)
			)
		)
		(sheetname "LPDDR5")
		(sheetfile "lpddr5.kicad_sch")
		(attr smd)
		(fp_rect
			(start -0.9659 0.481258)
			(end 0.9649 -0.458742)
			(stroke
				(width 0.05)
				(type solid)
			)
			(fill no)
			(layer "B.CrtYd")
		)
		(fp_line
			(start -0.499 -0.248)
			(end -0.499 0.25)
			(stroke
				(width 0.15)
				(type solid)
			)
			(layer "B.Fab")
		)
		(fp_line
			(start -0.499 0.25)
			(end 0.499 0.25)
			(stroke
				(width 0.15)
				(type solid)
			)
			(layer "B.Fab")
		)
		(fp_line
			(start 0.499 -0.248)
			(end -0.499 -0.248)
			(stroke
				(width 0.15)
				(type solid)
			)
			(layer "B.Fab")
		)
		(fp_line
			(start 0.499 0.25)
			(end 0.499 -0.248)
			(stroke
				(width 0.15)
				(type solid)
			)
			(layer "B.Fab")
		)
		(pad "1" smd roundrect
			(at -0.484 0)
			(size 0.59 0.64)
			(layers "B.Cu" "B.Mask" "B.Paste")
			(roundrect_rratio 0.25)
			(net 14 "GND")
			(pintype "passive")
		)
		(pad "2" smd roundrect
			(at 0.484 0)
			(size 0.59 0.64)
			(layers "B.Cu" "B.Mask" "B.Paste")
			(roundrect_rratio 0.25)
			(net 4 "+0V5")
			(pintype "passive")
		)
	)
	(footprint "antmicro-footprints:R_0402_1005Metric"
		(layer "B.Cu")
		(at 154.9 89.31)
		(descr "Resistor SMD 0402")
		(tags "resistor SMD 0402")
		(property "Reference" "R82"
			(at -1 -0.61 0)
			(unlocked yes)
			(layer "B.SilkS")
			(effects
				(font
					(size 0.7 0.7)
					(thickness 0.15)
				)
				(justify right bottom mirror)
			)
		)
		(property "Value" "R_100R_0402"
			(at -1.011843 -1.772047 0)
			(layer "B.Fab")
			(effects
				(font
					(size 0.7 0.7)
					(thickness 0.15)
				)
				(justify right bottom mirror)
			)
		)
		(property "Author" "Antmicro"
			(at 0 0 0)
			(layer "B.Fab")
			(hide yes)
			(effects
				(font
					(size 1 1)
					(thickness 0.15)
				)
				(justify mirror)
			)
		)
		(property "License" "Apache-2.0"
			(at 0 0 0)
			(layer "B.Fab")
			(hide yes)
			(effects
				(font
					(size 1 1)
					(thickness 0.15)
				)
				(justify mirror)
			)
		)
		(property "MPN" "CR0402-FX-1000GLF"
			(at 0 0 0)
			(layer "B.Fab")
			(hide yes)
			(effects
				(font
					(size 1 1)
					(thickness 0.15)
				)
				(justify mirror)
			)
		)
		(property "Manufacturer" "Bourns"
			(at 0 0 0)
			(layer "B.Fab")
			(hide yes)
			(effects
				(font
					(size 1 1)
					(thickness 0.15)
				)
				(justify mirror)
			)
		)
		(property "Tolerance" "1%"
			(at 0 0 0)
			(layer "B.Fab")
			(hide yes)
			(effects
				(font
					(size 1 1)
					(thickness 0.15)
				)
				(justify mirror)
			)
		)
		(property "Val" "100R"
			(at 0 0 0)
			(layer "B.Fab")
			(hide yes)
			(effects
				(font
					(size 1 1)
					(thickness 0.15)
				)
				(justify mirror)
			)
		)
		(sheetname "Translators1")
		(sheetfile "translators.kicad_sch")
		(attr smd)
		(fp_rect
			(start -0.93 0.47)
			(end 0.93 -0.47)
			(stroke
				(width 0.05)
				(type solid)
			)
			(fill no)
			(layer "B.CrtYd")
		)
		(fp_rect
			(start -0.5 0.25)
			(end 0.5 -0.25)
			(stroke
				(width 0.15)
				(type solid)
			)
			(fill no)
			(layer "B.Fab")
		)
		(pad "1" smd roundrect
			(at -0.485 0)
			(size 0.59 0.64)
			(layers "B.Cu" "B.Mask" "B.Paste")
			(roundrect_rratio 0.25)
			(net 111 "/LPDDR5/LPDDR5_B.WCK1_P")
			(pintype "passive")
		)
		(pad "2" smd roundrect
			(at 0.485 0)
			(size 0.59 0.64)
			(layers "B.Cu" "B.Mask" "B.Paste")
			(roundrect_rratio 0.25)
			(net 14 "GND")
			(pintype "passive")
		)
	)
	(footprint "antmicro-footprints:R_0402_1005Metric"
		(layer "B.Cu")
		(at 163.95 90.9 90)
		(descr "Resistor SMD 0402")
		(tags "resistor SMD 0402")
		(property "Reference" "R64"
			(at -1.2 -0.65 90)
			(unlocked yes)
			(layer "B.SilkS")
			(effects
				(font
					(size 0.7 0.7)
					(thickness 0.15)
				)
				(justify right bottom mirror)
			)
		)
		(property "Value" "R_100R_0402"
			(at -1.011843 -1.772047 90)
			(layer "B.Fab")
			(effects
				(font
					(size 0.7 0.7)
					(thickness 0.15)
				)
				(justify right bottom mirror)
			)
		)
		(property "Author" "Antmicro"
			(at 254.85 -73.05 0)
			(layer "B.Fab")
			(hide yes)
			(effects
				(font
					(size 1 1)
					(thickness 0.15)
				)
				(justify mirror)
			)
		)
		(property "License" "Apache-2.0"
			(at 254.85 -73.05 0)
			(layer "B.Fab")
			(hide yes)
			(effects
				(font
					(size 1 1)
					(thickness 0.15)
				)
				(justify mirror)
			)
		)
		(property "MPN" "CR0402-FX-1000GLF"
			(at 254.85 -73.05 0)
			(layer "B.Fab")
			(hide yes)
			(effects
				(font
					(size 1 1)
					(thickness 0.15)
				)
				(justify mirror)
			)
		)
		(property "Manufacturer" "Bourns"
			(at 254.85 -73.05 0)
			(layer "B.Fab")
			(hide yes)
			(effects
				(font
					(size 1 1)
					(thickness 0.15)
				)
				(justify mirror)
			)
		)
		(property "Tolerance" "1%"
			(at 254.85 -73.05 0)
			(layer "B.Fab")
			(hide yes)
			(effects
				(font
					(size 1 1)
					(thickness 0.15)
				)
				(justify mirror)
			)
		)
		(property "Val" "100R"
			(at 254.85 -73.05 0)
			(layer "B.Fab")
			(hide yes)
			(effects
				(font
					(size 1 1)
					(thickness 0.15)
				)
				(justify mirror)
			)
		)
		(sheetname "Translators1")
		(sheetfile "translators.kicad_sch")
		(attr smd)
		(fp_rect
			(start -0.93 0.47)
			(end 0.93 -0.47)
			(stroke
				(width 0.05)
				(type solid)
			)
			(fill no)
			(layer "B.CrtYd")
		)
		(fp_rect
			(start -0.5 0.25)
			(end 0.5 -0.25)
			(stroke
				(width 0.15)
				(type solid)
			)
			(fill no)
			(layer "B.Fab")
		)
		(pad "1" smd roundrect
			(at -0.485 0 90)
			(size 0.59 0.64)
			(layers "B.Cu" "B.Mask" "B.Paste")
			(roundrect_rratio 0.25)
			(net 127 "/SODIMM/LPDDR5_IN_B.WCK0_N")
			(pintype "passive")
		)
		(pad "2" smd roundrect
			(at 0.485 0 90)
			(size 0.59 0.64)
			(layers "B.Cu" "B.Mask" "B.Paste")
			(roundrect_rratio 0.25)
			(net 109 "/LPDDR5/LPDDR5_B.WCK0_N")
			(pintype "passive")
		)
	)
	(footprint "antmicro-footprints:R_0402_1005Metric"
		(layer "B.Cu")
		(at 136.15 91.35 -90)
		(descr "Resistor SMD 0402")
		(tags "resistor SMD 0402")
		(property "Reference" "R54"
			(at -1.05 -1.45 90)
			(unlocked yes)
			(layer "B.SilkS")
			(effects
				(font
					(size 0.7 0.7)
					(thickness 0.15)
				)
				(justify left bottom mirror)
			)
		)
		(property "Value" "R_100R_0402"
			(at -1.011843 -1.772047 90)
			(layer "B.Fab")
			(effects
				(font
					(size 0.7 0.7)
					(thickness 0.15)
				)
				(justify left bottom mirror)
			)
		)
		(property "Author" "Antmicro"
			(at 44.8 227.5 0)
			(layer "B.Fab")
			(hide yes)
			(effects
				(font
					(size 1 1)
					(thickness 0.15)
				)
				(justify mirror)
			)
		)
		(property "License" "Apache-2.0"
			(at 44.8 227.5 0)
			(layer "B.Fab")
			(hide yes)
			(effects
				(font
					(size 1 1)
					(thickness 0.15)
				)
				(justify mirror)
			)
		)
		(property "MPN" "CR0402-FX-1000GLF"
			(at 44.8 227.5 0)
			(layer "B.Fab")
			(hide yes)
			(effects
				(font
					(size 1 1)
					(thickness 0.15)
				)
				(justify mirror)
			)
		)
		(property "Manufacturer" "Bourns"
			(at 44.8 227.5 0)
			(layer "B.Fab")
			(hide yes)
			(effects
				(font
					(size 1 1)
					(thickness 0.15)
				)
				(justify mirror)
			)
		)
		(property "Tolerance" "1%"
			(at 44.8 227.5 0)
			(layer "B.Fab")
			(hide yes)
			(effects
				(font
					(size 1 1)
					(thickness 0.15)
				)
				(justify mirror)
			)
		)
		(property "Val" "100R"
			(at 44.8 227.5 0)
			(layer "B.Fab")
			(hide yes)
			(effects
				(font
					(size 1 1)
					(thickness 0.15)
				)
				(justify mirror)
			)
		)
		(sheetname "Translators")
		(sheetfile "translators.kicad_sch")
		(attr smd)
		(fp_rect
			(start -0.93 0.47)
			(end 0.93 -0.47)
			(stroke
				(width 0.05)
				(type solid)
			)
			(fill no)
			(layer "B.CrtYd")
		)
		(fp_rect
			(start -0.5 0.25)
			(end 0.5 -0.25)
			(stroke
				(width 0.15)
				(type solid)
			)
			(fill no)
			(layer "B.Fab")
		)
		(pad "1" smd roundrect
			(at -0.485 0 270)
			(size 0.59 0.64)
			(layers "B.Cu" "B.Mask" "B.Paste")
			(roundrect_rratio 0.25)
			(net 50 "/LPDDR5/LPDDR5_A.CK_N")
			(pintype "passive")
		)
		(pad "2" smd roundrect
			(at 0.485 0 270)
			(size 0.59 0.64)
			(layers "B.Cu" "B.Mask" "B.Paste")
			(roundrect_rratio 0.25)
			(net 14 "GND")
			(pintype "passive")
		)
	)
	(footprint "antmicro-footprints:C_0402_1005Metric"
		(layer "B.Cu")
		(at 130.775 81.45)
		(descr "Capacitor SMD 0402")
		(tags "capacitor SMD 0402")
		(property "Reference" "C57"
			(at 0.825 0.35 0)
			(unlocked yes)
			(layer "B.SilkS")
			(effects
				(font
					(size 0.7 0.7)
					(thickness 0.15)
				)
				(justify right bottom mirror)
			)
		)
		(property "Value" "C_4u7_0402"
			(at -1.022927 -2.155213 0)
			(layer "B.Fab")
			(effects
				(font
					(size 0.7 0.7)
					(thickness 0.15)
				)
				(justify right bottom mirror)
			)
		)
		(property "Author" "Antmicro"
			(at 0 0 0)
			(layer "B.Fab")
			(hide yes)
			(effects
				(font
					(size 1 1)
					(thickness 0.15)
				)
				(justify mirror)
			)
		)
		(property "Dielectric" ""
			(at 0 0 0)
			(layer "B.Fab")
			(hide yes)
			(effects
				(font
					(size 1 1)
					(thickness 0.15)
				)
				(justify mirror)
			)
		)
		(property "License" "Apache-2.0"
			(at 0 0 0)
			(layer "B.Fab")
			(hide yes)
			(effects
				(font
					(size 1 1)
					(thickness 0.15)
				)
				(justify mirror)
			)
		)
		(property "MPN" "GRM155R61A475MEAAD"
			(at 0 0 0)
			(layer "B.Fab")
			(hide yes)
			(effects
				(font
					(size 1 1)
					(thickness 0.15)
				)
				(justify mirror)
			)
		)
		(property "Manufacturer" "Murata"
			(at 0 0 0)
			(layer "B.Fab")
			(hide yes)
			(effects
				(font
					(size 1 1)
					(thickness 0.15)
				)
				(justify mirror)
			)
		)
		(property "Val" "4u7"
			(at 0 0 0)
			(layer "B.Fab")
			(hide yes)
			(effects
				(font
					(size 1 1)
					(thickness 0.15)
				)
				(justify mirror)
			)
		)
		(property "Voltage" ""
			(at 0 0 0)
			(layer "B.Fab")
			(hide yes)
			(effects
				(font
					(size 1 1)
					(thickness 0.15)
				)
				(justify mirror)
			)
		)
		(sheetname "LPDDR5")
		(sheetfile "lpddr5.kicad_sch")
		(attr smd)
		(fp_rect
			(start -0.9659 0.481258)
			(end 0.9649 -0.458742)
			(stroke
				(width 0.05)
				(type solid)
			)
			(fill no)
			(layer "B.CrtYd")
		)
		(fp_line
			(start -0.499 -0.248)
			(end -0.499 0.25)
			(stroke
				(width 0.15)
				(type solid)
			)
			(layer "B.Fab")
		)
		(fp_line
			(start -0.499 0.25)
			(end 0.499 0.25)
			(stroke
				(width 0.15)
				(type solid)
			)
			(layer "B.Fab")
		)
		(fp_line
			(start 0.499 -0.248)
			(end -0.499 -0.248)
			(stroke
				(width 0.15)
				(type solid)
			)
			(layer "B.Fab")
		)
		(fp_line
			(start 0.499 0.25)
			(end 0.499 -0.248)
			(stroke
				(width 0.15)
				(type solid)
			)
			(layer "B.Fab")
		)
		(pad "1" smd roundrect
			(at -0.484 0)
			(size 0.59 0.64)
			(layers "B.Cu" "B.Mask" "B.Paste")
			(roundrect_rratio 0.25)
			(net 14 "GND")
			(pintype "passive")
		)
		(pad "2" smd roundrect
			(at 0.484 0)
			(size 0.59 0.64)
			(layers "B.Cu" "B.Mask" "B.Paste")
			(roundrect_rratio 0.25)
			(net 13 "+1V05")
			(pintype "passive")
		)
	)
	(footprint "antmicro-footprints:R_0402_1005Metric"
		(layer "B.Cu")
		(at 153.45 90.785 90)
		(descr "Resistor SMD 0402")
		(tags "resistor SMD 0402")
		(property "Reference" "R66"
			(at -1.215 -0.55 90)
			(unlocked yes)
			(layer "B.SilkS")
			(effects
				(font
					(size 0.7 0.7)
					(thickness 0.15)
				)
				(justify right bottom mirror)
			)
		)
		(property "Value" "R_100R_0402"
			(at -1.011843 -1.772047 90)
			(layer "B.Fab")
			(effects
				(font
					(size 0.7 0.7)
					(thickness 0.15)
				)
				(justify right bottom mirror)
			)
		)
		(property "Author" "Antmicro"
			(at 244.235 -62.665 0)
			(layer "B.Fab")
			(hide yes)
			(effects
				(font
					(size 1 1)
					(thickness 0.15)
				)
				(justify mirror)
			)
		)
		(property "License" "Apache-2.0"
			(at 244.235 -62.665 0)
			(layer "B.Fab")
			(hide yes)
			(effects
				(font
					(size 1 1)
					(thickness 0.15)
				)
				(justify mirror)
			)
		)
		(property "MPN" "CR0402-FX-1000GLF"
			(at 244.235 -62.665 0)
			(layer "B.Fab")
			(hide yes)
			(effects
				(font
					(size 1 1)
					(thickness 0.15)
				)
				(justify mirror)
			)
		)
		(property "Manufacturer" "Bourns"
			(at 244.235 -62.665 0)
			(layer "B.Fab")
			(hide yes)
			(effects
				(font
					(size 1 1)
					(thickness 0.15)
				)
				(justify mirror)
			)
		)
		(property "Tolerance" "1%"
			(at 244.235 -62.665 0)
			(layer "B.Fab")
			(hide yes)
			(effects
				(font
					(size 1 1)
					(thickness 0.15)
				)
				(justify mirror)
			)
		)
		(property "Val" "100R"
			(at 244.235 -62.665 0)
			(layer "B.Fab")
			(hide yes)
			(effects
				(font
					(size 1 1)
					(thickness 0.15)
				)
				(justify mirror)
			)
		)
		(sheetname "Translators1")
		(sheetfile "translators.kicad_sch")
		(attr smd)
		(fp_rect
			(start -0.93 0.47)
			(end 0.93 -0.47)
			(stroke
				(width 0.05)
				(type solid)
			)
			(fill no)
			(layer "B.CrtYd")
		)
		(fp_rect
			(start -0.5 0.25)
			(end 0.5 -0.25)
			(stroke
				(width 0.15)
				(type solid)
			)
			(fill no)
			(layer "B.Fab")
		)
		(pad "1" smd roundrect
			(at -0.485 0 90)
			(size 0.59 0.64)
			(layers "B.Cu" "B.Mask" "B.Paste")
			(roundrect_rratio 0.25)
			(net 138 "/SODIMM/LPDDR5_IN_B.WCK1_N")
			(pintype "passive")
		)
		(pad "2" smd roundrect
			(at 0.485 0 90)
			(size 0.59 0.64)
			(layers "B.Cu" "B.Mask" "B.Paste")
			(roundrect_rratio 0.25)
			(net 110 "/LPDDR5/LPDDR5_B.WCK1_N")
			(pintype "passive")
		)
	)
	(footprint "antmicro-footprints:R_0402_1005Metric"
		(layer "B.Cu")
		(at 106.25 79.7 90)
		(descr "Resistor SMD 0402")
		(tags "resistor SMD 0402")
		(property "Reference" "R26"
			(at -1.1 -0.75 90)
			(unlocked yes)
			(layer "B.SilkS")
			(effects
				(font
					(size 0.7 0.7)
					(thickness 0.15)
				)
				(justify right bottom mirror)
			)
		)
		(property "Value" "R_0R_0402"
			(at -1.011843 -1.772047 90)
			(layer "B.Fab")
			(effects
				(font
					(size 0.7 0.7)
					(thickness 0.15)
				)
				(justify right bottom mirror)
			)
		)
		(property "Author" "Antmicro"
			(at 185.95 -26.55 0)
			(layer "B.Fab")
			(hide yes)
			(effects
				(font
					(size 1 1)
					(thickness 0.15)
				)
				(justify mirror)
			)
		)
		(property "Current" "1A"
			(at 185.95 -26.55 0)
			(layer "B.Fab")
			(hide yes)
			(effects
				(font
					(size 1 1)
					(thickness 0.15)
				)
				(justify mirror)
			)
		)
		(property "License" "Apache-2.0"
			(at 185.95 -26.55 0)
			(layer "B.Fab")
			(hide yes)
			(effects
				(font
					(size 1 1)
					(thickness 0.15)
				)
				(justify mirror)
			)
		)
		(property "MPN" "ERJ2GE0R00X"
			(at 185.95 -26.55 0)
			(layer "B.Fab")
			(hide yes)
			(effects
				(font
					(size 1 1)
					(thickness 0.15)
				)
				(justify mirror)
			)
		)
		(property "Manufacturer" "Panasonic"
			(at 185.95 -26.55 0)
			(layer "B.Fab")
			(hide yes)
			(effects
				(font
					(size 1 1)
					(thickness 0.15)
				)
				(justify mirror)
			)
		)
		(property "Tolerance" ""
			(at 185.95 -26.55 0)
			(layer "B.Fab")
			(hide yes)
			(effects
				(font
					(size 1 1)
					(thickness 0.15)
				)
				(justify mirror)
			)
		)
		(property "Val" "0R"
			(at 185.95 -26.55 0)
			(layer "B.Fab")
			(hide yes)
			(effects
				(font
					(size 1 1)
					(thickness 0.15)
				)
				(justify mirror)
			)
		)
		(sheetname "SODIMM")
		(sheetfile "sodim.kicad_sch")
		(attr smd)
		(fp_rect
			(start -0.93 0.47)
			(end 0.93 -0.47)
			(stroke
				(width 0.05)
				(type solid)
			)
			(fill no)
			(layer "B.CrtYd")
		)
		(fp_rect
			(start -0.5 0.25)
			(end 0.5 -0.25)
			(stroke
				(width 0.15)
				(type solid)
			)
			(fill no)
			(layer "B.Fab")
		)
		(pad "1" smd roundrect
			(at -0.485 0 90)
			(size 0.59 0.64)
			(layers "B.Cu" "B.Mask" "B.Paste")
			(roundrect_rratio 0.25)
			(net 18 "/SODIMM/HSCL")
			(pintype "passive")
		)
		(pad "2" smd roundrect
			(at 0.485 0 90)
			(size 0.59 0.64)
			(layers "B.Cu" "B.Mask" "B.Paste")
			(roundrect_rratio 0.25)
			(net 39 "/Power supply/I2C.SCL")
			(pintype "passive")
		)
	)
	(footprint "antmicro-footprints:R_0402_1005Metric"
		(layer "B.Cu")
		(at 133.9 93.8425 90)
		(descr "Resistor SMD 0402")
		(tags "resistor SMD 0402")
		(property "Reference" "R99"
			(at -1.0575 -0.5 90)
			(unlocked yes)
			(layer "B.SilkS")
			(effects
				(font
					(size 0.7 0.7)
					(thickness 0.15)
				)
				(justify right bottom mirror)
			)
		)
		(property "Value" "R_100k_0402"
			(at -1.011843 -1.772047 90)
			(layer "B.Fab")
			(effects
				(font
					(size 0.7 0.7)
					(thickness 0.15)
				)
				(justify right bottom mirror)
			)
		)
		(property "Author" "Antmicro"
			(at 227.7425 -40.0575 0)
			(layer "B.Fab")
			(hide yes)
			(effects
				(font
					(size 1 1)
					(thickness 0.15)
				)
				(justify mirror)
			)
		)
		(property "License" "Apache-2.0"
			(at 227.7425 -40.0575 0)
			(layer "B.Fab")
			(hide yes)
			(effects
				(font
					(size 1 1)
					(thickness 0.15)
				)
				(justify mirror)
			)
		)
		(property "MPN" "CR0402-FX-1003GLF"
			(at 227.7425 -40.0575 0)
			(layer "B.Fab")
			(hide yes)
			(effects
				(font
					(size 1 1)
					(thickness 0.15)
				)
				(justify mirror)
			)
		)
		(property "Manufacturer" "Bourns"
			(at 227.7425 -40.0575 0)
			(layer "B.Fab")
			(hide yes)
			(effects
				(font
					(size 1 1)
					(thickness 0.15)
				)
				(justify mirror)
			)
		)
		(property "Tolerance" "1%"
			(at 227.7425 -40.0575 0)
			(layer "B.Fab")
			(hide yes)
			(effects
				(font
					(size 1 1)
					(thickness 0.15)
				)
				(justify mirror)
			)
		)
		(property "Val" "100k"
			(at 227.7425 -40.0575 0)
			(layer "B.Fab")
			(hide yes)
			(effects
				(font
					(size 1 1)
					(thickness 0.15)
				)
				(justify mirror)
			)
		)
		(sheetname "SODIMM")
		(sheetfile "sodim.kicad_sch")
		(attr smd exclude_from_pos_files exclude_from_bom dnp)
		(fp_rect
			(start -0.93 0.47)
			(end 0.93 -0.47)
			(stroke
				(width 0.05)
				(type solid)
			)
			(fill no)
			(layer "B.CrtYd")
		)
		(fp_rect
			(start -0.5 0.25)
			(end 0.5 -0.25)
			(stroke
				(width 0.15)
				(type solid)
			)
			(fill no)
			(layer "B.Fab")
		)
		(pad "1" smd roundrect
			(at -0.485 0 90)
			(size 0.59 0.64)
			(layers "B.Cu" "B.Mask" "B.Paste")
			(roundrect_rratio 0.25)
			(net 33 "Net-(J1-Pad130)")
			(pintype "passive")
		)
		(pad "2" smd roundrect
			(at 0.485 0 90)
			(size 0.59 0.64)
			(layers "B.Cu" "B.Mask" "B.Paste")
			(roundrect_rratio 0.25)
			(net 14 "GND")
			(pintype "passive")
		)
	)
	(footprint "antmicro-footprints:C_0402_1005Metric"
		(layer "B.Cu")
		(at 133.375 84.35 -90)
		(descr "Capacitor SMD 0402")
		(tags "capacitor SMD 0402")
		(property "Reference" "C51"
			(at 0.85 -0.425 90)
			(unlocked yes)
			(layer "B.SilkS")
			(effects
				(font
					(size 0.7 0.7)
					(thickness 0.15)
				)
				(justify left bottom mirror)
			)
		)
		(property "Value" "C_4u7_0402"
			(at -1.022927 -2.155213 90)
			(layer "B.Fab")
			(effects
				(font
					(size 0.7 0.7)
					(thickness 0.15)
				)
				(justify left bottom mirror)
			)
		)
		(property "Author" "Antmicro"
			(at 49.025 217.725 0)
			(layer "B.Fab")
			(hide yes)
			(effects
				(font
					(size 1 1)
					(thickness 0.15)
				)
				(justify mirror)
			)
		)
		(property "Dielectric" ""
			(at 49.025 217.725 0)
			(layer "B.Fab")
			(hide yes)
			(effects
				(font
					(size 1 1)
					(thickness 0.15)
				)
				(justify mirror)
			)
		)
		(property "License" "Apache-2.0"
			(at 49.025 217.725 0)
			(layer "B.Fab")
			(hide yes)
			(effects
				(font
					(size 1 1)
					(thickness 0.15)
				)
				(justify mirror)
			)
		)
		(property "MPN" "GRM155R61A475MEAAD"
			(at 49.025 217.725 0)
			(layer "B.Fab")
			(hide yes)
			(effects
				(font
					(size 1 1)
					(thickness 0.15)
				)
				(justify mirror)
			)
		)
		(property "Manufacturer" "Murata"
			(at 49.025 217.725 0)
			(layer "B.Fab")
			(hide yes)
			(effects
				(font
					(size 1 1)
					(thickness 0.15)
				)
				(justify mirror)
			)
		)
		(property "Val" "4u7"
			(at 49.025 217.725 0)
			(layer "B.Fab")
			(hide yes)
			(effects
				(font
					(size 1 1)
					(thickness 0.15)
				)
				(justify mirror)
			)
		)
		(property "Voltage" ""
			(at 49.025 217.725 0)
			(layer "B.Fab")
			(hide yes)
			(effects
				(font
					(size 1 1)
					(thickness 0.15)
				)
				(justify mirror)
			)
		)
		(sheetname "LPDDR5")
		(sheetfile "lpddr5.kicad_sch")
		(attr smd)
		(fp_rect
			(start -0.9659 0.481258)
			(end 0.9649 -0.458742)
			(stroke
				(width 0.05)
				(type solid)
			)
			(fill no)
			(layer "B.CrtYd")
		)
		(fp_line
			(start -0.499 0.25)
			(end 0.499 0.25)
			(stroke
				(width 0.15)
				(type solid)
			)
			(layer "B.Fab")
		)
		(fp_line
			(start 0.499 0.25)
			(end 0.499 -0.248)
			(stroke
				(width 0.15)
				(type solid)
			)
			(layer "B.Fab")
		)
		(fp_line
			(start -0.499 -0.248)
			(end -0.499 0.25)
			(stroke
				(width 0.15)
				(type solid)
			)
			(layer "B.Fab")
		)
		(fp_line
			(start 0.499 -0.248)
			(end -0.499 -0.248)
			(stroke
				(width 0.15)
				(type solid)
			)
			(layer "B.Fab")
		)
		(pad "1" smd roundrect
			(at -0.484 0 270)
			(size 0.59 0.64)
			(layers "B.Cu" "B.Mask" "B.Paste")
			(roundrect_rratio 0.25)
			(net 14 "GND")
			(pintype "passive")
		)
		(pad "2" smd roundrect
			(at 0.484 0 270)
			(size 0.59 0.64)
			(layers "B.Cu" "B.Mask" "B.Paste")
			(roundrect_rratio 0.25)
			(net 12 "+0V9")
			(pintype "passive")
		)
	)
	(footprint "antmicro-footprints:R_Array_4x0402_Panasonic_EXB28V"
		(layer "B.Cu")
		(at 155.7 93.85)
		(property "Reference" "R78"
			(at -1.1 1.8 0)
			(unlocked yes)
			(layer "B.SilkS")
			(effects
				(font
					(size 0.7 0.7)
					(thickness 0.15)
				)
				(justify right bottom mirror)
			)
		)
		(property "Value" "R_4x100R_0402_array"
			(at -1.5 -2 0)
			(layer "B.Fab")
			(effects
				(font
					(size 0.7 0.7)
					(thickness 0.15)
				)
				(justify right bottom mirror)
			)
		)
		(property "Author" "Antmicro"
			(at 0 0 0)
			(layer "B.Fab")
			(hide yes)
			(effects
				(font
					(size 1 1)
					(thickness 0.15)
				)
				(justify mirror)
			)
		)
		(property "License" "Apache-2.0"
			(at 0 0 0)
			(layer "B.Fab")
			(hide yes)
			(effects
				(font
					(size 1 1)
					(thickness 0.15)
				)
				(justify mirror)
			)
		)
		(property "MPN" "EXB-28V101JX"
			(at 0 0 0)
			(layer "B.Fab")
			(hide yes)
			(effects
				(font
					(size 1 1)
					(thickness 0.15)
				)
				(justify mirror)
			)
		)
		(property "Manufacturer" "Panasonic"
			(at 0 0 0)
			(layer "B.Fab")
			(hide yes)
			(effects
				(font
					(size 1 1)
					(thickness 0.15)
				)
				(justify mirror)
			)
		)
		(property "Val" "R_4x100R_0402"
			(at 0 0 0)
			(layer "B.Fab")
			(hide yes)
			(effects
				(font
					(size 1 1)
					(thickness 0.15)
				)
				(justify mirror)
			)
		)
		(sheetname "Translators1")
		(sheetfile "translators.kicad_sch")
		(attr smd)
		(fp_line
			(start -1.25 0.5)
			(end -1.25 -0.498)
			(stroke
				(width 0.15)
				(type solid)
			)
			(layer "B.SilkS")
		)
		(fp_line
			(start 1.25 -0.499)
			(end 1.25 0.499)
			(stroke
				(width 0.15)
				(type solid)
			)
			(layer "B.SilkS")
		)
		(fp_rect
			(start -1.25 0.8)
			(end 1.25 -0.8)
			(stroke
				(width 0.05)
				(type solid)
			)
			(fill no)
			(layer "B.CrtYd")
		)
		(fp_line
			(start -1 -0.498)
			(end -1 0.5)
			(stroke
				(width 0.15)
				(type solid)
			)
			(layer "B.Fab")
		)
		(fp_line
			(start -1 0.5)
			(end 0.998 0.5)
			(stroke
				(width 0.15)
				(type solid)
			)
			(layer "B.Fab")
		)
		(fp_line
			(start 0.998 -0.498)
			(end -1 -0.498)
			(stroke
				(width 0.15)
				(type solid)
			)
			(layer "B.Fab")
		)
		(fp_line
			(start 0.998 0.5)
			(end 0.998 -0.498)
			(stroke
				(width 0.15)
				(type solid)
			)
			(layer "B.Fab")
		)
		(pad "1" smd roundrect
			(at -0.8875 -0.45)
			(size 0.525 0.5)
			(layers "B.Cu" "B.Mask" "B.Paste")
			(roundrect_rratio 0.25)
			(net 216 "/LPDDR5/LPDDR5_B.DQ15")
			(pinfunction "R1.1")
			(pintype "passive")
		)
		(pad "2" smd roundrect
			(at -0.25 -0.45)
			(size 0.25 0.5)
			(layers "B.Cu" "B.Mask" "B.Paste")
			(roundrect_rratio 0.25)
			(net 215 "/LPDDR5/LPDDR5_B.DQ14")
			(pinfunction "R2.1")
			(pintype "passive")
		)
		(pad "3" smd roundrect
			(at 0.25 -0.45)
			(size 0.25 0.5)
			(layers "B.Cu" "B.Mask" "B.Paste")
			(roundrect_rratio 0.25)
			(net 213 "/LPDDR5/LPDDR5_B.DQ12")
			(pinfunction "R3.1")
			(pintype "passive")
		)
		(pad "4" smd roundrect
			(at 0.8875 -0.45)
			(size 0.525 0.5)
			(layers "B.Cu" "B.Mask" "B.Paste")
			(roundrect_rratio 0.25)
			(net 214 "/LPDDR5/LPDDR5_B.DQ13")
			(pinfunction "R4.1")
			(pintype "passive")
		)
		(pad "5" smd roundrect
			(at 0.8875 0.45)
			(size 0.525 0.5)
			(layers "B.Cu" "B.Mask" "B.Paste")
			(roundrect_rratio 0.25)
			(net 14 "GND")
			(pinfunction "R4.2")
			(pintype "passive")
		)
		(pad "6" smd roundrect
			(at 0.25 0.45)
			(size 0.25 0.5)
			(layers "B.Cu" "B.Mask" "B.Paste")
			(roundrect_rratio 0.25)
			(net 14 "GND")
			(pinfunction "R3.2")
			(pintype "passive")
		)
		(pad "7" smd roundrect
			(at -0.25 0.45)
			(size 0.25 0.5)
			(layers "B.Cu" "B.Mask" "B.Paste")
			(roundrect_rratio 0.25)
			(net 14 "GND")
			(pinfunction "R2.2")
			(pintype "passive")
		)
		(pad "8" smd roundrect
			(at -0.8875 0.45)
			(size 0.525 0.5)
			(layers "B.Cu" "B.Mask" "B.Paste")
			(roundrect_rratio 0.25)
			(net 14 "GND")
			(pinfunction "R1.2")
			(pintype "passive")
		)
	)
	(footprint "antmicro-footprints:C_0402_1005Metric"
		(layer "B.Cu")
		(at 129.175 84.95 180)
		(descr "Capacitor SMD 0402")
		(tags "capacitor SMD 0402")
		(property "Reference" "C39"
			(at 0.875 -0.35 0)
			(unlocked yes)
			(layer "B.SilkS")
			(effects
				(font
					(size 0.7 0.7)
					(thickness 0.15)
				)
				(justify left bottom mirror)
			)
		)
		(property "Value" "C_4u7_0402"
			(at -1.022927 -2.155213 0)
			(layer "B.Fab")
			(effects
				(font
					(size 0.7 0.7)
					(thickness 0.15)
				)
				(justify left bottom mirror)
			)
		)
		(property "Author" "Antmicro"
			(at 258.35 169.9 0)
			(layer "B.Fab")
			(hide yes)
			(effects
				(font
					(size 1 1)
					(thickness 0.15)
				)
				(justify mirror)
			)
		)
		(property "Dielectric" ""
			(at 258.35 169.9 0)
			(layer "B.Fab")
			(hide yes)
			(effects
				(font
					(size 1 1)
					(thickness 0.15)
				)
				(justify mirror)
			)
		)
		(property "License" "Apache-2.0"
			(at 258.35 169.9 0)
			(layer "B.Fab")
			(hide yes)
			(effects
				(font
					(size 1 1)
					(thickness 0.15)
				)
				(justify mirror)
			)
		)
		(property "MPN" "GRM155R61A475MEAAD"
			(at 258.35 169.9 0)
			(layer "B.Fab")
			(hide yes)
			(effects
				(font
					(size 1 1)
					(thickness 0.15)
				)
				(justify mirror)
			)
		)
		(property "Manufacturer" "Murata"
			(at 258.35 169.9 0)
			(layer "B.Fab")
			(hide yes)
			(effects
				(font
					(size 1 1)
					(thickness 0.15)
				)
				(justify mirror)
			)
		)
		(property "Val" "4u7"
			(at 258.35 169.9 0)
			(layer "B.Fab")
			(hide yes)
			(effects
				(font
					(size 1 1)
					(thickness 0.15)
				)
				(justify mirror)
			)
		)
		(property "Voltage" ""
			(at 258.35 169.9 0)
			(layer "B.Fab")
			(hide yes)
			(effects
				(font
					(size 1 1)
					(thickness 0.15)
				)
				(justify mirror)
			)
		)
		(sheetname "LPDDR5")
		(sheetfile "lpddr5.kicad_sch")
		(attr smd)
		(fp_rect
			(start -0.9659 0.481258)
			(end 0.9649 -0.458742)
			(stroke
				(width 0.05)
				(type solid)
			)
			(fill no)
			(layer "B.CrtYd")
		)
		(fp_line
			(start 0.499 0.25)
			(end 0.499 -0.248)
			(stroke
				(width 0.15)
				(type solid)
			)
			(layer "B.Fab")
		)
		(fp_line
			(start 0.499 -0.248)
			(end -0.499 -0.248)
			(stroke
				(width 0.15)
				(type solid)
			)
			(layer "B.Fab")
		)
		(fp_line
			(start -0.499 0.25)
			(end 0.499 0.25)
			(stroke
				(width 0.15)
				(type solid)
			)
			(layer "B.Fab")
		)
		(fp_line
			(start -0.499 -0.248)
			(end -0.499 0.25)
			(stroke
				(width 0.15)
				(type solid)
			)
			(layer "B.Fab")
		)
		(pad "1" smd roundrect
			(at -0.484 0 180)
			(size 0.59 0.64)
			(layers "B.Cu" "B.Mask" "B.Paste")
			(roundrect_rratio 0.25)
			(net 14 "GND")
			(pintype "passive")
		)
		(pad "2" smd roundrect
			(at 0.484 0 180)
			(size 0.59 0.64)
			(layers "B.Cu" "B.Mask" "B.Paste")
			(roundrect_rratio 0.25)
			(net 4 "+0V5")
			(pintype "passive")
		)
	)
	(footprint "antmicro-footprints:R_0402_1005Metric"
		(layer "B.Cu")
		(at 118.58 89.5)
		(descr "Resistor SMD 0402")
		(tags "resistor SMD 0402")
		(property "Reference" "R48"
			(at -0.98 -0.6 0)
			(unlocked yes)
			(layer "B.SilkS")
			(effects
				(font
					(size 0.7 0.7)
					(thickness 0.15)
				)
				(justify right bottom mirror)
			)
		)
		(property "Value" "R_100R_0402"
			(at -1.011843 -1.772047 0)
			(layer "B.Fab")
			(effects
				(font
					(size 0.7 0.7)
					(thickness 0.15)
				)
				(justify right bottom mirror)
			)
		)
		(property "Author" "Antmicro"
			(at 0 0 0)
			(layer "B.Fab")
			(hide yes)
			(effects
				(font
					(size 1 1)
					(thickness 0.15)
				)
				(justify mirror)
			)
		)
		(property "License" "Apache-2.0"
			(at 0 0 0)
			(layer "B.Fab")
			(hide yes)
			(effects
				(font
					(size 1 1)
					(thickness 0.15)
				)
				(justify mirror)
			)
		)
		(property "MPN" "CR0402-FX-1000GLF"
			(at 0 0 0)
			(layer "B.Fab")
			(hide yes)
			(effects
				(font
					(size 1 1)
					(thickness 0.15)
				)
				(justify mirror)
			)
		)
		(property "Manufacturer" "Bourns"
			(at 0 0 0)
			(layer "B.Fab")
			(hide yes)
			(effects
				(font
					(size 1 1)
					(thickness 0.15)
				)
				(justify mirror)
			)
		)
		(property "Tolerance" "1%"
			(at 0 0 0)
			(layer "B.Fab")
			(hide yes)
			(effects
				(font
					(size 1 1)
					(thickness 0.15)
				)
				(justify mirror)
			)
		)
		(property "Val" "100R"
			(at 0 0 0)
			(layer "B.Fab")
			(hide yes)
			(effects
				(font
					(size 1 1)
					(thickness 0.15)
				)
				(justify mirror)
			)
		)
		(sheetname "Translators")
		(sheetfile "translators.kicad_sch")
		(attr smd)
		(fp_rect
			(start -0.93 0.47)
			(end 0.93 -0.47)
			(stroke
				(width 0.05)
				(type solid)
			)
			(fill no)
			(layer "B.CrtYd")
		)
		(fp_rect
			(start -0.5 0.25)
			(end 0.5 -0.25)
			(stroke
				(width 0.15)
				(type solid)
			)
			(fill no)
			(layer "B.Fab")
		)
		(pad "1" smd roundrect
			(at -0.485 0)
			(size 0.59 0.64)
			(layers "B.Cu" "B.Mask" "B.Paste")
			(roundrect_rratio 0.25)
			(net 45 "/LPDDR5/LPDDR5_A.WCK0_P")
			(pintype "passive")
		)
		(pad "2" smd roundrect
			(at 0.485 0)
			(size 0.59 0.64)
			(layers "B.Cu" "B.Mask" "B.Paste")
			(roundrect_rratio 0.25)
			(net 14 "GND")
			(pintype "passive")
		)
	)
	(footprint "antmicro-footprints:R_0402_1005Metric"
		(layer "B.Cu")
		(at 132.1 93.8 -90)
		(descr "Resistor SMD 0402")
		(tags "resistor SMD 0402")
		(property "Reference" "R86"
			(at 0.8 -0.4 90)
			(unlocked yes)
			(layer "B.SilkS")
			(effects
				(font
					(size 0.7 0.7)
					(thickness 0.15)
				)
				(justify left bottom mirror)
			)
		)
		(property "Value" "R_100R_0402"
			(at -1.011843 -1.772047 90)
			(layer "B.Fab")
			(effects
				(font
					(size 0.7 0.7)
					(thickness 0.15)
				)
				(justify left bottom mirror)
			)
		)
		(property "Author" "Antmicro"
			(at 38.3 225.9 0)
			(layer "B.Fab")
			(hide yes)
			(effects
				(font
					(size 1 1)
					(thickness 0.15)
				)
				(justify mirror)
			)
		)
		(property "License" "Apache-2.0"
			(at 38.3 225.9 0)
			(layer "B.Fab")
			(hide yes)
			(effects
				(font
					(size 1 1)
					(thickness 0.15)
				)
				(justify mirror)
			)
		)
		(property "MPN" "CR0402-FX-1000GLF"
			(at 38.3 225.9 0)
			(layer "B.Fab")
			(hide yes)
			(effects
				(font
					(size 1 1)
					(thickness 0.15)
				)
				(justify mirror)
			)
		)
		(property "Manufacturer" "Bourns"
			(at 38.3 225.9 0)
			(layer "B.Fab")
			(hide yes)
			(effects
				(font
					(size 1 1)
					(thickness 0.15)
				)
				(justify mirror)
			)
		)
		(property "Tolerance" "1%"
			(at 38.3 225.9 0)
			(layer "B.Fab")
			(hide yes)
			(effects
				(font
					(size 1 1)
					(thickness 0.15)
				)
				(justify mirror)
			)
		)
		(property "Val" "100R"
			(at 38.3 225.9 0)
			(layer "B.Fab")
			(hide yes)
			(effects
				(font
					(size 1 1)
					(thickness 0.15)
				)
				(justify mirror)
			)
		)
		(sheetname "Translators")
		(sheetfile "translators.kicad_sch")
		(attr smd)
		(fp_rect
			(start -0.93 0.47)
			(end 0.93 -0.47)
			(stroke
				(width 0.05)
				(type solid)
			)
			(fill no)
			(layer "B.CrtYd")
		)
		(fp_rect
			(start -0.5 0.25)
			(end 0.5 -0.25)
			(stroke
				(width 0.15)
				(type solid)
			)
			(fill no)
			(layer "B.Fab")
		)
		(pad "1" smd roundrect
			(at -0.485 0 270)
			(size 0.59 0.64)
			(layers "B.Cu" "B.Mask" "B.Paste")
			(roundrect_rratio 0.25)
			(net 55 "/LPDDR5/LPDDR5_A.CA6")
			(pintype "passive")
		)
		(pad "2" smd roundrect
			(at 0.485 0 270)
			(size 0.59 0.64)
			(layers "B.Cu" "B.Mask" "B.Paste")
			(roundrect_rratio 0.25)
			(net 14 "GND")
			(pintype "passive")
		)
	)
	(footprint "antmicro-footprints:R_0402_1005Metric"
		(layer "B.Cu")
		(at 137.65 93.85 -90)
		(descr "Resistor SMD 0402")
		(tags "resistor SMD 0402")
		(property "Reference" "R83"
			(at 0.85 -0.35 90)
			(unlocked yes)
			(layer "B.SilkS")
			(effects
				(font
					(size 0.7 0.7)
					(thickness 0.15)
				)
				(justify left bottom mirror)
			)
		)
		(property "Value" "R_100R_0402"
			(at -1.011843 -1.772047 90)
			(layer "B.Fab")
			(effects
				(font
					(size 0.7 0.7)
					(thickness 0.15)
				)
				(justify left bottom mirror)
			)
		)
		(property "Author" "Antmicro"
			(at 43.8 231.5 0)
			(layer "B.Fab")
			(hide yes)
			(effects
				(font
					(size 1 1)
					(thickness 0.15)
				)
				(justify mirror)
			)
		)
		(property "License" "Apache-2.0"
			(at 43.8 231.5 0)
			(layer "B.Fab")
			(hide yes)
			(effects
				(font
					(size 1 1)
					(thickness 0.15)
				)
				(justify mirror)
			)
		)
		(property "MPN" "CR0402-FX-1000GLF"
			(at 43.8 231.5 0)
			(layer "B.Fab")
			(hide yes)
			(effects
				(font
					(size 1 1)
					(thickness 0.15)
				)
				(justify mirror)
			)
		)
		(property "Manufacturer" "Bourns"
			(at 43.8 231.5 0)
			(layer "B.Fab")
			(hide yes)
			(effects
				(font
					(size 1 1)
					(thickness 0.15)
				)
				(justify mirror)
			)
		)
		(property "Tolerance" "1%"
			(at 43.8 231.5 0)
			(layer "B.Fab")
			(hide yes)
			(effects
				(font
					(size 1 1)
					(thickness 0.15)
				)
				(justify mirror)
			)
		)
		(property "Val" "100R"
			(at 43.8 231.5 0)
			(layer "B.Fab")
			(hide yes)
			(effects
				(font
					(size 1 1)
					(thickness 0.15)
				)
				(justify mirror)
			)
		)
		(sheetname "Translators1")
		(sheetfile "translators.kicad_sch")
		(attr smd)
		(fp_rect
			(start -0.93 0.47)
			(end 0.93 -0.47)
			(stroke
				(width 0.05)
				(type solid)
			)
			(fill no)
			(layer "B.CrtYd")
		)
		(fp_rect
			(start -0.5 0.25)
			(end 0.5 -0.25)
			(stroke
				(width 0.15)
				(type solid)
			)
			(fill no)
			(layer "B.Fab")
		)
		(pad "1" smd roundrect
			(at -0.485 0 270)
			(size 0.59 0.64)
			(layers "B.Cu" "B.Mask" "B.Paste")
			(roundrect_rratio 0.25)
			(net 113 "/LPDDR5/LPDDR5_B.CK_N")
			(pintype "passive")
		)
		(pad "2" smd roundrect
			(at 0.485 0 270)
			(size 0.59 0.64)
			(layers "B.Cu" "B.Mask" "B.Paste")
			(roundrect_rratio 0.25)
			(net 14 "GND")
			(pintype "passive")
		)
	)
	(footprint "antmicro-footprints:R_0402_1005Metric"
		(layer "B.Cu")
		(at 108.25 79.7 90)
		(descr "Resistor SMD 0402")
		(tags "resistor SMD 0402")
		(property "Reference" "R27"
			(at -1 -0.55 90)
			(unlocked yes)
			(layer "B.SilkS")
			(effects
				(font
					(size 0.7 0.7)
					(thickness 0.15)
				)
				(justify right bottom mirror)
			)
		)
		(property "Value" "R_0R_0402"
			(at -1.011843 -1.772047 90)
			(layer "B.Fab")
			(effects
				(font
					(size 0.7 0.7)
					(thickness 0.15)
				)
				(justify right bottom mirror)
			)
		)
		(property "Author" "Antmicro"
			(at 187.95 -28.55 0)
			(layer "B.Fab")
			(hide yes)
			(effects
				(font
					(size 1 1)
					(thickness 0.15)
				)
				(justify mirror)
			)
		)
		(property "Current" "1A"
			(at 187.95 -28.55 0)
			(layer "B.Fab")
			(hide yes)
			(effects
				(font
					(size 1 1)
					(thickness 0.15)
				)
				(justify mirror)
			)
		)
		(property "License" "Apache-2.0"
			(at 187.95 -28.55 0)
			(layer "B.Fab")
			(hide yes)
			(effects
				(font
					(size 1 1)
					(thickness 0.15)
				)
				(justify mirror)
			)
		)
		(property "MPN" "ERJ2GE0R00X"
			(at 187.95 -28.55 0)
			(layer "B.Fab")
			(hide yes)
			(effects
				(font
					(size 1 1)
					(thickness 0.15)
				)
				(justify mirror)
			)
		)
		(property "Manufacturer" "Panasonic"
			(at 187.95 -28.55 0)
			(layer "B.Fab")
			(hide yes)
			(effects
				(font
					(size 1 1)
					(thickness 0.15)
				)
				(justify mirror)
			)
		)
		(property "Tolerance" ""
			(at 187.95 -28.55 0)
			(layer "B.Fab")
			(hide yes)
			(effects
				(font
					(size 1 1)
					(thickness 0.15)
				)
				(justify mirror)
			)
		)
		(property "Val" "0R"
			(at 187.95 -28.55 0)
			(layer "B.Fab")
			(hide yes)
			(effects
				(font
					(size 1 1)
					(thickness 0.15)
				)
				(justify mirror)
			)
		)
		(sheetname "SODIMM")
		(sheetfile "sodim.kicad_sch")
		(attr smd)
		(fp_rect
			(start -0.93 0.47)
			(end 0.93 -0.47)
			(stroke
				(width 0.05)
				(type solid)
			)
			(fill no)
			(layer "B.CrtYd")
		)
		(fp_rect
			(start -0.5 0.25)
			(end 0.5 -0.25)
			(stroke
				(width 0.15)
				(type solid)
			)
			(fill no)
			(layer "B.Fab")
		)
		(pad "1" smd roundrect
			(at -0.485 0 90)
			(size 0.59 0.64)
			(layers "B.Cu" "B.Mask" "B.Paste")
			(roundrect_rratio 0.25)
			(net 19 "/SODIMM/HSDA")
			(pintype "passive")
		)
		(pad "2" smd roundrect
			(at 0.485 0 90)
			(size 0.59 0.64)
			(layers "B.Cu" "B.Mask" "B.Paste")
			(roundrect_rratio 0.25)
			(net 38 "/Power supply/I2C.SDA")
			(pintype "passive")
		)
	)
	(footprint "antmicro-footprints:R_Array_4x0402_Panasonic_EXB28V"
		(layer "B.Cu")
		(at 108.85 93.8)
		(property "Reference" "R24"
			(at 0.95 1.8 0)
			(unlocked yes)
			(layer "B.SilkS")
			(effects
				(font
					(size 0.7 0.7)
					(thickness 0.15)
				)
				(justify left bottom mirror)
			)
		)
		(property "Value" "R_4x100R_0402_array"
			(at -1.5 -2 180)
			(layer "B.Fab")
			(effects
				(font
					(size 0.7 0.7)
					(thickness 0.15)
				)
				(justify left bottom mirror)
			)
		)
		(property "Author" "Antmicro"
			(at 0 0 0)
			(layer "B.Fab")
			(hide yes)
			(effects
				(font
					(size 1 1)
					(thickness 0.15)
				)
				(justify mirror)
			)
		)
		(property "License" "Apache-2.0"
			(at 0 0 0)
			(layer "B.Fab")
			(hide yes)
			(effects
				(font
					(size 1 1)
					(thickness 0.15)
				)
				(justify mirror)
			)
		)
		(property "MPN" "EXB-28V101JX"
			(at 0 0 0)
			(layer "B.Fab")
			(hide yes)
			(effects
				(font
					(size 1 1)
					(thickness 0.15)
				)
				(justify mirror)
			)
		)
		(property "Manufacturer" "Panasonic"
			(at 0 0 0)
			(layer "B.Fab")
			(hide yes)
			(effects
				(font
					(size 1 1)
					(thickness 0.15)
				)
				(justify mirror)
			)
		)
		(property "Val" "R_4x100R_0402"
			(at 0 0 0)
			(layer "B.Fab")
			(hide yes)
			(effects
				(font
					(size 1 1)
					(thickness 0.15)
				)
				(justify mirror)
			)
		)
		(sheetname "Translators")
		(sheetfile "translators.kicad_sch")
		(attr smd)
		(fp_line
			(start -1.25 0.5)
			(end -1.25 -0.498)
			(stroke
				(width 0.15)
				(type solid)
			)
			(layer "B.SilkS")
		)
		(fp_line
			(start 1.25 -0.499)
			(end 1.25 0.499)
			(stroke
				(width 0.15)
				(type solid)
			)
			(layer "B.SilkS")
		)
		(fp_rect
			(start -1.25 0.8)
			(end 1.25 -0.8)
			(stroke
				(width 0.05)
				(type solid)
			)
			(fill no)
			(layer "B.CrtYd")
		)
		(fp_line
			(start -1 -0.498)
			(end -1 0.5)
			(stroke
				(width 0.15)
				(type solid)
			)
			(layer "B.Fab")
		)
		(fp_line
			(start -1 0.5)
			(end 0.998 0.5)
			(stroke
				(width 0.15)
				(type solid)
			)
			(layer "B.Fab")
		)
		(fp_line
			(start 0.998 -0.498)
			(end -1 -0.498)
			(stroke
				(width 0.15)
				(type solid)
			)
			(layer "B.Fab")
		)
		(fp_line
			(start 0.998 0.5)
			(end 0.998 -0.498)
			(stroke
				(width 0.15)
				(type solid)
			)
			(layer "B.Fab")
		)
		(pad "1" smd roundrect
			(at -0.8875 -0.45)
			(size 0.525 0.5)
			(layers "B.Cu" "B.Mask" "B.Paste")
			(roundrect_rratio 0.25)
			(net 191 "/LPDDR5/LPDDR5_A.DQ15")
			(pinfunction "R1.1")
			(pintype "passive")
		)
		(pad "2" smd roundrect
			(at -0.25 -0.45)
			(size 0.25 0.5)
			(layers "B.Cu" "B.Mask" "B.Paste")
			(roundrect_rratio 0.25)
			(net 192 "/LPDDR5/LPDDR5_A.DQ14")
			(pinfunction "R2.1")
			(pintype "passive")
		)
		(pad "3" smd roundrect
			(at 0.25 -0.45)
			(size 0.25 0.5)
			(layers "B.Cu" "B.Mask" "B.Paste")
			(roundrect_rratio 0.25)
			(net 193 "/LPDDR5/LPDDR5_A.DQ12")
			(pinfunction "R3.1")
			(pintype "passive")
		)
		(pad "4" smd roundrect
			(at 0.8875 -0.45)
			(size 0.525 0.5)
			(layers "B.Cu" "B.Mask" "B.Paste")
			(roundrect_rratio 0.25)
			(net 194 "/LPDDR5/LPDDR5_A.DQ13")
			(pinfunction "R4.1")
			(pintype "passive")
		)
		(pad "5" smd roundrect
			(at 0.8875 0.45)
			(size 0.525 0.5)
			(layers "B.Cu" "B.Mask" "B.Paste")
			(roundrect_rratio 0.25)
			(net 14 "GND")
			(pinfunction "R4.2")
			(pintype "passive")
		)
		(pad "6" smd roundrect
			(at 0.25 0.45)
			(size 0.25 0.5)
			(layers "B.Cu" "B.Mask" "B.Paste")
			(roundrect_rratio 0.25)
			(net 14 "GND")
			(pinfunction "R3.2")
			(pintype "passive")
		)
		(pad "7" smd roundrect
			(at -0.25 0.45)
			(size 0.25 0.5)
			(layers "B.Cu" "B.Mask" "B.Paste")
			(roundrect_rratio 0.25)
			(net 14 "GND")
			(pinfunction "R2.2")
			(pintype "passive")
		)
		(pad "8" smd roundrect
			(at -0.8875 0.45)
			(size 0.525 0.5)
			(layers "B.Cu" "B.Mask" "B.Paste")
			(roundrect_rratio 0.25)
			(net 14 "GND")
			(pinfunction "R1.2")
			(pintype "passive")
		)
	)
	(footprint "antmicro-footprints:R_0402_1005Metric"
		(layer "B.Cu")
		(at 118.13 90.94 90)
		(descr "Resistor SMD 0402")
		(tags "resistor SMD 0402")
		(property "Reference" "R12"
			(at -1.36 1.37 90)
			(unlocked yes)
			(layer "B.SilkS")
			(effects
				(font
					(size 0.7 0.7)
					(thickness 0.15)
				)
				(justify right bottom mirror)
			)
		)
		(property "Value" "R_100R_0402"
			(at -1.011843 -1.772047 90)
			(layer "B.Fab")
			(effects
				(font
					(size 0.7 0.7)
					(thickness 0.15)
				)
				(justify right bottom mirror)
			)
		)
		(property "Author" "Antmicro"
			(at 209.07 -27.19 0)
			(layer "B.Fab")
			(hide yes)
			(effects
				(font
					(size 1 1)
					(thickness 0.15)
				)
				(justify mirror)
			)
		)
		(property "License" "Apache-2.0"
			(at 209.07 -27.19 0)
			(layer "B.Fab")
			(hide yes)
			(effects
				(font
					(size 1 1)
					(thickness 0.15)
				)
				(justify mirror)
			)
		)
		(property "MPN" "CR0402-FX-1000GLF"
			(at 209.07 -27.19 0)
			(layer "B.Fab")
			(hide yes)
			(effects
				(font
					(size 1 1)
					(thickness 0.15)
				)
				(justify mirror)
			)
		)
		(property "Manufacturer" "Bourns"
			(at 209.07 -27.19 0)
			(layer "B.Fab")
			(hide yes)
			(effects
				(font
					(size 1 1)
					(thickness 0.15)
				)
				(justify mirror)
			)
		)
		(property "Tolerance" "1%"
			(at 209.07 -27.19 0)
			(layer "B.Fab")
			(hide yes)
			(effects
				(font
					(size 1 1)
					(thickness 0.15)
				)
				(justify mirror)
			)
		)
		(property "Val" "100R"
			(at 209.07 -27.19 0)
			(layer "B.Fab")
			(hide yes)
			(effects
				(font
					(size 1 1)
					(thickness 0.15)
				)
				(justify mirror)
			)
		)
		(sheetname "Translators")
		(sheetfile "translators.kicad_sch")
		(attr smd)
		(fp_rect
			(start -0.93 0.47)
			(end 0.93 -0.47)
			(stroke
				(width 0.05)
				(type solid)
			)
			(fill no)
			(layer "B.CrtYd")
		)
		(fp_rect
			(start -0.5 0.25)
			(end 0.5 -0.25)
			(stroke
				(width 0.15)
				(type solid)
			)
			(fill no)
			(layer "B.Fab")
		)
		(pad "1" smd roundrect
			(at -0.485 0 90)
			(size 0.59 0.64)
			(layers "B.Cu" "B.Mask" "B.Paste")
			(roundrect_rratio 0.25)
			(net 170 "/SODIMM/LPDDR5_IN_A.WCK0_P")
			(pintype "passive")
		)
		(pad "2" smd roundrect
			(at 0.485 0 90)
			(size 0.59 0.64)
			(layers "B.Cu" "B.Mask" "B.Paste")
			(roundrect_rratio 0.25)
			(net 45 "/LPDDR5/LPDDR5_A.WCK0_P")
			(pintype "passive")
		)
	)
	(footprint "antmicro-footprints:C_0402_1005Metric"
		(layer "B.Cu")
		(at 104.875 70.641 -90)
		(descr "Capacitor SMD 0402")
		(tags "capacitor SMD 0402")
		(property "Reference" "C12"
			(at -1.141 0.675 90)
			(unlocked yes)
			(layer "B.SilkS")
			(effects
				(font
					(size 0.7 0.7)
					(thickness 0.15)
				)
				(justify left bottom mirror)
			)
		)
		(property "Value" "C_1u_0402"
			(at -1.022927 -2.155213 90)
			(layer "B.Fab")
			(effects
				(font
					(size 0.7 0.7)
					(thickness 0.15)
				)
				(justify left bottom mirror)
			)
		)
		(property "Author" "Antmicro"
			(at 34.234 175.516 0)
			(layer "B.Fab")
			(hide yes)
			(effects
				(font
					(size 1 1)
					(thickness 0.15)
				)
				(justify mirror)
			)
		)
		(property "Dielectric" ""
			(at 34.234 175.516 0)
			(layer "B.Fab")
			(hide yes)
			(effects
				(font
					(size 1 1)
					(thickness 0.15)
				)
				(justify mirror)
			)
		)
		(property "License" "Apache-2.0"
			(at 34.234 175.516 0)
			(layer "B.Fab")
			(hide yes)
			(effects
				(font
					(size 1 1)
					(thickness 0.15)
				)
				(justify mirror)
			)
		)
		(property "MPN" "C1005X6S1A105K050BC"
			(at 34.234 175.516 0)
			(layer "B.Fab")
			(hide yes)
			(effects
				(font
					(size 1 1)
					(thickness 0.15)
				)
				(justify mirror)
			)
		)
		(property "Manufacturer" "TDK"
			(at 34.234 175.516 0)
			(layer "B.Fab")
			(hide yes)
			(effects
				(font
					(size 1 1)
					(thickness 0.15)
				)
				(justify mirror)
			)
		)
		(property "Val" "1u"
			(at 34.234 175.516 0)
			(layer "B.Fab")
			(hide yes)
			(effects
				(font
					(size 1 1)
					(thickness 0.15)
				)
				(justify mirror)
			)
		)
		(property "Voltage" ""
			(at 34.234 175.516 0)
			(layer "B.Fab")
			(hide yes)
			(effects
				(font
					(size 1 1)
					(thickness 0.15)
				)
				(justify mirror)
			)
		)
		(sheetname "Power supply")
		(sheetfile "power_supply.kicad_sch")
		(attr smd)
		(fp_rect
			(start -0.9659 0.481258)
			(end 0.9649 -0.458742)
			(stroke
				(width 0.05)
				(type solid)
			)
			(fill no)
			(layer "B.CrtYd")
		)
		(fp_line
			(start -0.499 0.25)
			(end 0.499 0.25)
			(stroke
				(width 0.15)
				(type solid)
			)
			(layer "B.Fab")
		)
		(fp_line
			(start 0.499 0.25)
			(end 0.499 -0.248)
			(stroke
				(width 0.15)
				(type solid)
			)
			(layer "B.Fab")
		)
		(fp_line
			(start -0.499 -0.248)
			(end -0.499 0.25)
			(stroke
				(width 0.15)
				(type solid)
			)
			(layer "B.Fab")
		)
		(fp_line
			(start 0.499 -0.248)
			(end -0.499 -0.248)
			(stroke
				(width 0.15)
				(type solid)
			)
			(layer "B.Fab")
		)
		(pad "1" smd roundrect
			(at -0.484 0 270)
			(size 0.59 0.64)
			(layers "B.Cu" "B.Mask" "B.Paste")
			(roundrect_rratio 0.25)
			(net 14 "GND")
			(pintype "passive")
		)
		(pad "2" smd roundrect
			(at 0.484 0 270)
			(size 0.59 0.64)
			(layers "B.Cu" "B.Mask" "B.Paste")
			(roundrect_rratio 0.25)
			(net 117 "Net-(C12-Pad2)")
			(pintype "passive")
		)
	)
	(footprint "antmicro-footprints:R_0402_1005Metric"
		(layer "B.Cu")
		(at 155.9 92)
		(descr "Resistor SMD 0402")
		(tags "resistor SMD 0402")
		(property "Reference" "R91"
			(at 1 -0.2 0)
			(unlocked yes)
			(layer "B.SilkS")
			(effects
				(font
					(size 0.7 0.7)
					(thickness 0.15)
				)
				(justify right bottom mirror)
			)
		)
		(property "Value" "R_100R_0402"
			(at -1.011843 -1.772047 0)
			(layer "B.Fab")
			(effects
				(font
					(size 0.7 0.7)
					(thickness 0.15)
				)
				(justify right bottom mirror)
			)
		)
		(property "Author" "Antmicro"
			(at 0 0 0)
			(layer "B.Fab")
			(hide yes)
			(effects
				(font
					(size 1 1)
					(thickness 0.15)
				)
				(justify mirror)
			)
		)
		(property "License" "Apache-2.0"
			(at 0 0 0)
			(layer "B.Fab")
			(hide yes)
			(effects
				(font
					(size 1 1)
					(thickness 0.15)
				)
				(justify mirror)
			)
		)
		(property "MPN" "CR0402-FX-1000GLF"
			(at 0 0 0)
			(layer "B.Fab")
			(hide yes)
			(effects
				(font
					(size 1 1)
					(thickness 0.15)
				)
				(justify mirror)
			)
		)
		(property "Manufacturer" "Bourns"
			(at 0 0 0)
			(layer "B.Fab")
			(hide yes)
			(effects
				(font
					(size 1 1)
					(thickness 0.15)
				)
				(justify mirror)
			)
		)
		(property "Tolerance" "1%"
			(at 0 0 0)
			(layer "B.Fab")
			(hide yes)
			(effects
				(font
					(size 1 1)
					(thickness 0.15)
				)
				(justify mirror)
			)
		)
		(property "Val" "100R"
			(at 0 0 0)
			(layer "B.Fab")
			(hide yes)
			(effects
				(font
					(size 1 1)
					(thickness 0.15)
				)
				(justify mirror)
			)
		)
		(sheetname "Translators1")
		(sheetfile "translators.kicad_sch")
		(attr smd)
		(fp_rect
			(start -0.93 0.47)
			(end 0.93 -0.47)
			(stroke
				(width 0.05)
				(type solid)
			)
			(fill no)
			(layer "B.CrtYd")
		)
		(fp_rect
			(start -0.5 0.25)
			(end 0.5 -0.25)
			(stroke
				(width 0.15)
				(type solid)
			)
			(fill no)
			(layer "B.Fab")
		)
		(pad "1" smd roundrect
			(at -0.485 0)
			(size 0.59 0.64)
			(layers "B.Cu" "B.Mask" "B.Paste")
			(roundrect_rratio 0.25)
			(net 223 "/LPDDR5/LPDDR5_B.DMI1")
			(pintype "passive")
		)
		(pad "2" smd roundrect
			(at 0.485 0)
			(size 0.59 0.64)
			(layers "B.Cu" "B.Mask" "B.Paste")
			(roundrect_rratio 0.25)
			(net 14 "GND")
			(pintype "passive")
		)
	)
	(footprint "antmicro-footprints:R_Array_4x0402_Panasonic_EXB28V"
		(layer "B.Cu")
		(at 166.2 93.8)
		(property "Reference" "R72"
			(at -1.1 1.8 0)
			(unlocked yes)
			(layer "B.SilkS")
			(effects
				(font
					(size 0.7 0.7)
					(thickness 0.15)
				)
				(justify right bottom mirror)
			)
		)
		(property "Value" "R_4x100R_0402_array"
			(at -1.5 -2 0)
			(layer "B.Fab")
			(effects
				(font
					(size 0.7 0.7)
					(thickness 0.15)
				)
				(justify right bottom mirror)
			)
		)
		(property "Author" "Antmicro"
			(at 0 0 0)
			(layer "B.Fab")
			(hide yes)
			(effects
				(font
					(size 1 1)
					(thickness 0.15)
				)
				(justify mirror)
			)
		)
		(property "License" "Apache-2.0"
			(at 0 0 0)
			(layer "B.Fab")
			(hide yes)
			(effects
				(font
					(size 1 1)
					(thickness 0.15)
				)
				(justify mirror)
			)
		)
		(property "MPN" "EXB-28V101JX"
			(at 0 0 0)
			(layer "B.Fab")
			(hide yes)
			(effects
				(font
					(size 1 1)
					(thickness 0.15)
				)
				(justify mirror)
			)
		)
		(property "Manufacturer" "Panasonic"
			(at 0 0 0)
			(layer "B.Fab")
			(hide yes)
			(effects
				(font
					(size 1 1)
					(thickness 0.15)
				)
				(justify mirror)
			)
		)
		(property "Val" "R_4x100R_0402"
			(at 0 0 0)
			(layer "B.Fab")
			(hide yes)
			(effects
				(font
					(size 1 1)
					(thickness 0.15)
				)
				(justify mirror)
			)
		)
		(sheetname "Translators1")
		(sheetfile "translators.kicad_sch")
		(attr smd)
		(fp_line
			(start -1.25 0.5)
			(end -1.25 -0.498)
			(stroke
				(width 0.15)
				(type solid)
			)
			(layer "B.SilkS")
		)
		(fp_line
			(start 1.25 -0.499)
			(end 1.25 0.499)
			(stroke
				(width 0.15)
				(type solid)
			)
			(layer "B.SilkS")
		)
		(fp_rect
			(start -1.25 0.8)
			(end 1.25 -0.8)
			(stroke
				(width 0.05)
				(type solid)
			)
			(fill no)
			(layer "B.CrtYd")
		)
		(fp_line
			(start -1 -0.498)
			(end -1 0.5)
			(stroke
				(width 0.15)
				(type solid)
			)
			(layer "B.Fab")
		)
		(fp_line
			(start -1 0.5)
			(end 0.998 0.5)
			(stroke
				(width 0.15)
				(type solid)
			)
			(layer "B.Fab")
		)
		(fp_line
			(start 0.998 -0.498)
			(end -1 -0.498)
			(stroke
				(width 0.15)
				(type solid)
			)
			(layer "B.Fab")
		)
		(fp_line
			(start 0.998 0.5)
			(end 0.998 -0.498)
			(stroke
				(width 0.15)
				(type solid)
			)
			(layer "B.Fab")
		)
		(pad "1" smd roundrect
			(at -0.8875 -0.45)
			(size 0.525 0.5)
			(layers "B.Cu" "B.Mask" "B.Paste")
			(roundrect_rratio 0.25)
			(net 224 "/LPDDR5/LPDDR5_B.DQ3")
			(pinfunction "R1.1")
			(pintype "passive")
		)
		(pad "2" smd roundrect
			(at -0.25 -0.45)
			(size 0.25 0.5)
			(layers "B.Cu" "B.Mask" "B.Paste")
			(roundrect_rratio 0.25)
			(net 226 "/LPDDR5/LPDDR5_B.DQ1")
			(pinfunction "R2.1")
			(pintype "passive")
		)
		(pad "3" smd roundrect
			(at 0.25 -0.45)
			(size 0.25 0.5)
			(layers "B.Cu" "B.Mask" "B.Paste")
			(roundrect_rratio 0.25)
			(net 225 "/LPDDR5/LPDDR5_B.DQ2")
			(pinfunction "R3.1")
			(pintype "passive")
		)
		(pad "4" smd roundrect
			(at 0.8875 -0.45)
			(size 0.525 0.5)
			(layers "B.Cu" "B.Mask" "B.Paste")
			(roundrect_rratio 0.25)
			(net 227 "/LPDDR5/LPDDR5_B.DQ0")
			(pinfunction "R4.1")
			(pintype "passive")
		)
		(pad "5" smd roundrect
			(at 0.8875 0.45)
			(size 0.525 0.5)
			(layers "B.Cu" "B.Mask" "B.Paste")
			(roundrect_rratio 0.25)
			(net 14 "GND")
			(pinfunction "R4.2")
			(pintype "passive")
		)
		(pad "6" smd roundrect
			(at 0.25 0.45)
			(size 0.25 0.5)
			(layers "B.Cu" "B.Mask" "B.Paste")
			(roundrect_rratio 0.25)
			(net 14 "GND")
			(pinfunction "R3.2")
			(pintype "passive")
		)
		(pad "7" smd roundrect
			(at -0.25 0.45)
			(size 0.25 0.5)
			(layers "B.Cu" "B.Mask" "B.Paste")
			(roundrect_rratio 0.25)
			(net 14 "GND")
			(pinfunction "R2.2")
			(pintype "passive")
		)
		(pad "8" smd roundrect
			(at -0.8875 0.45)
			(size 0.525 0.5)
			(layers "B.Cu" "B.Mask" "B.Paste")
			(roundrect_rratio 0.25)
			(net 14 "GND")
			(pinfunction "R1.2")
			(pintype "passive")
		)
	)
	(footprint "antmicro-footprints:C_0402_1005Metric"
		(layer "B.Cu")
		(at 140.375 73.75)
		(descr "Capacitor SMD 0402")
		(tags "capacitor SMD 0402")
		(property "Reference" "C41"
			(at 1.125 0.35 0)
			(unlocked yes)
			(layer "B.SilkS")
			(effects
				(font
					(size 0.7 0.7)
					(thickness 0.15)
				)
				(justify right bottom mirror)
			)
		)
		(property "Value" "C_4u7_0402"
			(at -1.022927 -2.155213 0)
			(layer "B.Fab")
			(effects
				(font
					(size 0.7 0.7)
					(thickness 0.15)
				)
				(justify right bottom mirror)
			)
		)
		(property "Author" "Antmicro"
			(at 0 0 0)
			(layer "B.Fab")
			(hide yes)
			(effects
				(font
					(size 1 1)
					(thickness 0.15)
				)
				(justify mirror)
			)
		)
		(property "Dielectric" ""
			(at 0 0 0)
			(layer "B.Fab")
			(hide yes)
			(effects
				(font
					(size 1 1)
					(thickness 0.15)
				)
				(justify mirror)
			)
		)
		(property "License" "Apache-2.0"
			(at 0 0 0)
			(layer "B.Fab")
			(hide yes)
			(effects
				(font
					(size 1 1)
					(thickness 0.15)
				)
				(justify mirror)
			)
		)
		(property "MPN" "GRM155R61A475MEAAD"
			(at 0 0 0)
			(layer "B.Fab")
			(hide yes)
			(effects
				(font
					(size 1 1)
					(thickness 0.15)
				)
				(justify mirror)
			)
		)
		(property "Manufacturer" "Murata"
			(at 0 0 0)
			(layer "B.Fab")
			(hide yes)
			(effects
				(font
					(size 1 1)
					(thickness 0.15)
				)
				(justify mirror)
			)
		)
		(property "Val" "4u7"
			(at 0 0 0)
			(layer "B.Fab")
			(hide yes)
			(effects
				(font
					(size 1 1)
					(thickness 0.15)
				)
				(justify mirror)
			)
		)
		(property "Voltage" ""
			(at 0 0 0)
			(layer "B.Fab")
			(hide yes)
			(effects
				(font
					(size 1 1)
					(thickness 0.15)
				)
				(justify mirror)
			)
		)
		(sheetname "LPDDR5")
		(sheetfile "lpddr5.kicad_sch")
		(attr smd)
		(fp_rect
			(start -0.9659 0.481258)
			(end 0.9649 -0.458742)
			(stroke
				(width 0.05)
				(type solid)
			)
			(fill no)
			(layer "B.CrtYd")
		)
		(fp_line
			(start -0.499 -0.248)
			(end -0.499 0.25)
			(stroke
				(width 0.15)
				(type solid)
			)
			(layer "B.Fab")
		)
		(fp_line
			(start -0.499 0.25)
			(end 0.499 0.25)
			(stroke
				(width 0.15)
				(type solid)
			)
			(layer "B.Fab")
		)
		(fp_line
			(start 0.499 -0.248)
			(end -0.499 -0.248)
			(stroke
				(width 0.15)
				(type solid)
			)
			(layer "B.Fab")
		)
		(fp_line
			(start 0.499 0.25)
			(end 0.499 -0.248)
			(stroke
				(width 0.15)
				(type solid)
			)
			(layer "B.Fab")
		)
		(pad "1" smd roundrect
			(at -0.484 0)
			(size 0.59 0.64)
			(layers "B.Cu" "B.Mask" "B.Paste")
			(roundrect_rratio 0.25)
			(net 14 "GND")
			(pintype "passive")
		)
		(pad "2" smd roundrect
			(at 0.484 0)
			(size 0.59 0.64)
			(layers "B.Cu" "B.Mask" "B.Paste")
			(roundrect_rratio 0.25)
			(net 35 "+1V8")
			(pintype "passive")
		)
	)
	(footprint "antmicro-footprints:C_0402_1005Metric"
		(layer "B.Cu")
		(at 131.275 82.45 180)
		(descr "Capacitor SMD 0402")
		(tags "capacitor SMD 0402")
		(property "Reference" "C46"
			(at -3.025 -0.45 0)
			(unlocked yes)
			(layer "B.SilkS")
			(effects
				(font
					(size 0.7 0.7)
					(thickness 0.15)
				)
				(justify left bottom mirror)
			)
		)
		(property "Value" "C_4u7_0402"
			(at -1.022927 -2.155213 0)
			(layer "B.Fab")
			(effects
				(font
					(size 0.7 0.7)
					(thickness 0.15)
				)
				(justify left bottom mirror)
			)
		)
		(property "Author" "Antmicro"
			(at 262.55 164.9 0)
			(layer "B.Fab")
			(hide yes)
			(effects
				(font
					(size 1 1)
					(thickness 0.15)
				)
				(justify mirror)
			)
		)
		(property "Dielectric" ""
			(at 262.55 164.9 0)
			(layer "B.Fab")
			(hide yes)
			(effects
				(font
					(size 1 1)
					(thickness 0.15)
				)
				(justify mirror)
			)
		)
		(property "License" "Apache-2.0"
			(at 262.55 164.9 0)
			(layer "B.Fab")
			(hide yes)
			(effects
				(font
					(size 1 1)
					(thickness 0.15)
				)
				(justify mirror)
			)
		)
		(property "MPN" "GRM155R61A475MEAAD"
			(at 262.55 164.9 0)
			(layer "B.Fab")
			(hide yes)
			(effects
				(font
					(size 1 1)
					(thickness 0.15)
				)
				(justify mirror)
			)
		)
		(property "Manufacturer" "Murata"
			(at 262.55 164.9 0)
			(layer "B.Fab")
			(hide yes)
			(effects
				(font
					(size 1 1)
					(thickness 0.15)
				)
				(justify mirror)
			)
		)
		(property "Val" "4u7"
			(at 262.55 164.9 0)
			(layer "B.Fab")
			(hide yes)
			(effects
				(font
					(size 1 1)
					(thickness 0.15)
				)
				(justify mirror)
			)
		)
		(property "Voltage" ""
			(at 262.55 164.9 0)
			(layer "B.Fab")
			(hide yes)
			(effects
				(font
					(size 1 1)
					(thickness 0.15)
				)
				(justify mirror)
			)
		)
		(sheetname "LPDDR5")
		(sheetfile "lpddr5.kicad_sch")
		(attr smd)
		(fp_rect
			(start -0.9659 0.481258)
			(end 0.9649 -0.458742)
			(stroke
				(width 0.05)
				(type solid)
			)
			(fill no)
			(layer "B.CrtYd")
		)
		(fp_line
			(start 0.499 0.25)
			(end 0.499 -0.248)
			(stroke
				(width 0.15)
				(type solid)
			)
			(layer "B.Fab")
		)
		(fp_line
			(start 0.499 -0.248)
			(end -0.499 -0.248)
			(stroke
				(width 0.15)
				(type solid)
			)
			(layer "B.Fab")
		)
		(fp_line
			(start -0.499 0.25)
			(end 0.499 0.25)
			(stroke
				(width 0.15)
				(type solid)
			)
			(layer "B.Fab")
		)
		(fp_line
			(start -0.499 -0.248)
			(end -0.499 0.25)
			(stroke
				(width 0.15)
				(type solid)
			)
			(layer "B.Fab")
		)
		(pad "1" smd roundrect
			(at -0.484 0 180)
			(size 0.59 0.64)
			(layers "B.Cu" "B.Mask" "B.Paste")
			(roundrect_rratio 0.25)
			(net 14 "GND")
			(pintype "passive")
		)
		(pad "2" smd roundrect
			(at 0.484 0 180)
			(size 0.59 0.64)
			(layers "B.Cu" "B.Mask" "B.Paste")
			(roundrect_rratio 0.25)
			(net 4 "+0V5")
			(pintype "passive")
		)
	)
	(footprint "antmicro-footprints:R_Array_4x0402_Panasonic_EXB28V"
		(layer "B.Cu")
		(at 162.7125 93.8)
		(property "Reference" "R73"
			(at -1.1 1.8 0)
			(unlocked yes)
			(layer "B.SilkS")
			(effects
				(font
					(size 0.7 0.7)
					(thickness 0.15)
				)
				(justify right bottom mirror)
			)
		)
		(property "Value" "R_4x100R_0402_array"
			(at -1.5 -2 0)
			(layer "B.Fab")
			(effects
				(font
					(size 0.7 0.7)
					(thickness 0.15)
				)
				(justify right bottom mirror)
			)
		)
		(property "Author" "Antmicro"
			(at 0 0 0)
			(layer "B.Fab")
			(hide yes)
			(effects
				(font
					(size 1 1)
					(thickness 0.15)
				)
				(justify mirror)
			)
		)
		(property "License" "Apache-2.0"
			(at 0 0 0)
			(layer "B.Fab")
			(hide yes)
			(effects
				(font
					(size 1 1)
					(thickness 0.15)
				)
				(justify mirror)
			)
		)
		(property "MPN" "EXB-28V101JX"
			(at 0 0 0)
			(layer "B.Fab")
			(hide yes)
			(effects
				(font
					(size 1 1)
					(thickness 0.15)
				)
				(justify mirror)
			)
		)
		(property "Manufacturer" "Panasonic"
			(at 0 0 0)
			(layer "B.Fab")
			(hide yes)
			(effects
				(font
					(size 1 1)
					(thickness 0.15)
				)
				(justify mirror)
			)
		)
		(property "Val" "R_4x100R_0402"
			(at 0 0 0)
			(layer "B.Fab")
			(hide yes)
			(effects
				(font
					(size 1 1)
					(thickness 0.15)
				)
				(justify mirror)
			)
		)
		(sheetname "Translators1")
		(sheetfile "translators.kicad_sch")
		(attr smd)
		(fp_line
			(start -1.25 0.5)
			(end -1.25 -0.498)
			(stroke
				(width 0.15)
				(type solid)
			)
			(layer "B.SilkS")
		)
		(fp_line
			(start 1.25 -0.499)
			(end 1.25 0.499)
			(stroke
				(width 0.15)
				(type solid)
			)
			(layer "B.SilkS")
		)
		(fp_rect
			(start -1.25 0.8)
			(end 1.25 -0.8)
			(stroke
				(width 0.05)
				(type solid)
			)
			(fill no)
			(layer "B.CrtYd")
		)
		(fp_line
			(start -1 -0.498)
			(end -1 0.5)
			(stroke
				(width 0.15)
				(type solid)
			)
			(layer "B.Fab")
		)
		(fp_line
			(start -1 0.5)
			(end 0.998 0.5)
			(stroke
				(width 0.15)
				(type solid)
			)
			(layer "B.Fab")
		)
		(fp_line
			(start 0.998 -0.498)
			(end -1 -0.498)
			(stroke
				(width 0.15)
				(type solid)
			)
			(layer "B.Fab")
		)
		(fp_line
			(start 0.998 0.5)
			(end 0.998 -0.498)
			(stroke
				(width 0.15)
				(type solid)
			)
			(layer "B.Fab")
		)
		(pad "1" smd roundrect
			(at -0.8875 -0.45)
			(size 0.525 0.5)
			(layers "B.Cu" "B.Mask" "B.Paste")
			(roundrect_rratio 0.25)
			(net 219 "/LPDDR5/LPDDR5_B.DQ5")
			(pinfunction "R1.1")
			(pintype "passive")
		)
		(pad "2" smd roundrect
			(at -0.25 -0.45)
			(size 0.25 0.5)
			(layers "B.Cu" "B.Mask" "B.Paste")
			(roundrect_rratio 0.25)
			(net 220 "/LPDDR5/LPDDR5_B.DQ4")
			(pinfunction "R2.1")
			(pintype "passive")
		)
		(pad "3" smd roundrect
			(at 0.25 -0.45)
			(size 0.25 0.5)
			(layers "B.Cu" "B.Mask" "B.Paste")
			(roundrect_rratio 0.25)
			(net 218 "/LPDDR5/LPDDR5_B.DQ6")
			(pinfunction "R3.1")
			(pintype "passive")
		)
		(pad "4" smd roundrect
			(at 0.8875 -0.45)
			(size 0.525 0.5)
			(layers "B.Cu" "B.Mask" "B.Paste")
			(roundrect_rratio 0.25)
			(net 217 "/LPDDR5/LPDDR5_B.DQ7")
			(pinfunction "R4.1")
			(pintype "passive")
		)
		(pad "5" smd roundrect
			(at 0.8875 0.45)
			(size 0.525 0.5)
			(layers "B.Cu" "B.Mask" "B.Paste")
			(roundrect_rratio 0.25)
			(net 14 "GND")
			(pinfunction "R4.2")
			(pintype "passive")
		)
		(pad "6" smd roundrect
			(at 0.25 0.45)
			(size 0.25 0.5)
			(layers "B.Cu" "B.Mask" "B.Paste")
			(roundrect_rratio 0.25)
			(net 14 "GND")
			(pinfunction "R3.2")
			(pintype "passive")
		)
		(pad "7" smd roundrect
			(at -0.25 0.45)
			(size 0.25 0.5)
			(layers "B.Cu" "B.Mask" "B.Paste")
			(roundrect_rratio 0.25)
			(net 14 "GND")
			(pinfunction "R2.2")
			(pintype "passive")
		)
		(pad "8" smd roundrect
			(at -0.8875 0.45)
			(size 0.525 0.5)
			(layers "B.Cu" "B.Mask" "B.Paste")
			(roundrect_rratio 0.25)
			(net 14 "GND")
			(pinfunction "R1.2")
			(pintype "passive")
		)
	)
	(footprint "antmicro-footprints:C_0402_1005Metric"
		(layer "B.Cu")
		(at 138.275 82.45)
		(descr "Capacitor SMD 0402")
		(tags "capacitor SMD 0402")
		(property "Reference" "C48"
			(at 0.925 0.45 0)
			(unlocked yes)
			(layer "B.SilkS")
			(effects
				(font
					(size 0.7 0.7)
					(thickness 0.15)
				)
				(justify right bottom mirror)
			)
		)
		(property "Value" "C_4u7_0402"
			(at -1.022927 -2.155213 0)
			(layer "B.Fab")
			(effects
				(font
					(size 0.7 0.7)
					(thickness 0.15)
				)
				(justify right bottom mirror)
			)
		)
		(property "Author" "Antmicro"
			(at 0 0 0)
			(layer "B.Fab")
			(hide yes)
			(effects
				(font
					(size 1 1)
					(thickness 0.15)
				)
				(justify mirror)
			)
		)
		(property "Dielectric" ""
			(at 0 0 0)
			(layer "B.Fab")
			(hide yes)
			(effects
				(font
					(size 1 1)
					(thickness 0.15)
				)
				(justify mirror)
			)
		)
		(property "License" "Apache-2.0"
			(at 0 0 0)
			(layer "B.Fab")
			(hide yes)
			(effects
				(font
					(size 1 1)
					(thickness 0.15)
				)
				(justify mirror)
			)
		)
		(property "MPN" "GRM155R61A475MEAAD"
			(at 0 0 0)
			(layer "B.Fab")
			(hide yes)
			(effects
				(font
					(size 1 1)
					(thickness 0.15)
				)
				(justify mirror)
			)
		)
		(property "Manufacturer" "Murata"
			(at 0 0 0)
			(layer "B.Fab")
			(hide yes)
			(effects
				(font
					(size 1 1)
					(thickness 0.15)
				)
				(justify mirror)
			)
		)
		(property "Val" "4u7"
			(at 0 0 0)
			(layer "B.Fab")
			(hide yes)
			(effects
				(font
					(size 1 1)
					(thickness 0.15)
				)
				(justify mirror)
			)
		)
		(property "Voltage" ""
			(at 0 0 0)
			(layer "B.Fab")
			(hide yes)
			(effects
				(font
					(size 1 1)
					(thickness 0.15)
				)
				(justify mirror)
			)
		)
		(sheetname "LPDDR5")
		(sheetfile "lpddr5.kicad_sch")
		(attr smd)
		(fp_rect
			(start -0.9659 0.481258)
			(end 0.9649 -0.458742)
			(stroke
				(width 0.05)
				(type solid)
			)
			(fill no)
			(layer "B.CrtYd")
		)
		(fp_line
			(start -0.499 -0.248)
			(end -0.499 0.25)
			(stroke
				(width 0.15)
				(type solid)
			)
			(layer "B.Fab")
		)
		(fp_line
			(start -0.499 0.25)
			(end 0.499 0.25)
			(stroke
				(width 0.15)
				(type solid)
			)
			(layer "B.Fab")
		)
		(fp_line
			(start 0.499 -0.248)
			(end -0.499 -0.248)
			(stroke
				(width 0.15)
				(type solid)
			)
			(layer "B.Fab")
		)
		(fp_line
			(start 0.499 0.25)
			(end 0.499 -0.248)
			(stroke
				(width 0.15)
				(type solid)
			)
			(layer "B.Fab")
		)
		(pad "1" smd roundrect
			(at -0.484 0)
			(size 0.59 0.64)
			(layers "B.Cu" "B.Mask" "B.Paste")
			(roundrect_rratio 0.25)
			(net 14 "GND")
			(pintype "passive")
		)
		(pad "2" smd roundrect
			(at 0.484 0)
			(size 0.59 0.64)
			(layers "B.Cu" "B.Mask" "B.Paste")
			(roundrect_rratio 0.25)
			(net 4 "+0V5")
			(pintype "passive")
		)
	)
	(footprint "antmicro-footprints:R_Array_4x0402_Panasonic_EXB28V"
		(layer "B.Cu")
		(at 127.7 93.8)
		(property "Reference" "R21"
			(at 1.1 -1.3 0)
			(unlocked yes)
			(layer "B.SilkS")
			(effects
				(font
					(size 0.7 0.7)
					(thickness 0.15)
				)
				(justify left bottom mirror)
			)
		)
		(property "Value" "R_4x100R_0402_array"
			(at -1.5 -2 180)
			(layer "B.Fab")
			(effects
				(font
					(size 0.7 0.7)
					(thickness 0.15)
				)
				(justify left bottom mirror)
			)
		)
		(property "Author" "Antmicro"
			(at 0 0 0)
			(layer "B.Fab")
			(hide yes)
			(effects
				(font
					(size 1 1)
					(thickness 0.15)
				)
				(justify mirror)
			)
		)
		(property "License" "Apache-2.0"
			(at 0 0 0)
			(layer "B.Fab")
			(hide yes)
			(effects
				(font
					(size 1 1)
					(thickness 0.15)
				)
				(justify mirror)
			)
		)
		(property "MPN" "EXB-28V101JX"
			(at 0 0 0)
			(layer "B.Fab")
			(hide yes)
			(effects
				(font
					(size 1 1)
					(thickness 0.15)
				)
				(justify mirror)
			)
		)
		(property "Manufacturer" "Panasonic"
			(at 0 0 0)
			(layer "B.Fab")
			(hide yes)
			(effects
				(font
					(size 1 1)
					(thickness 0.15)
				)
				(justify mirror)
			)
		)
		(property "Val" "R_4x100R_0402"
			(at 0 0 0)
			(layer "B.Fab")
			(hide yes)
			(effects
				(font
					(size 1 1)
					(thickness 0.15)
				)
				(justify mirror)
			)
		)
		(sheetname "Translators")
		(sheetfile "translators.kicad_sch")
		(attr smd)
		(fp_line
			(start -1.25 0.5)
			(end -1.25 -0.498)
			(stroke
				(width 0.15)
				(type solid)
			)
			(layer "B.SilkS")
		)
		(fp_line
			(start 1.25 -0.499)
			(end 1.25 0.499)
			(stroke
				(width 0.15)
				(type solid)
			)
			(layer "B.SilkS")
		)
		(fp_rect
			(start -1.25 0.8)
			(end 1.25 -0.8)
			(stroke
				(width 0.05)
				(type solid)
			)
			(fill no)
			(layer "B.CrtYd")
		)
		(fp_line
			(start -1 -0.498)
			(end -1 0.5)
			(stroke
				(width 0.15)
				(type solid)
			)
			(layer "B.Fab")
		)
		(fp_line
			(start -1 0.5)
			(end 0.998 0.5)
			(stroke
				(width 0.15)
				(type solid)
			)
			(layer "B.Fab")
		)
		(fp_line
			(start 0.998 -0.498)
			(end -1 -0.498)
			(stroke
				(width 0.15)
				(type solid)
			)
			(layer "B.Fab")
		)
		(fp_line
			(start 0.998 0.5)
			(end 0.998 -0.498)
			(stroke
				(width 0.15)
				(type solid)
			)
			(layer "B.Fab")
		)
		(pad "1" smd roundrect
			(at -0.8875 -0.45)
			(size 0.525 0.5)
			(layers "B.Cu" "B.Mask" "B.Paste")
			(roundrect_rratio 0.25)
			(net 43 "/LPDDR5/LPDDR5_A.CS0")
			(pinfunction "R1.1")
			(pintype "passive")
		)
		(pad "2" smd roundrect
			(at -0.25 -0.45)
			(size 0.25 0.5)
			(layers "B.Cu" "B.Mask" "B.Paste")
			(roundrect_rratio 0.25)
			(net 44 "/LPDDR5/LPDDR5_A.CS1")
			(pinfunction "R2.1")
			(pintype "passive")
		)
		(pad "3" smd roundrect
			(at 0.25 -0.45)
			(size 0.25 0.5)
			(layers "B.Cu" "B.Mask" "B.Paste")
			(roundrect_rratio 0.25)
			(net 57 "/LPDDR5/LPDDR5_A.CA0")
			(pinfunction "R3.1")
			(pintype "passive")
		)
		(pad "4" smd roundrect
			(at 0.8875 -0.45)
			(size 0.525 0.5)
			(layers "B.Cu" "B.Mask" "B.Paste")
			(roundrect_rratio 0.25)
			(net 58 "/LPDDR5/LPDDR5_A.CA1")
			(pinfunction "R4.1")
			(pintype "passive")
		)
		(pad "5" smd roundrect
			(at 0.8875 0.45)
			(size 0.525 0.5)
			(layers "B.Cu" "B.Mask" "B.Paste")
			(roundrect_rratio 0.25)
			(net 14 "GND")
			(pinfunction "R4.2")
			(pintype "passive")
		)
		(pad "6" smd roundrect
			(at 0.25 0.45)
			(size 0.25 0.5)
			(layers "B.Cu" "B.Mask" "B.Paste")
			(roundrect_rratio 0.25)
			(net 14 "GND")
			(pinfunction "R3.2")
			(pintype "passive")
		)
		(pad "7" smd roundrect
			(at -0.25 0.45)
			(size 0.25 0.5)
			(layers "B.Cu" "B.Mask" "B.Paste")
			(roundrect_rratio 0.25)
			(net 14 "GND")
			(pinfunction "R2.2")
			(pintype "passive")
		)
		(pad "8" smd roundrect
			(at -0.8875 0.45)
			(size 0.525 0.5)
			(layers "B.Cu" "B.Mask" "B.Paste")
			(roundrect_rratio 0.25)
			(net 14 "GND")
			(pinfunction "R1.2")
			(pintype "passive")
		)
	)
	(footprint "antmicro-footprints:R_0402_1005Metric"
		(layer "B.Cu")
		(at 105.17 91.95 180)
		(descr "Resistor SMD 0402")
		(tags "resistor SMD 0402")
		(property "Reference" "R85"
			(at 1.07 -0.35 0)
			(unlocked yes)
			(layer "B.SilkS")
			(effects
				(font
					(size 0.7 0.7)
					(thickness 0.15)
				)
				(justify left bottom mirror)
			)
		)
		(property "Value" "R_100R_0402"
			(at -1.011843 -1.772047 0)
			(layer "B.Fab")
			(effects
				(font
					(size 0.7 0.7)
					(thickness 0.15)
				)
				(justify left bottom mirror)
			)
		)
		(property "Author" "Antmicro"
			(at 210.34 183.9 0)
			(layer "B.Fab")
			(hide yes)
			(effects
				(font
					(size 1 1)
					(thickness 0.15)
				)
				(justify mirror)
			)
		)
		(property "License" "Apache-2.0"
			(at 210.34 183.9 0)
			(layer "B.Fab")
			(hide yes)
			(effects
				(font
					(size 1 1)
					(thickness 0.15)
				)
				(justify mirror)
			)
		)
		(property "MPN" "CR0402-FX-1000GLF"
			(at 210.34 183.9 0)
			(layer "B.Fab")
			(hide yes)
			(effects
				(font
					(size 1 1)
					(thickness 0.15)
				)
				(justify mirror)
			)
		)
		(property "Manufacturer" "Bourns"
			(at 210.34 183.9 0)
			(layer "B.Fab")
			(hide yes)
			(effects
				(font
					(size 1 1)
					(thickness 0.15)
				)
				(justify mirror)
			)
		)
		(property "Tolerance" "1%"
			(at 210.34 183.9 0)
			(layer "B.Fab")
			(hide yes)
			(effects
				(font
					(size 1 1)
					(thickness 0.15)
				)
				(justify mirror)
			)
		)
		(property "Val" "100R"
			(at 210.34 183.9 0)
			(layer "B.Fab")
			(hide yes)
			(effects
				(font
					(size 1 1)
					(thickness 0.15)
				)
				(justify mirror)
			)
		)
		(sheetname "Translators")
		(sheetfile "translators.kicad_sch")
		(attr smd)
		(fp_rect
			(start -0.93 0.47)
			(end 0.93 -0.47)
			(stroke
				(width 0.05)
				(type solid)
			)
			(fill no)
			(layer "B.CrtYd")
		)
		(fp_rect
			(start -0.5 0.25)
			(end 0.5 -0.25)
			(stroke
				(width 0.15)
				(type solid)
			)
			(fill no)
			(layer "B.Fab")
		)
		(pad "1" smd roundrect
			(at -0.485 0 180)
			(size 0.59 0.64)
			(layers "B.Cu" "B.Mask" "B.Paste")
			(roundrect_rratio 0.25)
			(net 190 "/LPDDR5/LPDDR5_A.DMI1")
			(pintype "passive")
		)
		(pad "2" smd roundrect
			(at 0.485 0 180)
			(size 0.59 0.64)
			(layers "B.Cu" "B.Mask" "B.Paste")
			(roundrect_rratio 0.25)
			(net 14 "GND")
			(pintype "passive")
		)
	)
	(footprint "antmicro-footprints:C_0402_1005Metric"
		(layer "B.Cu")
		(at 129.175 86.15 180)
		(descr "Capacitor SMD 0402")
		(tags "capacitor SMD 0402")
		(property "Reference" "C35"
			(at 0.875 -0.35 0)
			(unlocked yes)
			(layer "B.SilkS")
			(effects
				(font
					(size 0.7 0.7)
					(thickness 0.15)
				)
				(justify left bottom mirror)
			)
		)
		(property "Value" "C_4u7_0402"
			(at -1.022927 -2.155213 0)
			(layer "B.Fab")
			(effects
				(font
					(size 0.7 0.7)
					(thickness 0.15)
				)
				(justify left bottom mirror)
			)
		)
		(property "Author" "Antmicro"
			(at 258.35 172.3 0)
			(layer "B.Fab")
			(hide yes)
			(effects
				(font
					(size 1 1)
					(thickness 0.15)
				)
				(justify mirror)
			)
		)
		(property "Dielectric" ""
			(at 258.35 172.3 0)
			(layer "B.Fab")
			(hide yes)
			(effects
				(font
					(size 1 1)
					(thickness 0.15)
				)
				(justify mirror)
			)
		)
		(property "License" "Apache-2.0"
			(at 258.35 172.3 0)
			(layer "B.Fab")
			(hide yes)
			(effects
				(font
					(size 1 1)
					(thickness 0.15)
				)
				(justify mirror)
			)
		)
		(property "MPN" "GRM155R61A475MEAAD"
			(at 258.35 172.3 0)
			(layer "B.Fab")
			(hide yes)
			(effects
				(font
					(size 1 1)
					(thickness 0.15)
				)
				(justify mirror)
			)
		)
		(property "Manufacturer" "Murata"
			(at 258.35 172.3 0)
			(layer "B.Fab")
			(hide yes)
			(effects
				(font
					(size 1 1)
					(thickness 0.15)
				)
				(justify mirror)
			)
		)
		(property "Val" "4u7"
			(at 258.35 172.3 0)
			(layer "B.Fab")
			(hide yes)
			(effects
				(font
					(size 1 1)
					(thickness 0.15)
				)
				(justify mirror)
			)
		)
		(property "Voltage" ""
			(at 258.35 172.3 0)
			(layer "B.Fab")
			(hide yes)
			(effects
				(font
					(size 1 1)
					(thickness 0.15)
				)
				(justify mirror)
			)
		)
		(sheetname "LPDDR5")
		(sheetfile "lpddr5.kicad_sch")
		(attr smd)
		(fp_rect
			(start -0.9659 0.481258)
			(end 0.9649 -0.458742)
			(stroke
				(width 0.05)
				(type solid)
			)
			(fill no)
			(layer "B.CrtYd")
		)
		(fp_line
			(start 0.499 0.25)
			(end 0.499 -0.248)
			(stroke
				(width 0.15)
				(type solid)
			)
			(layer "B.Fab")
		)
		(fp_line
			(start 0.499 -0.248)
			(end -0.499 -0.248)
			(stroke
				(width 0.15)
				(type solid)
			)
			(layer "B.Fab")
		)
		(fp_line
			(start -0.499 0.25)
			(end 0.499 0.25)
			(stroke
				(width 0.15)
				(type solid)
			)
			(layer "B.Fab")
		)
		(fp_line
			(start -0.499 -0.248)
			(end -0.499 0.25)
			(stroke
				(width 0.15)
				(type solid)
			)
			(layer "B.Fab")
		)
		(pad "1" smd roundrect
			(at -0.484 0 180)
			(size 0.59 0.64)
			(layers "B.Cu" "B.Mask" "B.Paste")
			(roundrect_rratio 0.25)
			(net 14 "GND")
			(pintype "passive")
		)
		(pad "2" smd roundrect
			(at 0.484 0 180)
			(size 0.59 0.64)
			(layers "B.Cu" "B.Mask" "B.Paste")
			(roundrect_rratio 0.25)
			(net 35 "+1V8")
			(pintype "passive")
		)
	)
	(footprint "antmicro-footprints:C_0402_1005Metric"
		(layer "B.Cu")
		(at 129.175 74.95 180)
		(descr "Capacitor SMD 0402")
		(tags "capacitor SMD 0402")
		(property "Reference" "C40"
			(at 1.075 -0.35 0)
			(unlocked yes)
			(layer "B.SilkS")
			(effects
				(font
					(size 0.7 0.7)
					(thickness 0.15)
				)
				(justify left bottom mirror)
			)
		)
		(property "Value" "C_4u7_0402"
			(at -1.022927 -2.155213 0)
			(layer "B.Fab")
			(effects
				(font
					(size 0.7 0.7)
					(thickness 0.15)
				)
				(justify left bottom mirror)
			)
		)
		(property "Author" "Antmicro"
			(at 258.35 149.9 0)
			(layer "B.Fab")
			(hide yes)
			(effects
				(font
					(size 1 1)
					(thickness 0.15)
				)
				(justify mirror)
			)
		)
		(property "Dielectric" ""
			(at 258.35 149.9 0)
			(layer "B.Fab")
			(hide yes)
			(effects
				(font
					(size 1 1)
					(thickness 0.15)
				)
				(justify mirror)
			)
		)
		(property "License" "Apache-2.0"
			(at 258.35 149.9 0)
			(layer "B.Fab")
			(hide yes)
			(effects
				(font
					(size 1 1)
					(thickness 0.15)
				)
				(justify mirror)
			)
		)
		(property "MPN" "GRM155R61A475MEAAD"
			(at 258.35 149.9 0)
			(layer "B.Fab")
			(hide yes)
			(effects
				(font
					(size 1 1)
					(thickness 0.15)
				)
				(justify mirror)
			)
		)
		(property "Manufacturer" "Murata"
			(at 258.35 149.9 0)
			(layer "B.Fab")
			(hide yes)
			(effects
				(font
					(size 1 1)
					(thickness 0.15)
				)
				(justify mirror)
			)
		)
		(property "Val" "4u7"
			(at 258.35 149.9 0)
			(layer "B.Fab")
			(hide yes)
			(effects
				(font
					(size 1 1)
					(thickness 0.15)
				)
				(justify mirror)
			)
		)
		(property "Voltage" ""
			(at 258.35 149.9 0)
			(layer "B.Fab")
			(hide yes)
			(effects
				(font
					(size 1 1)
					(thickness 0.15)
				)
				(justify mirror)
			)
		)
		(sheetname "LPDDR5")
		(sheetfile "lpddr5.kicad_sch")
		(attr smd)
		(fp_rect
			(start -0.9659 0.481258)
			(end 0.9649 -0.458742)
			(stroke
				(width 0.05)
				(type solid)
			)
			(fill no)
			(layer "B.CrtYd")
		)
		(fp_line
			(start 0.499 0.25)
			(end 0.499 -0.248)
			(stroke
				(width 0.15)
				(type solid)
			)
			(layer "B.Fab")
		)
		(fp_line
			(start 0.499 -0.248)
			(end -0.499 -0.248)
			(stroke
				(width 0.15)
				(type solid)
			)
			(layer "B.Fab")
		)
		(fp_line
			(start -0.499 0.25)
			(end 0.499 0.25)
			(stroke
				(width 0.15)
				(type solid)
			)
			(layer "B.Fab")
		)
		(fp_line
			(start -0.499 -0.248)
			(end -0.499 0.25)
			(stroke
				(width 0.15)
				(type solid)
			)
			(layer "B.Fab")
		)
		(pad "1" smd roundrect
			(at -0.484 0 180)
			(size 0.59 0.64)
			(layers "B.Cu" "B.Mask" "B.Paste")
			(roundrect_rratio 0.25)
			(net 14 "GND")
			(pintype "passive")
		)
		(pad "2" smd roundrect
			(at 0.484 0 180)
			(size 0.59 0.64)
			(layers "B.Cu" "B.Mask" "B.Paste")
			(roundrect_rratio 0.25)
			(net 4 "+0V5")
			(pintype "passive")
		)
	)
	(footprint "antmicro-footprints:C_0402_1005Metric"
		(layer "B.Cu")
		(at 131.975 75.55 90)
		(descr "Capacitor SMD 0402")
		(tags "capacitor SMD 0402")
		(property "Reference" "C47"
			(at 1.25 0.699 90)
			(unlocked yes)
			(layer "B.SilkS")
			(effects
				(font
					(size 0.7 0.7)
					(thickness 0.15)
				)
				(justify right bottom mirror)
			)
		)
		(property "Value" "C_4u7_0402"
			(at -1.022927 -2.155213 90)
			(layer "B.Fab")
			(effects
				(font
					(size 0.7 0.7)
					(thickness 0.15)
				)
				(justify right bottom mirror)
			)
		)
		(property "Author" "Antmicro"
			(at 207.525 -56.425 0)
			(layer "B.Fab")
			(hide yes)
			(effects
				(font
					(size 1 1)
					(thickness 0.15)
				)
				(justify mirror)
			)
		)
		(property "Dielectric" ""
			(at 207.525 -56.425 0)
			(layer "B.Fab")
			(hide yes)
			(effects
				(font
					(size 1 1)
					(thickness 0.15)
				)
				(justify mirror)
			)
		)
		(property "License" "Apache-2.0"
			(at 207.525 -56.425 0)
			(layer "B.Fab")
			(hide yes)
			(effects
				(font
					(size 1 1)
					(thickness 0.15)
				)
				(justify mirror)
			)
		)
		(property "MPN" "GRM155R61A475MEAAD"
			(at 207.525 -56.425 0)
			(layer "B.Fab")
			(hide yes)
			(effects
				(font
					(size 1 1)
					(thickness 0.15)
				)
				(justify mirror)
			)
		)
		(property "Manufacturer" "Murata"
			(at 207.525 -56.425 0)
			(layer "B.Fab")
			(hide yes)
			(effects
				(font
					(size 1 1)
					(thickness 0.15)
				)
				(justify mirror)
			)
		)
		(property "Val" "4u7"
			(at 207.525 -56.425 0)
			(layer "B.Fab")
			(hide yes)
			(effects
				(font
					(size 1 1)
					(thickness 0.15)
				)
				(justify mirror)
			)
		)
		(property "Voltage" ""
			(at 207.525 -56.425 0)
			(layer "B.Fab")
			(hide yes)
			(effects
				(font
					(size 1 1)
					(thickness 0.15)
				)
				(justify mirror)
			)
		)
		(sheetname "LPDDR5")
		(sheetfile "lpddr5.kicad_sch")
		(attr smd)
		(fp_rect
			(start -0.9659 0.481258)
			(end 0.9649 -0.458742)
			(stroke
				(width 0.05)
				(type solid)
			)
			(fill no)
			(layer "B.CrtYd")
		)
		(fp_line
			(start 0.499 -0.248)
			(end -0.499 -0.248)
			(stroke
				(width 0.15)
				(type solid)
			)
			(layer "B.Fab")
		)
		(fp_line
			(start -0.499 -0.248)
			(end -0.499 0.25)
			(stroke
				(width 0.15)
				(type solid)
			)
			(layer "B.Fab")
		)
		(fp_line
			(start 0.499 0.25)
			(end 0.499 -0.248)
			(stroke
				(width 0.15)
				(type solid)
			)
			(layer "B.Fab")
		)
		(fp_line
			(start -0.499 0.25)
			(end 0.499 0.25)
			(stroke
				(width 0.15)
				(type solid)
			)
			(layer "B.Fab")
		)
		(pad "1" smd roundrect
			(at -0.484 0 90)
			(size 0.59 0.64)
			(layers "B.Cu" "B.Mask" "B.Paste")
			(roundrect_rratio 0.25)
			(net 14 "GND")
			(pintype "passive")
		)
		(pad "2" smd roundrect
			(at 0.484 0 90)
			(size 0.59 0.64)
			(layers "B.Cu" "B.Mask" "B.Paste")
			(roundrect_rratio 0.25)
			(net 4 "+0V5")
			(pintype "passive")
		)
	)
	(footprint "antmicro-footprints:R_0402_1005Metric"
		(layer "B.Cu")
		(at 134.9 93.8425 -90)
		(descr "Resistor SMD 0402")
		(tags "resistor SMD 0402")
		(property "Reference" "R28"
			(at 0.8575 -0.3 90)
			(unlocked yes)
			(layer "B.SilkS")
			(effects
				(font
					(size 0.7 0.7)
					(thickness 0.15)
				)
				(justify left bottom mirror)
			)
		)
		(property "Value" "R_200k_0402"
			(at -1.011843 -1.772047 90)
			(layer "B.Fab")
			(effects
				(font
					(size 0.7 0.7)
					(thickness 0.15)
				)
				(justify left bottom mirror)
			)
		)
		(property "Author" "Antmicro"
			(at 41.0575 228.7425 0)
			(layer "B.Fab")
			(hide yes)
			(effects
				(font
					(size 1 1)
					(thickness 0.15)
				)
				(justify mirror)
			)
		)
		(property "License" "Apache-2.0"
			(at 41.0575 228.7425 0)
			(layer "B.Fab")
			(hide yes)
			(effects
				(font
					(size 1 1)
					(thickness 0.15)
				)
				(justify mirror)
			)
		)
		(property "MPN" "CR0402-FX-2003GLF"
			(at 41.0575 228.7425 0)
			(layer "B.Fab")
			(hide yes)
			(effects
				(font
					(size 1 1)
					(thickness 0.15)
				)
				(justify mirror)
			)
		)
		(property "Manufacturer" "Bourns"
			(at 41.0575 228.7425 0)
			(layer "B.Fab")
			(hide yes)
			(effects
				(font
					(size 1 1)
					(thickness 0.15)
				)
				(justify mirror)
			)
		)
		(property "Tolerance" "1%"
			(at 41.0575 228.7425 0)
			(layer "B.Fab")
			(hide yes)
			(effects
				(font
					(size 1 1)
					(thickness 0.15)
				)
				(justify mirror)
			)
		)
		(property "Val" "200k"
			(at 41.0575 228.7425 0)
			(layer "B.Fab")
			(hide yes)
			(effects
				(font
					(size 1 1)
					(thickness 0.15)
				)
				(justify mirror)
			)
		)
		(sheetname "SODIMM")
		(sheetfile "sodim.kicad_sch")
		(attr smd exclude_from_pos_files exclude_from_bom dnp)
		(fp_rect
			(start -0.93 0.47)
			(end 0.93 -0.47)
			(stroke
				(width 0.05)
				(type solid)
			)
			(fill no)
			(layer "B.CrtYd")
		)
		(fp_rect
			(start -0.5 0.25)
			(end 0.5 -0.25)
			(stroke
				(width 0.15)
				(type solid)
			)
			(fill no)
			(layer "B.Fab")
		)
		(pad "1" smd roundrect
			(at -0.485 0 270)
			(size 0.59 0.64)
			(layers "B.Cu" "B.Mask" "B.Paste")
			(roundrect_rratio 0.25)
			(net 5 "+5V")
			(pintype "passive")
		)
		(pad "2" smd roundrect
			(at 0.485 0 270)
			(size 0.59 0.64)
			(layers "B.Cu" "B.Mask" "B.Paste")
			(roundrect_rratio 0.25)
			(net 33 "Net-(J1-Pad130)")
			(pintype "passive")
		)
	)
	(footprint "antmicro-footprints:R_0402_1005Metric"
		(layer "B.Cu")
		(at 107.63 90.97 90)
		(descr "Resistor SMD 0402")
		(tags "resistor SMD 0402")
		(property "Reference" "R14"
			(at -1.23 1.37 90)
			(unlocked yes)
			(layer "B.SilkS")
			(effects
				(font
					(size 0.7 0.7)
					(thickness 0.15)
				)
				(justify right bottom mirror)
			)
		)
		(property "Value" "R_100R_0402"
			(at -1.011843 -1.772047 90)
			(layer "B.Fab")
			(effects
				(font
					(size 0.7 0.7)
					(thickness 0.15)
				)
				(justify right bottom mirror)
			)
		)
		(property "Author" "Antmicro"
			(at 198.6 -16.66 0)
			(layer "B.Fab")
			(hide yes)
			(effects
				(font
					(size 1 1)
					(thickness 0.15)
				)
				(justify mirror)
			)
		)
		(property "License" "Apache-2.0"
			(at 198.6 -16.66 0)
			(layer "B.Fab")
			(hide yes)
			(effects
				(font
					(size 1 1)
					(thickness 0.15)
				)
				(justify mirror)
			)
		)
		(property "MPN" "CR0402-FX-1000GLF"
			(at 198.6 -16.66 0)
			(layer "B.Fab")
			(hide yes)
			(effects
				(font
					(size 1 1)
					(thickness 0.15)
				)
				(justify mirror)
			)
		)
		(property "Manufacturer" "Bourns"
			(at 198.6 -16.66 0)
			(layer "B.Fab")
			(hide yes)
			(effects
				(font
					(size 1 1)
					(thickness 0.15)
				)
				(justify mirror)
			)
		)
		(property "Tolerance" "1%"
			(at 198.6 -16.66 0)
			(layer "B.Fab")
			(hide yes)
			(effects
				(font
					(size 1 1)
					(thickness 0.15)
				)
				(justify mirror)
			)
		)
		(property "Val" "100R"
			(at 198.6 -16.66 0)
			(layer "B.Fab")
			(hide yes)
			(effects
				(font
					(size 1 1)
					(thickness 0.15)
				)
				(justify mirror)
			)
		)
		(sheetname "Translators")
		(sheetfile "translators.kicad_sch")
		(attr smd)
		(fp_rect
			(start -0.93 0.47)
			(end 0.93 -0.47)
			(stroke
				(width 0.05)
				(type solid)
			)
			(fill no)
			(layer "B.CrtYd")
		)
		(fp_rect
			(start -0.5 0.25)
			(end 0.5 -0.25)
			(stroke
				(width 0.15)
				(type solid)
			)
			(fill no)
			(layer "B.Fab")
		)
		(pad "1" smd roundrect
			(at -0.485 0 90)
			(size 0.59 0.64)
			(layers "B.Cu" "B.Mask" "B.Paste")
			(roundrect_rratio 0.25)
			(net 181 "/SODIMM/LPDDR5_IN_A.WCK1_P")
			(pintype "passive")
		)
		(pad "2" smd roundrect
			(at 0.485 0 90)
			(size 0.59 0.64)
			(layers "B.Cu" "B.Mask" "B.Paste")
			(roundrect_rratio 0.25)
			(net 48 "/LPDDR5/LPDDR5_A.WCK1_P")
			(pintype "passive")
		)
	)
	(footprint "antmicro-footprints:C_0402_1005Metric"
		(layer "B.Cu")
		(at 142.575 80.75 180)
		(descr "Capacitor SMD 0402")
		(tags "capacitor SMD 0402")
		(property "Reference" "C61"
			(at -3.225 -0.25 0)
			(unlocked yes)
			(layer "B.SilkS")
			(effects
				(font
					(size 0.7 0.7)
					(thickness 0.15)
				)
				(justify left bottom mirror)
			)
		)
		(property "Value" "C_4u7_0402"
			(at -1.022927 -2.155213 0)
			(layer "B.Fab")
			(effects
				(font
					(size 0.7 0.7)
					(thickness 0.15)
				)
				(justify left bottom mirror)
			)
		)
		(property "Author" "Antmicro"
			(at 285.15 161.5 0)
			(layer "B.Fab")
			(hide yes)
			(effects
				(font
					(size 1 1)
					(thickness 0.15)
				)
				(justify mirror)
			)
		)
		(property "Dielectric" ""
			(at 285.15 161.5 0)
			(layer "B.Fab")
			(hide yes)
			(effects
				(font
					(size 1 1)
					(thickness 0.15)
				)
				(justify mirror)
			)
		)
		(property "License" "Apache-2.0"
			(at 285.15 161.5 0)
			(layer "B.Fab")
			(hide yes)
			(effects
				(font
					(size 1 1)
					(thickness 0.15)
				)
				(justify mirror)
			)
		)
		(property "MPN" "GRM155R61A475MEAAD"
			(at 285.15 161.5 0)
			(layer "B.Fab")
			(hide yes)
			(effects
				(font
					(size 1 1)
					(thickness 0.15)
				)
				(justify mirror)
			)
		)
		(property "Manufacturer" "Murata"
			(at 285.15 161.5 0)
			(layer "B.Fab")
			(hide yes)
			(effects
				(font
					(size 1 1)
					(thickness 0.15)
				)
				(justify mirror)
			)
		)
		(property "Val" "4u7"
			(at 285.15 161.5 0)
			(layer "B.Fab")
			(hide yes)
			(effects
				(font
					(size 1 1)
					(thickness 0.15)
				)
				(justify mirror)
			)
		)
		(property "Voltage" ""
			(at 285.15 161.5 0)
			(layer "B.Fab")
			(hide yes)
			(effects
				(font
					(size 1 1)
					(thickness 0.15)
				)
				(justify mirror)
			)
		)
		(sheetname "LPDDR5")
		(sheetfile "lpddr5.kicad_sch")
		(attr smd)
		(fp_rect
			(start -0.9659 0.481258)
			(end 0.9649 -0.458742)
			(stroke
				(width 0.05)
				(type solid)
			)
			(fill no)
			(layer "B.CrtYd")
		)
		(fp_line
			(start 0.499 0.25)
			(end 0.499 -0.248)
			(stroke
				(width 0.15)
				(type solid)
			)
			(layer "B.Fab")
		)
		(fp_line
			(start 0.499 -0.248)
			(end -0.499 -0.248)
			(stroke
				(width 0.15)
				(type solid)
			)
			(layer "B.Fab")
		)
		(fp_line
			(start -0.499 0.25)
			(end 0.499 0.25)
			(stroke
				(width 0.15)
				(type solid)
			)
			(layer "B.Fab")
		)
		(fp_line
			(start -0.499 -0.248)
			(end -0.499 0.25)
			(stroke
				(width 0.15)
				(type solid)
			)
			(layer "B.Fab")
		)
		(pad "1" smd roundrect
			(at -0.484 0 180)
			(size 0.59 0.64)
			(layers "B.Cu" "B.Mask" "B.Paste")
			(roundrect_rratio 0.25)
			(net 14 "GND")
			(pintype "passive")
		)
		(pad "2" smd roundrect
			(at 0.484 0 180)
			(size 0.59 0.64)
			(layers "B.Cu" "B.Mask" "B.Paste")
			(roundrect_rratio 0.25)
			(net 13 "+1V05")
			(pintype "passive")
		)
	)
	(footprint "antmicro-footprints:C_0402_1005Metric"
		(layer "B.Cu")
		(at 131.275 77.5 180)
		(descr "Capacitor SMD 0402")
		(tags "capacitor SMD 0402")
		(property "Reference" "C42"
			(at 0 0.699 0)
			(unlocked yes)
			(layer "B.SilkS")
			(effects
				(font
					(size 0.7 0.7)
					(thickness 0.15)
				)
				(justify left bottom mirror)
			)
		)
		(property "Value" "C_4u7_0402"
			(at -1.022927 -2.155213 0)
			(layer "B.Fab")
			(effects
				(font
					(size 0.7 0.7)
					(thickness 0.15)
				)
				(justify left bottom mirror)
			)
		)
		(property "Author" "Antmicro"
			(at 262.55 155 0)
			(layer "B.Fab")
			(hide yes)
			(effects
				(font
					(size 1 1)
					(thickness 0.15)
				)
				(justify mirror)
			)
		)
		(property "Dielectric" ""
			(at 262.55 155 0)
			(layer "B.Fab")
			(hide yes)
			(effects
				(font
					(size 1 1)
					(thickness 0.15)
				)
				(justify mirror)
			)
		)
		(property "License" "Apache-2.0"
			(at 262.55 155 0)
			(layer "B.Fab")
			(hide yes)
			(effects
				(font
					(size 1 1)
					(thickness 0.15)
				)
				(justify mirror)
			)
		)
		(property "MPN" "GRM155R61A475MEAAD"
			(at 262.55 155 0)
			(layer "B.Fab")
			(hide yes)
			(effects
				(font
					(size 1 1)
					(thickness 0.15)
				)
				(justify mirror)
			)
		)
		(property "Manufacturer" "Murata"
			(at 262.55 155 0)
			(layer "B.Fab")
			(hide yes)
			(effects
				(font
					(size 1 1)
					(thickness 0.15)
				)
				(justify mirror)
			)
		)
		(property "Val" "4u7"
			(at 262.55 155 0)
			(layer "B.Fab")
			(hide yes)
			(effects
				(font
					(size 1 1)
					(thickness 0.15)
				)
				(justify mirror)
			)
		)
		(property "Voltage" ""
			(at 262.55 155 0)
			(layer "B.Fab")
			(hide yes)
			(effects
				(font
					(size 1 1)
					(thickness 0.15)
				)
				(justify mirror)
			)
		)
		(sheetname "LPDDR5")
		(sheetfile "lpddr5.kicad_sch")
		(attr smd)
		(fp_rect
			(start -0.9659 0.481258)
			(end 0.9649 -0.458742)
			(stroke
				(width 0.05)
				(type solid)
			)
			(fill no)
			(layer "B.CrtYd")
		)
		(fp_line
			(start 0.499 0.25)
			(end 0.499 -0.248)
			(stroke
				(width 0.15)
				(type solid)
			)
			(layer "B.Fab")
		)
		(fp_line
			(start 0.499 -0.248)
			(end -0.499 -0.248)
			(stroke
				(width 0.15)
				(type solid)
			)
			(layer "B.Fab")
		)
		(fp_line
			(start -0.499 0.25)
			(end 0.499 0.25)
			(stroke
				(width 0.15)
				(type solid)
			)
			(layer "B.Fab")
		)
		(fp_line
			(start -0.499 -0.248)
			(end -0.499 0.25)
			(stroke
				(width 0.15)
				(type solid)
			)
			(layer "B.Fab")
		)
		(pad "1" smd roundrect
			(at -0.484 0 180)
			(size 0.59 0.64)
			(layers "B.Cu" "B.Mask" "B.Paste")
			(roundrect_rratio 0.25)
			(net 14 "GND")
			(pintype "passive")
		)
		(pad "2" smd roundrect
			(at 0.484 0 180)
			(size 0.59 0.64)
			(layers "B.Cu" "B.Mask" "B.Paste")
			(roundrect_rratio 0.25)
			(net 4 "+0V5")
			(pintype "passive")
		)
	)
	(footprint "antmicro-footprints:C_0402_1005Metric"
		(layer "B.Cu")
		(at 131.975 84.35 -90)
		(descr "Capacitor SMD 0402")
		(tags "capacitor SMD 0402")
		(property "Reference" "C50"
			(at 0.85 -0.425 90)
			(unlocked yes)
			(layer "B.SilkS")
			(effects
				(font
					(size 0.7 0.7)
					(thickness 0.15)
				)
				(justify left bottom mirror)
			)
		)
		(property "Value" "C_4u7_0402"
			(at -1.022927 -2.155213 90)
			(layer "B.Fab")
			(effects
				(font
					(size 0.7 0.7)
					(thickness 0.15)
				)
				(justify left bottom mirror)
			)
		)
		(property "Author" "Antmicro"
			(at 47.625 216.325 0)
			(layer "B.Fab")
			(hide yes)
			(effects
				(font
					(size 1 1)
					(thickness 0.15)
				)
				(justify mirror)
			)
		)
		(property "Dielectric" ""
			(at 47.625 216.325 0)
			(layer "B.Fab")
			(hide yes)
			(effects
				(font
					(size 1 1)
					(thickness 0.15)
				)
				(justify mirror)
			)
		)
		(property "License" "Apache-2.0"
			(at 47.625 216.325 0)
			(layer "B.Fab")
			(hide yes)
			(effects
				(font
					(size 1 1)
					(thickness 0.15)
				)
				(justify mirror)
			)
		)
		(property "MPN" "GRM155R61A475MEAAD"
			(at 47.625 216.325 0)
			(layer "B.Fab")
			(hide yes)
			(effects
				(font
					(size 1 1)
					(thickness 0.15)
				)
				(justify mirror)
			)
		)
		(property "Manufacturer" "Murata"
			(at 47.625 216.325 0)
			(layer "B.Fab")
			(hide yes)
			(effects
				(font
					(size 1 1)
					(thickness 0.15)
				)
				(justify mirror)
			)
		)
		(property "Val" "4u7"
			(at 47.625 216.325 0)
			(layer "B.Fab")
			(hide yes)
			(effects
				(font
					(size 1 1)
					(thickness 0.15)
				)
				(justify mirror)
			)
		)
		(property "Voltage" ""
			(at 47.625 216.325 0)
			(layer "B.Fab")
			(hide yes)
			(effects
				(font
					(size 1 1)
					(thickness 0.15)
				)
				(justify mirror)
			)
		)
		(sheetname "LPDDR5")
		(sheetfile "lpddr5.kicad_sch")
		(attr smd)
		(fp_rect
			(start -0.9659 0.481258)
			(end 0.9649 -0.458742)
			(stroke
				(width 0.05)
				(type solid)
			)
			(fill no)
			(layer "B.CrtYd")
		)
		(fp_line
			(start -0.499 0.25)
			(end 0.499 0.25)
			(stroke
				(width 0.15)
				(type solid)
			)
			(layer "B.Fab")
		)
		(fp_line
			(start 0.499 0.25)
			(end 0.499 -0.248)
			(stroke
				(width 0.15)
				(type solid)
			)
			(layer "B.Fab")
		)
		(fp_line
			(start -0.499 -0.248)
			(end -0.499 0.25)
			(stroke
				(width 0.15)
				(type solid)
			)
			(layer "B.Fab")
		)
		(fp_line
			(start 0.499 -0.248)
			(end -0.499 -0.248)
			(stroke
				(width 0.15)
				(type solid)
			)
			(layer "B.Fab")
		)
		(pad "1" smd roundrect
			(at -0.484 0 270)
			(size 0.59 0.64)
			(layers "B.Cu" "B.Mask" "B.Paste")
			(roundrect_rratio 0.25)
			(net 14 "GND")
			(pintype "passive")
		)
		(pad "2" smd roundrect
			(at 0.484 0 270)
			(size 0.59 0.64)
			(layers "B.Cu" "B.Mask" "B.Paste")
			(roundrect_rratio 0.25)
			(net 4 "+0V5")
			(pintype "passive")
		)
	)
	(footprint "antmicro-footprints:D_SOD-123F"
		(layer "B.Cu")
		(at 113.1 64)
		(property "Reference" "D1"
			(at -2 -1.3 0)
			(unlocked yes)
			(layer "B.SilkS")
			(effects
				(font
					(size 0.7 0.7)
					(thickness 0.15)
				)
				(justify right bottom mirror)
			)
		)
		(property "Value" "PTVS48VS1UR"
			(at 0 -2.1 0)
			(layer "B.Fab")
			(effects
				(font
					(size 0.7 0.7)
					(thickness 0.15)
				)
				(justify right bottom mirror)
			)
		)
		(property "Author" "Antmicro"
			(at 0 0 0)
			(layer "B.Fab")
			(hide yes)
			(effects
				(font
					(size 1 1)
					(thickness 0.15)
				)
				(justify mirror)
			)
		)
		(property "License" "Apache-2.0"
			(at 0 0 0)
			(layer "B.Fab")
			(hide yes)
			(effects
				(font
					(size 1 1)
					(thickness 0.15)
				)
				(justify mirror)
			)
		)
		(property "MPN" "PTVS48VS1UR,115"
			(at 0 0 0)
			(layer "B.Fab")
			(hide yes)
			(effects
				(font
					(size 1 1)
					(thickness 0.15)
				)
				(justify mirror)
			)
		)
		(property "Manufacturer" "Nexperia"
			(at 0 0 0)
			(layer "B.Fab")
			(hide yes)
			(effects
				(font
					(size 1 1)
					(thickness 0.15)
				)
				(justify mirror)
			)
		)
		(sheetname "Power supply")
		(sheetfile "power_supply.kicad_sch")
		(attr smd)
		(fp_line
			(start -0.7 0.8)
			(end -0.7 -0.8)
			(stroke
				(width 0.15)
				(type solid)
			)
			(layer "B.SilkS")
		)
		(fp_line
			(start -2.21 -1.1)
			(end -2.21 1.1)
			(stroke
				(width 0.05)
				(type solid)
			)
			(layer "B.CrtYd")
		)
		(fp_line
			(start 2.2 -1.1)
			(end -2.21 -1.1)
			(stroke
				(width 0.05)
				(type solid)
			)
			(layer "B.CrtYd")
		)
		(fp_line
			(start 2.2 1.1)
			(end -2.21 1.1)
			(stroke
				(width 0.05)
				(type solid)
			)
			(layer "B.CrtYd")
		)
		(fp_line
			(start 2.2 1.1)
			(end 2.2 -1.1)
			(stroke
				(width 0.05)
				(type solid)
			)
			(layer "B.CrtYd")
		)
		(fp_line
			(start -0.8 0.8)
			(end -0.8 -0.8)
			(stroke
				(width 0.1)
				(type solid)
			)
			(layer "B.Fab")
		)
		(fp_rect
			(start -1.75 0.802)
			(end 1.749 -0.8)
			(stroke
				(width 0.1)
				(type solid)
			)
			(fill no)
			(layer "B.Fab")
		)
		(pad "A" smd roundrect
			(at 1.398 0)
			(size 1.2 1.2)
			(layers "B.Cu" "B.Mask" "B.Paste")
			(roundrect_rratio 0.25)
			(net 15 "/Power supply/3.3V_QWIIC")
			(pinfunction "A")
			(pintype "passive")
		)
		(pad "K" smd roundrect
			(at -1.401 0)
			(size 1.2 1.2)
			(layers "B.Cu" "B.Mask" "B.Paste")
			(roundrect_rratio 0.25)
			(net 5 "+5V")
			(pinfunction "C")
			(pintype "passive")
		)
	)
	(footprint "antmicro-footprints:R_0402_1005Metric"
		(layer "B.Cu")
		(at 136.65 93.85 -90)
		(descr "Resistor SMD 0402")
		(tags "resistor SMD 0402")
		(property "Reference" "R84"
			(at 0.85 -0.35 90)
			(unlocked yes)
			(layer "B.SilkS")
			(effects
				(font
					(size 0.7 0.7)
					(thickness 0.15)
				)
				(justify left bottom mirror)
			)
		)
		(property "Value" "R_100R_0402"
			(at -1.011843 -1.772047 90)
			(layer "B.Fab")
			(effects
				(font
					(size 0.7 0.7)
					(thickness 0.15)
				)
				(justify left bottom mirror)
			)
		)
		(property "Author" "Antmicro"
			(at 42.8 230.5 0)
			(layer "B.Fab")
			(hide yes)
			(effects
				(font
					(size 1 1)
					(thickness 0.15)
				)
				(justify mirror)
			)
		)
		(property "License" "Apache-2.0"
			(at 42.8 230.5 0)
			(layer "B.Fab")
			(hide yes)
			(effects
				(font
					(size 1 1)
					(thickness 0.15)
				)
				(justify mirror)
			)
		)
		(property "MPN" "CR0402-FX-1000GLF"
			(at 42.8 230.5 0)
			(layer "B.Fab")
			(hide yes)
			(effects
				(font
					(size 1 1)
					(thickness 0.15)
				)
				(justify mirror)
			)
		)
		(property "Manufacturer" "Bourns"
			(at 42.8 230.5 0)
			(layer "B.Fab")
			(hide yes)
			(effects
				(font
					(size 1 1)
					(thickness 0.15)
				)
				(justify mirror)
			)
		)
		(property "Tolerance" "1%"
			(at 42.8 230.5 0)
			(layer "B.Fab")
			(hide yes)
			(effects
				(font
					(size 1 1)
					(thickness 0.15)
				)
				(justify mirror)
			)
		)
		(property "Val" "100R"
			(at 42.8 230.5 0)
			(layer "B.Fab")
			(hide yes)
			(effects
				(font
					(size 1 1)
					(thickness 0.15)
				)
				(justify mirror)
			)
		)
		(sheetname "Translators1")
		(sheetfile "translators.kicad_sch")
		(attr smd)
		(fp_rect
			(start -0.93 0.47)
			(end 0.93 -0.47)
			(stroke
				(width 0.05)
				(type solid)
			)
			(fill no)
			(layer "B.CrtYd")
		)
		(fp_rect
			(start -0.5 0.25)
			(end 0.5 -0.25)
			(stroke
				(width 0.15)
				(type solid)
			)
			(fill no)
			(layer "B.Fab")
		)
		(pad "1" smd roundrect
			(at -0.485 0 270)
			(size 0.59 0.64)
			(layers "B.Cu" "B.Mask" "B.Paste")
			(roundrect_rratio 0.25)
			(net 112 "/LPDDR5/LPDDR5_B.CK_P")
			(pintype "passive")
		)
		(pad "2" smd roundrect
			(at 0.485 0 270)
			(size 0.59 0.64)
			(layers "B.Cu" "B.Mask" "B.Paste")
			(roundrect_rratio 0.25)
			(net 14 "GND")
			(pintype "passive")
		)
	)
	(footprint "antmicro-footprints:R_0402_1005Metric"
		(layer "B.Cu")
		(at 163.5 89.465 180)
		(descr "Resistor SMD 0402")
		(tags "resistor SMD 0402")
		(property "Reference" "R79"
			(at -0.9 0.765 0)
			(unlocked yes)
			(layer "B.SilkS")
			(effects
				(font
					(size 0.7 0.7)
					(thickness 0.15)
				)
				(justify left bottom mirror)
			)
		)
		(property "Value" "R_100R_0402"
			(at -1.011843 -1.772047 0)
			(layer "B.Fab")
			(effects
				(font
					(size 0.7 0.7)
					(thickness 0.15)
				)
				(justify left bottom mirror)
			)
		)
		(property "Author" "Antmicro"
			(at 327 178.93 0)
			(layer "B.Fab")
			(hide yes)
			(effects
				(font
					(size 1 1)
					(thickness 0.15)
				)
				(justify mirror)
			)
		)
		(property "License" "Apache-2.0"
			(at 327 178.93 0)
			(layer "B.Fab")
			(hide yes)
			(effects
				(font
					(size 1 1)
					(thickness 0.15)
				)
				(justify mirror)
			)
		)
		(property "MPN" "CR0402-FX-1000GLF"
			(at 327 178.93 0)
			(layer "B.Fab")
			(hide yes)
			(effects
				(font
					(size 1 1)
					(thickness 0.15)
				)
				(justify mirror)
			)
		)
		(property "Manufacturer" "Bourns"
			(at 327 178.93 0)
			(layer "B.Fab")
			(hide yes)
			(effects
				(font
					(size 1 1)
					(thickness 0.15)
				)
				(justify mirror)
			)
		)
		(property "Tolerance" "1%"
			(at 327 178.93 0)
			(layer "B.Fab")
			(hide yes)
			(effects
				(font
					(size 1 1)
					(thickness 0.15)
				)
				(justify mirror)
			)
		)
		(property "Val" "100R"
			(at 327 178.93 0)
			(layer "B.Fab")
			(hide yes)
			(effects
				(font
					(size 1 1)
					(thickness 0.15)
				)
				(justify mirror)
			)
		)
		(sheetname "Translators1")
		(sheetfile "translators.kicad_sch")
		(attr smd)
		(fp_rect
			(start -0.93 0.47)
			(end 0.93 -0.47)
			(stroke
				(width 0.05)
				(type solid)
			)
			(fill no)
			(layer "B.CrtYd")
		)
		(fp_rect
			(start -0.5 0.25)
			(end 0.5 -0.25)
			(stroke
				(width 0.15)
				(type solid)
			)
			(fill no)
			(layer "B.Fab")
		)
		(pad "1" smd roundrect
			(at -0.485 0 180)
			(size 0.59 0.64)
			(layers "B.Cu" "B.Mask" "B.Paste")
			(roundrect_rratio 0.25)
			(net 109 "/LPDDR5/LPDDR5_B.WCK0_N")
			(pintype "passive")
		)
		(pad "2" smd roundrect
			(at 0.485 0 180)
			(size 0.59 0.64)
			(layers "B.Cu" "B.Mask" "B.Paste")
			(roundrect_rratio 0.25)
			(net 14 "GND")
			(pintype "passive")
		)
	)
	(footprint "antmicro-footprints:R_0402_1005Metric"
		(layer "B.Cu")
		(at 106.18 89.57 180)
		(descr "Resistor SMD 0402")
		(tags "resistor SMD 0402")
		(property "Reference" "R49"
			(at -1.02 0.67 0)
			(unlocked yes)
			(layer "B.SilkS")
			(effects
				(font
					(size 0.7 0.7)
					(thickness 0.15)
				)
				(justify left bottom mirror)
			)
		)
		(property "Value" "R_100R_0402"
			(at -1.011843 -1.772047 0)
			(layer "B.Fab")
			(effects
				(font
					(size 0.7 0.7)
					(thickness 0.15)
				)
				(justify left bottom mirror)
			)
		)
		(property "Author" "Antmicro"
			(at 212.36 179.14 0)
			(layer "B.Fab")
			(hide yes)
			(effects
				(font
					(size 1 1)
					(thickness 0.15)
				)
				(justify mirror)
			)
		)
		(property "License" "Apache-2.0"
			(at 212.36 179.14 0)
			(layer "B.Fab")
			(hide yes)
			(effects
				(font
					(size 1 1)
					(thickness 0.15)
				)
				(justify mirror)
			)
		)
		(property "MPN" "CR0402-FX-1000GLF"
			(at 212.36 179.14 0)
			(layer "B.Fab")
			(hide yes)
			(effects
				(font
					(size 1 1)
					(thickness 0.15)
				)
				(justify mirror)
			)
		)
		(property "Manufacturer" "Bourns"
			(at 212.36 179.14 0)
			(layer "B.Fab")
			(hide yes)
			(effects
				(font
					(size 1 1)
					(thickness 0.15)
				)
				(justify mirror)
			)
		)
		(property "Tolerance" "1%"
			(at 212.36 179.14 0)
			(layer "B.Fab")
			(hide yes)
			(effects
				(font
					(size 1 1)
					(thickness 0.15)
				)
				(justify mirror)
			)
		)
		(property "Val" "100R"
			(at 212.36 179.14 0)
			(layer "B.Fab")
			(hide yes)
			(effects
				(font
					(size 1 1)
					(thickness 0.15)
				)
				(justify mirror)
			)
		)
		(sheetname "Translators")
		(sheetfile "translators.kicad_sch")
		(attr smd)
		(fp_rect
			(start -0.93 0.47)
			(end 0.93 -0.47)
			(stroke
				(width 0.05)
				(type solid)
			)
			(fill no)
			(layer "B.CrtYd")
		)
		(fp_rect
			(start -0.5 0.25)
			(end 0.5 -0.25)
			(stroke
				(width 0.15)
				(type solid)
			)
			(fill no)
			(layer "B.Fab")
		)
		(pad "1" smd roundrect
			(at -0.485 0 180)
			(size 0.59 0.64)
			(layers "B.Cu" "B.Mask" "B.Paste")
			(roundrect_rratio 0.25)
			(net 47 "/LPDDR5/LPDDR5_A.WCK1_N")
			(pintype "passive")
		)
		(pad "2" smd roundrect
			(at 0.485 0 180)
			(size 0.59 0.64)
			(layers "B.Cu" "B.Mask" "B.Paste")
			(roundrect_rratio 0.25)
			(net 14 "GND")
			(pintype "passive")
		)
	)
	(footprint "antmicro-footprints:R_0402_1005Metric"
		(layer "B.Cu")
		(at 146.05 93.8 90)
		(descr "Resistor SMD 0402")
		(tags "resistor SMD 0402")
		(property "Reference" "R2"
			(at -0.7 1.55 90)
			(unlocked yes)
			(layer "B.SilkS")
			(effects
				(font
					(size 0.7 0.7)
					(thickness 0.15)
				)
				(justify right bottom mirror)
			)
		)
		(property "Value" "R_100R_0402"
			(at -1.011843 -1.772047 90)
			(layer "B.Fab")
			(effects
				(font
					(size 0.7 0.7)
					(thickness 0.15)
				)
				(justify right bottom mirror)
			)
		)
		(property "Author" "Antmicro"
			(at 239.85 -52.25 0)
			(layer "B.Fab")
			(hide yes)
			(effects
				(font
					(size 1 1)
					(thickness 0.15)
				)
				(justify mirror)
			)
		)
		(property "License" "Apache-2.0"
			(at 239.85 -52.25 0)
			(layer "B.Fab")
			(hide yes)
			(effects
				(font
					(size 1 1)
					(thickness 0.15)
				)
				(justify mirror)
			)
		)
		(property "MPN" "CR0402-FX-1000GLF"
			(at 239.85 -52.25 0)
			(layer "B.Fab")
			(hide yes)
			(effects
				(font
					(size 1 1)
					(thickness 0.15)
				)
				(justify mirror)
			)
		)
		(property "Manufacturer" "Bourns"
			(at 239.85 -52.25 0)
			(layer "B.Fab")
			(hide yes)
			(effects
				(font
					(size 1 1)
					(thickness 0.15)
				)
				(justify mirror)
			)
		)
		(property "Tolerance" "1%"
			(at 239.85 -52.25 0)
			(layer "B.Fab")
			(hide yes)
			(effects
				(font
					(size 1 1)
					(thickness 0.15)
				)
				(justify mirror)
			)
		)
		(property "Val" "100R"
			(at 239.85 -52.25 0)
			(layer "B.Fab")
			(hide yes)
			(effects
				(font
					(size 1 1)
					(thickness 0.15)
				)
				(justify mirror)
			)
		)
		(sheetfile "lpddr5-testbed.kicad_sch")
		(attr smd exclude_from_pos_files exclude_from_bom dnp)
		(fp_rect
			(start -0.93 0.47)
			(end 0.93 -0.47)
			(stroke
				(width 0.05)
				(type solid)
			)
			(fill no)
			(layer "B.CrtYd")
		)
		(fp_rect
			(start -0.5 0.25)
			(end 0.5 -0.25)
			(stroke
				(width 0.15)
				(type solid)
			)
			(fill no)
			(layer "B.Fab")
		)
		(pad "1" smd roundrect
			(at -0.485 0 90)
			(size 0.59 0.64)
			(layers "B.Cu" "B.Mask" "B.Paste")
			(roundrect_rratio 0.25)
			(net 14 "GND")
			(pintype "passive")
		)
		(pad "2" smd roundrect
			(at 0.485 0 90)
			(size 0.59 0.64)
			(layers "B.Cu" "B.Mask" "B.Paste")
			(roundrect_rratio 0.25)
			(net 40 "/LPDDR5/~{RESET}")
			(pintype "passive")
		)
	)
	(footprint "antmicro-footprints:C_0402_1005Metric"
		(layer "B.Cu")
		(at 136.175 84.35 -90)
		(descr "Capacitor SMD 0402")
		(tags "capacitor SMD 0402")
		(property "Reference" "C52"
			(at 0.85 -0.325 90)
			(unlocked yes)
			(layer "B.SilkS")
			(effects
				(font
					(size 0.7 0.7)
					(thickness 0.15)
				)
				(justify left bottom mirror)
			)
		)
		(property "Value" "C_4u7_0402"
			(at -1.022927 -2.155213 90)
			(layer "B.Fab")
			(effects
				(font
					(size 0.7 0.7)
					(thickness 0.15)
				)
				(justify left bottom mirror)
			)
		)
		(property "Author" "Antmicro"
			(at 51.825 220.525 0)
			(layer "B.Fab")
			(hide yes)
			(effects
				(font
					(size 1 1)
					(thickness 0.15)
				)
				(justify mirror)
			)
		)
		(property "Dielectric" ""
			(at 51.825 220.525 0)
			(layer "B.Fab")
			(hide yes)
			(effects
				(font
					(size 1 1)
					(thickness 0.15)
				)
				(justify mirror)
			)
		)
		(property "License" "Apache-2.0"
			(at 51.825 220.525 0)
			(layer "B.Fab")
			(hide yes)
			(effects
				(font
					(size 1 1)
					(thickness 0.15)
				)
				(justify mirror)
			)
		)
		(property "MPN" "GRM155R61A475MEAAD"
			(at 51.825 220.525 0)
			(layer "B.Fab")
			(hide yes)
			(effects
				(font
					(size 1 1)
					(thickness 0.15)
				)
				(justify mirror)
			)
		)
		(property "Manufacturer" "Murata"
			(at 51.825 220.525 0)
			(layer "B.Fab")
			(hide yes)
			(effects
				(font
					(size 1 1)
					(thickness 0.15)
				)
				(justify mirror)
			)
		)
		(property "Val" "4u7"
			(at 51.825 220.525 0)
			(layer "B.Fab")
			(hide yes)
			(effects
				(font
					(size 1 1)
					(thickness 0.15)
				)
				(justify mirror)
			)
		)
		(property "Voltage" ""
			(at 51.825 220.525 0)
			(layer "B.Fab")
			(hide yes)
			(effects
				(font
					(size 1 1)
					(thickness 0.15)
				)
				(justify mirror)
			)
		)
		(sheetname "LPDDR5")
		(sheetfile "lpddr5.kicad_sch")
		(attr smd)
		(fp_rect
			(start -0.9659 0.481258)
			(end 0.9649 -0.458742)
			(stroke
				(width 0.05)
				(type solid)
			)
			(fill no)
			(layer "B.CrtYd")
		)
		(fp_line
			(start -0.499 0.25)
			(end 0.499 0.25)
			(stroke
				(width 0.15)
				(type solid)
			)
			(layer "B.Fab")
		)
		(fp_line
			(start 0.499 0.25)
			(end 0.499 -0.248)
			(stroke
				(width 0.15)
				(type solid)
			)
			(layer "B.Fab")
		)
		(fp_line
			(start -0.499 -0.248)
			(end -0.499 0.25)
			(stroke
				(width 0.15)
				(type solid)
			)
			(layer "B.Fab")
		)
		(fp_line
			(start 0.499 -0.248)
			(end -0.499 -0.248)
			(stroke
				(width 0.15)
				(type solid)
			)
			(layer "B.Fab")
		)
		(pad "1" smd roundrect
			(at -0.484 0 270)
			(size 0.59 0.64)
			(layers "B.Cu" "B.Mask" "B.Paste")
			(roundrect_rratio 0.25)
			(net 14 "GND")
			(pintype "passive")
		)
		(pad "2" smd roundrect
			(at 0.484 0 270)
			(size 0.59 0.64)
			(layers "B.Cu" "B.Mask" "B.Paste")
			(roundrect_rratio 0.25)
			(net 12 "+0V9")
			(pintype "passive")
		)
	)
	(footprint "antmicro-footprints:C_0402_1005Metric"
		(layer "B.Cu")
		(at 140.375 86.15)
		(descr "Capacitor SMD 0402")
		(tags "capacitor SMD 0402")
		(property "Reference" "C44"
			(at 0.925 0.55 0)
			(unlocked yes)
			(layer "B.SilkS")
			(effects
				(font
					(size 0.7 0.7)
					(thickness 0.15)
				)
				(justify right bottom mirror)
			)
		)
		(property "Value" "C_4u7_0402"
			(at -1.022927 -2.155213 0)
			(layer "B.Fab")
			(effects
				(font
					(size 0.7 0.7)
					(thickness 0.15)
				)
				(justify right bottom mirror)
			)
		)
		(property "Author" "Antmicro"
			(at 0 0 0)
			(layer "B.Fab")
			(hide yes)
			(effects
				(font
					(size 1 1)
					(thickness 0.15)
				)
				(justify mirror)
			)
		)
		(property "Dielectric" ""
			(at 0 0 0)
			(layer "B.Fab")
			(hide yes)
			(effects
				(font
					(size 1 1)
					(thickness 0.15)
				)
				(justify mirror)
			)
		)
		(property "License" "Apache-2.0"
			(at 0 0 0)
			(layer "B.Fab")
			(hide yes)
			(effects
				(font
					(size 1 1)
					(thickness 0.15)
				)
				(justify mirror)
			)
		)
		(property "MPN" "GRM155R61A475MEAAD"
			(at 0 0 0)
			(layer "B.Fab")
			(hide yes)
			(effects
				(font
					(size 1 1)
					(thickness 0.15)
				)
				(justify mirror)
			)
		)
		(property "Manufacturer" "Murata"
			(at 0 0 0)
			(layer "B.Fab")
			(hide yes)
			(effects
				(font
					(size 1 1)
					(thickness 0.15)
				)
				(justify mirror)
			)
		)
		(property "Val" "4u7"
			(at 0 0 0)
			(layer "B.Fab")
			(hide yes)
			(effects
				(font
					(size 1 1)
					(thickness 0.15)
				)
				(justify mirror)
			)
		)
		(property "Voltage" ""
			(at 0 0 0)
			(layer "B.Fab")
			(hide yes)
			(effects
				(font
					(size 1 1)
					(thickness 0.15)
				)
				(justify mirror)
			)
		)
		(sheetname "LPDDR5")
		(sheetfile "lpddr5.kicad_sch")
		(attr smd)
		(fp_rect
			(start -0.9659 0.481258)
			(end 0.9649 -0.458742)
			(stroke
				(width 0.05)
				(type solid)
			)
			(fill no)
			(layer "B.CrtYd")
		)
		(fp_line
			(start -0.499 -0.248)
			(end -0.499 0.25)
			(stroke
				(width 0.15)
				(type solid)
			)
			(layer "B.Fab")
		)
		(fp_line
			(start -0.499 0.25)
			(end 0.499 0.25)
			(stroke
				(width 0.15)
				(type solid)
			)
			(layer "B.Fab")
		)
		(fp_line
			(start 0.499 -0.248)
			(end -0.499 -0.248)
			(stroke
				(width 0.15)
				(type solid)
			)
			(layer "B.Fab")
		)
		(fp_line
			(start 0.499 0.25)
			(end 0.499 -0.248)
			(stroke
				(width 0.15)
				(type solid)
			)
			(layer "B.Fab")
		)
		(pad "1" smd roundrect
			(at -0.484 0)
			(size 0.59 0.64)
			(layers "B.Cu" "B.Mask" "B.Paste")
			(roundrect_rratio 0.25)
			(net 14 "GND")
			(pintype "passive")
		)
		(pad "2" smd roundrect
			(at 0.484 0)
			(size 0.59 0.64)
			(layers "B.Cu" "B.Mask" "B.Paste")
			(roundrect_rratio 0.25)
			(net 35 "+1V8")
			(pintype "passive")
		)
	)
	(footprint "antmicro-footprints:R_Array_4x0402_Panasonic_EXB28V"
		(layer "B.Cu")
		(at 105.375 93.8)
		(property "Reference" "R23"
			(at 1.125 1.8 0)
			(unlocked yes)
			(layer "B.SilkS")
			(effects
				(font
					(size 0.7 0.7)
					(thickness 0.15)
				)
				(justify left bottom mirror)
			)
		)
		(property "Value" "R_4x100R_0402_array"
			(at -1.5 -2 180)
			(layer "B.Fab")
			(effects
				(font
					(size 0.7 0.7)
					(thickness 0.15)
				)
				(justify left bottom mirror)
			)
		)
		(property "Author" "Antmicro"
			(at 0 0 0)
			(layer "B.Fab")
			(hide yes)
			(effects
				(font
					(size 1 1)
					(thickness 0.15)
				)
				(justify mirror)
			)
		)
		(property "License" "Apache-2.0"
			(at 0 0 0)
			(layer "B.Fab")
			(hide yes)
			(effects
				(font
					(size 1 1)
					(thickness 0.15)
				)
				(justify mirror)
			)
		)
		(property "MPN" "EXB-28V101JX"
			(at 0 0 0)
			(layer "B.Fab")
			(hide yes)
			(effects
				(font
					(size 1 1)
					(thickness 0.15)
				)
				(justify mirror)
			)
		)
		(property "Manufacturer" "Panasonic"
			(at 0 0 0)
			(layer "B.Fab")
			(hide yes)
			(effects
				(font
					(size 1 1)
					(thickness 0.15)
				)
				(justify mirror)
			)
		)
		(property "Val" "R_4x100R_0402"
			(at 0 0 0)
			(layer "B.Fab")
			(hide yes)
			(effects
				(font
					(size 1 1)
					(thickness 0.15)
				)
				(justify mirror)
			)
		)
		(sheetname "Translators")
		(sheetfile "translators.kicad_sch")
		(attr smd)
		(fp_line
			(start -1.25 0.5)
			(end -1.25 -0.498)
			(stroke
				(width 0.15)
				(type solid)
			)
			(layer "B.SilkS")
		)
		(fp_line
			(start 1.25 -0.499)
			(end 1.25 0.499)
			(stroke
				(width 0.15)
				(type solid)
			)
			(layer "B.SilkS")
		)
		(fp_rect
			(start -1.25 0.8)
			(end 1.25 -0.8)
			(stroke
				(width 0.05)
				(type solid)
			)
			(fill no)
			(layer "B.CrtYd")
		)
		(fp_line
			(start -1 -0.498)
			(end -1 0.5)
			(stroke
				(width 0.15)
				(type solid)
			)
			(layer "B.Fab")
		)
		(fp_line
			(start -1 0.5)
			(end 0.998 0.5)
			(stroke
				(width 0.15)
				(type solid)
			)
			(layer "B.Fab")
		)
		(fp_line
			(start 0.998 -0.498)
			(end -1 -0.498)
			(stroke
				(width 0.15)
				(type solid)
			)
			(layer "B.Fab")
		)
		(fp_line
			(start 0.998 0.5)
			(end 0.998 -0.498)
			(stroke
				(width 0.15)
				(type solid)
			)
			(layer "B.Fab")
		)
		(pad "1" smd roundrect
			(at -0.8875 -0.45)
			(size 0.525 0.5)
			(layers "B.Cu" "B.Mask" "B.Paste")
			(roundrect_rratio 0.25)
			(net 128 "/LPDDR5/LPDDR5_A.DQ8")
			(pinfunction "R1.1")
			(pintype "passive")
		)
		(pad "2" smd roundrect
			(at -0.25 -0.45)
			(size 0.25 0.5)
			(layers "B.Cu" "B.Mask" "B.Paste")
			(roundrect_rratio 0.25)
			(net 139 "/LPDDR5/LPDDR5_A.DQ10")
			(pinfunction "R2.1")
			(pintype "passive")
		)
		(pad "3" smd roundrect
			(at 0.25 -0.45)
			(size 0.25 0.5)
			(layers "B.Cu" "B.Mask" "B.Paste")
			(roundrect_rratio 0.25)
			(net 172 "/LPDDR5/LPDDR5_A.DQ9")
			(pinfunction "R3.1")
			(pintype "passive")
		)
		(pad "4" smd roundrect
			(at 0.8875 -0.45)
			(size 0.525 0.5)
			(layers "B.Cu" "B.Mask" "B.Paste")
			(roundrect_rratio 0.25)
			(net 183 "/LPDDR5/LPDDR5_A.DQ11")
			(pinfunction "R4.1")
			(pintype "passive")
		)
		(pad "5" smd roundrect
			(at 0.8875 0.45)
			(size 0.525 0.5)
			(layers "B.Cu" "B.Mask" "B.Paste")
			(roundrect_rratio 0.25)
			(net 14 "GND")
			(pinfunction "R4.2")
			(pintype "passive")
		)
		(pad "6" smd roundrect
			(at 0.25 0.45)
			(size 0.25 0.5)
			(layers "B.Cu" "B.Mask" "B.Paste")
			(roundrect_rratio 0.25)
			(net 14 "GND")
			(pinfunction "R3.2")
			(pintype "passive")
		)
		(pad "7" smd roundrect
			(at -0.25 0.45)
			(size 0.25 0.5)
			(layers "B.Cu" "B.Mask" "B.Paste")
			(roundrect_rratio 0.25)
			(net 14 "GND")
			(pinfunction "R2.2")
			(pintype "passive")
		)
		(pad "8" smd roundrect
			(at -0.8875 0.45)
			(size 0.525 0.5)
			(layers "B.Cu" "B.Mask" "B.Paste")
			(roundrect_rratio 0.25)
			(net 14 "GND")
			(pinfunction "R1.2")
			(pintype "passive")
		)
	)
	(footprint "antmicro-footprints:R_Array_4x0402_Panasonic_EXB28V"
		(layer "B.Cu")
		(at 141.6 93.8 180)
		(property "Reference" "R61"
			(at -1.301 1.45 0)
			(unlocked yes)
			(layer "B.SilkS")
			(effects
				(font
					(size 0.7 0.7)
					(thickness 0.15)
				)
				(justify left bottom mirror)
			)
		)
		(property "Value" "R_4x100R_0402_array"
			(at -1.5 -2 0)
			(layer "B.Fab")
			(effects
				(font
					(size 0.7 0.7)
					(thickness 0.15)
				)
				(justify left bottom mirror)
			)
		)
		(property "Author" "Antmicro"
			(at 283.2 187.6 0)
			(layer "B.Fab")
			(hide yes)
			(effects
				(font
					(size 1 1)
					(thickness 0.15)
				)
				(justify mirror)
			)
		)
		(property "License" "Apache-2.0"
			(at 283.2 187.6 0)
			(layer "B.Fab")
			(hide yes)
			(effects
				(font
					(size 1 1)
					(thickness 0.15)
				)
				(justify mirror)
			)
		)
		(property "MPN" "EXB-28V101JX"
			(at 283.2 187.6 0)
			(layer "B.Fab")
			(hide yes)
			(effects
				(font
					(size 1 1)
					(thickness 0.15)
				)
				(justify mirror)
			)
		)
		(property "Manufacturer" "Panasonic"
			(at 283.2 187.6 0)
			(layer "B.Fab")
			(hide yes)
			(effects
				(font
					(size 1 1)
					(thickness 0.15)
				)
				(justify mirror)
			)
		)
		(property "Val" "R_4x100R_0402"
			(at 283.2 187.6 0)
			(layer "B.Fab")
			(hide yes)
			(effects
				(font
					(size 1 1)
					(thickness 0.15)
				)
				(justify mirror)
			)
		)
		(sheetname "Translators1")
		(sheetfile "translators.kicad_sch")
		(attr smd)
		(fp_line
			(start 1.25 -0.499)
			(end 1.25 0.499)
			(stroke
				(width 0.15)
				(type solid)
			)
			(layer "B.SilkS")
		)
		(fp_line
			(start -1.25 0.5)
			(end -1.25 -0.498)
			(stroke
				(width 0.15)
				(type solid)
			)
			(layer "B.SilkS")
		)
		(fp_rect
			(start -1.25 0.8)
			(end 1.25 -0.8)
			(stroke
				(width 0.05)
				(type solid)
			)
			(fill no)
			(layer "B.CrtYd")
		)
		(fp_line
			(start 0.998 0.5)
			(end 0.998 -0.498)
			(stroke
				(width 0.15)
				(type solid)
			)
			(layer "B.Fab")
		)
		(fp_line
			(start 0.998 -0.498)
			(end -1 -0.498)
			(stroke
				(width 0.15)
				(type solid)
			)
			(layer "B.Fab")
		)
		(fp_line
			(start -1 0.5)
			(end 0.998 0.5)
			(stroke
				(width 0.15)
				(type solid)
			)
			(layer "B.Fab")
		)
		(fp_line
			(start -1 -0.498)
			(end -1 0.5)
			(stroke
				(width 0.15)
				(type solid)
			)
			(layer "B.Fab")
		)
		(pad "1" smd roundrect
			(at -0.8875 -0.45 180)
			(size 0.525 0.5)
			(layers "B.Cu" "B.Mask" "B.Paste")
			(roundrect_rratio 0.25)
			(net 148 "/SODIMM/LPDDR5_IN_B.CA2")
			(pinfunction "R1.1")
			(pintype "passive")
		)
		(pad "2" smd roundrect
			(at -0.25 -0.45 180)
			(size 0.25 0.5)
			(layers "B.Cu" "B.Mask" "B.Paste")
			(roundrect_rratio 0.25)
			(net 149 "/SODIMM/LPDDR5_IN_B.CA3")
			(pinfunction "R2.1")
			(pintype "passive")
		)
		(pad "3" smd roundrect
			(at 0.25 -0.45 180)
			(size 0.25 0.5)
			(layers "B.Cu" "B.Mask" "B.Paste")
			(roundrect_rratio 0.25)
			(net 150 "/SODIMM/LPDDR5_IN_B.CA4")
			(pinfunction "R3.1")
			(pintype "passive")
		)
		(pad "4" smd roundrect
			(at 0.8875 -0.45 180)
			(size 0.525 0.5)
			(layers "B.Cu" "B.Mask" "B.Paste")
			(roundrect_rratio 0.25)
			(net 151 "/SODIMM/LPDDR5_IN_B.CA5")
			(pinfunction "R4.1")
			(pintype "passive")
		)
		(pad "5" smd roundrect
			(at 0.8875 0.45 180)
			(size 0.525 0.5)
			(layers "B.Cu" "B.Mask" "B.Paste")
			(roundrect_rratio 0.25)
			(net 101 "/LPDDR5/LPDDR5_B.CA5")
			(pinfunction "R4.2")
			(pintype "passive")
		)
		(pad "6" smd roundrect
			(at 0.25 0.45 180)
			(size 0.25 0.5)
			(layers "B.Cu" "B.Mask" "B.Paste")
			(roundrect_rratio 0.25)
			(net 105 "/LPDDR5/LPDDR5_B.CA4")
			(pinfunction "R3.2")
			(pintype "passive")
		)
		(pad "7" smd roundrect
			(at -0.25 0.45 180)
			(size 0.25 0.5)
			(layers "B.Cu" "B.Mask" "B.Paste")
			(roundrect_rratio 0.25)
			(net 99 "/LPDDR5/LPDDR5_B.CA3")
			(pinfunction "R2.2")
			(pintype "passive")
		)
		(pad "8" smd roundrect
			(at -0.8875 0.45 180)
			(size 0.525 0.5)
			(layers "B.Cu" "B.Mask" "B.Paste")
			(roundrect_rratio 0.25)
			(net 104 "/LPDDR5/LPDDR5_B.CA2")
			(pinfunction "R1.2")
			(pintype "passive")
		)
	)
	(footprint "antmicro-footprints:R_Array_4x0402_Panasonic_EXB28V"
		(layer "B.Cu")
		(at 115.875 93.8)
		(property "Reference" "R19"
			(at 1.025 1.8 0)
			(unlocked yes)
			(layer "B.SilkS")
			(effects
				(font
					(size 0.7 0.7)
					(thickness 0.15)
				)
				(justify left bottom mirror)
			)
		)
		(property "Value" "R_4x100R_0402_array"
			(at -1.5 -2 180)
			(layer "B.Fab")
			(effects
				(font
					(size 0.7 0.7)
					(thickness 0.15)
				)
				(justify left bottom mirror)
			)
		)
		(property "Author" "Antmicro"
			(at 0 0 0)
			(layer "B.Fab")
			(hide yes)
			(effects
				(font
					(size 1 1)
					(thickness 0.15)
				)
				(justify mirror)
			)
		)
		(property "License" "Apache-2.0"
			(at 0 0 0)
			(layer "B.Fab")
			(hide yes)
			(effects
				(font
					(size 1 1)
					(thickness 0.15)
				)
				(justify mirror)
			)
		)
		(property "MPN" "EXB-28V101JX"
			(at 0 0 0)
			(layer "B.Fab")
			(hide yes)
			(effects
				(font
					(size 1 1)
					(thickness 0.15)
				)
				(justify mirror)
			)
		)
		(property "Manufacturer" "Panasonic"
			(at 0 0 0)
			(layer "B.Fab")
			(hide yes)
			(effects
				(font
					(size 1 1)
					(thickness 0.15)
				)
				(justify mirror)
			)
		)
		(property "Val" "R_4x100R_0402"
			(at 0 0 0)
			(layer "B.Fab")
			(hide yes)
			(effects
				(font
					(size 1 1)
					(thickness 0.15)
				)
				(justify mirror)
			)
		)
		(sheetname "Translators")
		(sheetfile "translators.kicad_sch")
		(attr smd)
		(fp_line
			(start -1.25 0.5)
			(end -1.25 -0.498)
			(stroke
				(width 0.15)
				(type solid)
			)
			(layer "B.SilkS")
		)
		(fp_line
			(start 1.25 -0.499)
			(end 1.25 0.499)
			(stroke
				(width 0.15)
				(type solid)
			)
			(layer "B.SilkS")
		)
		(fp_rect
			(start -1.25 0.8)
			(end 1.25 -0.8)
			(stroke
				(width 0.05)
				(type solid)
			)
			(fill no)
			(layer "B.CrtYd")
		)
		(fp_line
			(start -1 -0.498)
			(end -1 0.5)
			(stroke
				(width 0.15)
				(type solid)
			)
			(layer "B.Fab")
		)
		(fp_line
			(start -1 0.5)
			(end 0.998 0.5)
			(stroke
				(width 0.15)
				(type solid)
			)
			(layer "B.Fab")
		)
		(fp_line
			(start 0.998 -0.498)
			(end -1 -0.498)
			(stroke
				(width 0.15)
				(type solid)
			)
			(layer "B.Fab")
		)
		(fp_line
			(start 0.998 0.5)
			(end 0.998 -0.498)
			(stroke
				(width 0.15)
				(type solid)
			)
			(layer "B.Fab")
		)
		(pad "1" smd roundrect
			(at -0.8875 -0.45)
			(size 0.525 0.5)
			(layers "B.Cu" "B.Mask" "B.Paste")
			(roundrect_rratio 0.25)
			(net 197 "/LPDDR5/LPDDR5_A.DQ5")
			(pinfunction "R1.1")
			(pintype "passive")
		)
		(pad "2" smd roundrect
			(at -0.25 -0.45)
			(size 0.25 0.5)
			(layers "B.Cu" "B.Mask" "B.Paste")
			(roundrect_rratio 0.25)
			(net 198 "/LPDDR5/LPDDR5_A.DQ4")
			(pinfunction "R2.1")
			(pintype "passive")
		)
		(pad "3" smd roundrect
			(at 0.25 -0.45)
			(size 0.25 0.5)
			(layers "B.Cu" "B.Mask" "B.Paste")
			(roundrect_rratio 0.25)
			(net 196 "/LPDDR5/LPDDR5_A.DQ6")
			(pinfunction "R3.1")
			(pintype "passive")
		)
		(pad "4" smd roundrect
			(at 0.8875 -0.45)
			(size 0.525 0.5)
			(layers "B.Cu" "B.Mask" "B.Paste")
			(roundrect_rratio 0.25)
			(net 195 "/LPDDR5/LPDDR5_A.DQ7")
			(pinfunction "R4.1")
			(pintype "passive")
		)
		(pad "5" smd roundrect
			(at 0.8875 0.45)
			(size 0.525 0.5)
			(layers "B.Cu" "B.Mask" "B.Paste")
			(roundrect_rratio 0.25)
			(net 14 "GND")
			(pinfunction "R4.2")
			(pintype "passive")
		)
		(pad "6" smd roundrect
			(at 0.25 0.45)
			(size 0.25 0.5)
			(layers "B.Cu" "B.Mask" "B.Paste")
			(roundrect_rratio 0.25)
			(net 14 "GND")
			(pinfunction "R3.2")
			(pintype "passive")
		)
		(pad "7" smd roundrect
			(at -0.25 0.45)
			(size 0.25 0.5)
			(layers "B.Cu" "B.Mask" "B.Paste")
			(roundrect_rratio 0.25)
			(net 14 "GND")
			(pinfunction "R2.2")
			(pintype "passive")
		)
		(pad "8" smd roundrect
			(at -0.8875 0.45)
			(size 0.525 0.5)
			(layers "B.Cu" "B.Mask" "B.Paste")
			(roundrect_rratio 0.25)
			(net 14 "GND")
			(pinfunction "R1.2")
			(pintype "passive")
		)
	)
	(footprint "antmicro-footprints:R_0402_1005Metric"
		(layer "B.Cu")
		(at 164.95 90.9 90)
		(descr "Resistor SMD 0402")
		(tags "resistor SMD 0402")
		(property "Reference" "R65"
			(at -0.1 0.45 0)
			(unlocked yes)
			(layer "B.SilkS")
			(effects
				(font
					(size 0.7 0.7)
					(thickness 0.15)
				)
				(justify right bottom mirror)
			)
		)
		(property "Value" "R_100R_0402"
			(at -1.011843 -1.772047 90)
			(layer "B.Fab")
			(effects
				(font
					(size 0.7 0.7)
					(thickness 0.15)
				)
				(justify right bottom mirror)
			)
		)
		(property "Author" "Antmicro"
			(at 255.85 -74.05 0)
			(layer "B.Fab")
			(hide yes)
			(effects
				(font
					(size 1 1)
					(thickness 0.15)
				)
				(justify mirror)
			)
		)
		(property "License" "Apache-2.0"
			(at 255.85 -74.05 0)
			(layer "B.Fab")
			(hide yes)
			(effects
				(font
					(size 1 1)
					(thickness 0.15)
				)
				(justify mirror)
			)
		)
		(property "MPN" "CR0402-FX-1000GLF"
			(at 255.85 -74.05 0)
			(layer "B.Fab")
			(hide yes)
			(effects
				(font
					(size 1 1)
					(thickness 0.15)
				)
				(justify mirror)
			)
		)
		(property "Manufacturer" "Bourns"
			(at 255.85 -74.05 0)
			(layer "B.Fab")
			(hide yes)
			(effects
				(font
					(size 1 1)
					(thickness 0.15)
				)
				(justify mirror)
			)
		)
		(property "Tolerance" "1%"
			(at 255.85 -74.05 0)
			(layer "B.Fab")
			(hide yes)
			(effects
				(font
					(size 1 1)
					(thickness 0.15)
				)
				(justify mirror)
			)
		)
		(property "Val" "100R"
			(at 255.85 -74.05 0)
			(layer "B.Fab")
			(hide yes)
			(effects
				(font
					(size 1 1)
					(thickness 0.15)
				)
				(justify mirror)
			)
		)
		(sheetname "Translators1")
		(sheetfile "translators.kicad_sch")
		(attr smd)
		(fp_rect
			(start -0.93 0.47)
			(end 0.93 -0.47)
			(stroke
				(width 0.05)
				(type solid)
			)
			(fill no)
			(layer "B.CrtYd")
		)
		(fp_rect
			(start -0.5 0.25)
			(end 0.5 -0.25)
			(stroke
				(width 0.15)
				(type solid)
			)
			(fill no)
			(layer "B.Fab")
		)
		(pad "1" smd roundrect
			(at -0.485 0 90)
			(size 0.59 0.64)
			(layers "B.Cu" "B.Mask" "B.Paste")
			(roundrect_rratio 0.25)
			(net 126 "/SODIMM/LPDDR5_IN_B.WCK0_P")
			(pintype "passive")
		)
		(pad "2" smd roundrect
			(at 0.485 0 90)
			(size 0.59 0.64)
			(layers "B.Cu" "B.Mask" "B.Paste")
			(roundrect_rratio 0.25)
			(net 108 "/LPDDR5/LPDDR5_B.WCK0_P")
			(pintype "passive")
		)
	)
	(footprint "antmicro-footprints:C_0402_1005Metric"
		(layer "B.Cu")
		(at 137.575 84.35 -90)
		(descr "Capacitor SMD 0402")
		(tags "capacitor SMD 0402")
		(property "Reference" "C37"
			(at 0.85 -0.325 90)
			(unlocked yes)
			(layer "B.SilkS")
			(effects
				(font
					(size 0.7 0.7)
					(thickness 0.15)
				)
				(justify left bottom mirror)
			)
		)
		(property "Value" "C_4u7_0402"
			(at -1.022927 -2.155213 90)
			(layer "B.Fab")
			(effects
				(font
					(size 0.7 0.7)
					(thickness 0.15)
				)
				(justify left bottom mirror)
			)
		)
		(property "Author" "Antmicro"
			(at 53.225 221.925 0)
			(layer "B.Fab")
			(hide yes)
			(effects
				(font
					(size 1 1)
					(thickness 0.15)
				)
				(justify mirror)
			)
		)
		(property "Dielectric" ""
			(at 53.225 221.925 0)
			(layer "B.Fab")
			(hide yes)
			(effects
				(font
					(size 1 1)
					(thickness 0.15)
				)
				(justify mirror)
			)
		)
		(property "License" "Apache-2.0"
			(at 53.225 221.925 0)
			(layer "B.Fab")
			(hide yes)
			(effects
				(font
					(size 1 1)
					(thickness 0.15)
				)
				(justify mirror)
			)
		)
		(property "MPN" "GRM155R61A475MEAAD"
			(at 53.225 221.925 0)
			(layer "B.Fab")
			(hide yes)
			(effects
				(font
					(size 1 1)
					(thickness 0.15)
				)
				(justify mirror)
			)
		)
		(property "Manufacturer" "Murata"
			(at 53.225 221.925 0)
			(layer "B.Fab")
			(hide yes)
			(effects
				(font
					(size 1 1)
					(thickness 0.15)
				)
				(justify mirror)
			)
		)
		(property "Val" "4u7"
			(at 53.225 221.925 0)
			(layer "B.Fab")
			(hide yes)
			(effects
				(font
					(size 1 1)
					(thickness 0.15)
				)
				(justify mirror)
			)
		)
		(property "Voltage" ""
			(at 53.225 221.925 0)
			(layer "B.Fab")
			(hide yes)
			(effects
				(font
					(size 1 1)
					(thickness 0.15)
				)
				(justify mirror)
			)
		)
		(sheetname "LPDDR5")
		(sheetfile "lpddr5.kicad_sch")
		(attr smd)
		(fp_rect
			(start -0.9659 0.481258)
			(end 0.9649 -0.458742)
			(stroke
				(width 0.05)
				(type solid)
			)
			(fill no)
			(layer "B.CrtYd")
		)
		(fp_line
			(start -0.499 0.25)
			(end 0.499 0.25)
			(stroke
				(width 0.15)
				(type solid)
			)
			(layer "B.Fab")
		)
		(fp_line
			(start 0.499 0.25)
			(end 0.499 -0.248)
			(stroke
				(width 0.15)
				(type solid)
			)
			(layer "B.Fab")
		)
		(fp_line
			(start -0.499 -0.248)
			(end -0.499 0.25)
			(stroke
				(width 0.15)
				(type solid)
			)
			(layer "B.Fab")
		)
		(fp_line
			(start 0.499 -0.248)
			(end -0.499 -0.248)
			(stroke
				(width 0.15)
				(type solid)
			)
			(layer "B.Fab")
		)
		(pad "1" smd roundrect
			(at -0.484 0 270)
			(size 0.59 0.64)
			(layers "B.Cu" "B.Mask" "B.Paste")
			(roundrect_rratio 0.25)
			(net 14 "GND")
			(pintype "passive")
		)
		(pad "2" smd roundrect
			(at 0.484 0 270)
			(size 0.59 0.64)
			(layers "B.Cu" "B.Mask" "B.Paste")
			(roundrect_rratio 0.25)
			(net 4 "+0V5")
			(pintype "passive")
		)
	)
	(footprint "antmicro-footprints:C_0402_1005Metric"
		(layer "B.Cu")
		(at 129.175 73.75 180)
		(descr "Capacitor SMD 0402")
		(tags "capacitor SMD 0402")
		(property "Reference" "C38"
			(at 1.075 -0.35 0)
			(unlocked yes)
			(layer "B.SilkS")
			(effects
				(font
					(size 0.7 0.7)
					(thickness 0.15)
				)
				(justify left bottom mirror)
			)
		)
		(property "Value" "C_4u7_0402"
			(at -1.022927 -2.155213 0)
			(layer "B.Fab")
			(effects
				(font
					(size 0.7 0.7)
					(thickness 0.15)
				)
				(justify left bottom mirror)
			)
		)
		(property "Author" "Antmicro"
			(at 258.35 147.5 0)
			(layer "B.Fab")
			(hide yes)
			(effects
				(font
					(size 1 1)
					(thickness 0.15)
				)
				(justify mirror)
			)
		)
		(property "Dielectric" ""
			(at 258.35 147.5 0)
			(layer "B.Fab")
			(hide yes)
			(effects
				(font
					(size 1 1)
					(thickness 0.15)
				)
				(justify mirror)
			)
		)
		(property "License" "Apache-2.0"
			(at 258.35 147.5 0)
			(layer "B.Fab")
			(hide yes)
			(effects
				(font
					(size 1 1)
					(thickness 0.15)
				)
				(justify mirror)
			)
		)
		(property "MPN" "GRM155R61A475MEAAD"
			(at 258.35 147.5 0)
			(layer "B.Fab")
			(hide yes)
			(effects
				(font
					(size 1 1)
					(thickness 0.15)
				)
				(justify mirror)
			)
		)
		(property "Manufacturer" "Murata"
			(at 258.35 147.5 0)
			(layer "B.Fab")
			(hide yes)
			(effects
				(font
					(size 1 1)
					(thickness 0.15)
				)
				(justify mirror)
			)
		)
		(property "Val" "4u7"
			(at 258.35 147.5 0)
			(layer "B.Fab")
			(hide yes)
			(effects
				(font
					(size 1 1)
					(thickness 0.15)
				)
				(justify mirror)
			)
		)
		(property "Voltage" ""
			(at 258.35 147.5 0)
			(layer "B.Fab")
			(hide yes)
			(effects
				(font
					(size 1 1)
					(thickness 0.15)
				)
				(justify mirror)
			)
		)
		(sheetname "LPDDR5")
		(sheetfile "lpddr5.kicad_sch")
		(attr smd)
		(fp_rect
			(start -0.9659 0.481258)
			(end 0.9649 -0.458742)
			(stroke
				(width 0.05)
				(type solid)
			)
			(fill no)
			(layer "B.CrtYd")
		)
		(fp_line
			(start 0.499 0.25)
			(end 0.499 -0.248)
			(stroke
				(width 0.15)
				(type solid)
			)
			(layer "B.Fab")
		)
		(fp_line
			(start 0.499 -0.248)
			(end -0.499 -0.248)
			(stroke
				(width 0.15)
				(type solid)
			)
			(layer "B.Fab")
		)
		(fp_line
			(start -0.499 0.25)
			(end 0.499 0.25)
			(stroke
				(width 0.15)
				(type solid)
			)
			(layer "B.Fab")
		)
		(fp_line
			(start -0.499 -0.248)
			(end -0.499 0.25)
			(stroke
				(width 0.15)
				(type solid)
			)
			(layer "B.Fab")
		)
		(pad "1" smd roundrect
			(at -0.484 0 180)
			(size 0.59 0.64)
			(layers "B.Cu" "B.Mask" "B.Paste")
			(roundrect_rratio 0.25)
			(net 14 "GND")
			(pintype "passive")
		)
		(pad "2" smd roundrect
			(at 0.484 0 180)
			(size 0.59 0.64)
			(layers "B.Cu" "B.Mask" "B.Paste")
			(roundrect_rratio 0.25)
			(net 35 "+1V8")
			(pintype "passive")
		)
	)
	(footprint "antmicro-footprints:SOT-23-5"
		(layer "B.Cu")
		(at 107.25 82.9 -90)
		(property "Reference" "U7"
			(at 0.002 2 90)
			(unlocked yes)
			(layer "B.SilkS")
			(effects
				(font
					(size 0.7 0.7)
					(thickness 0.15)
				)
				(justify left bottom mirror)
			)
		)
		(property "Value" "AT24CS01_SOT23"
			(at 0.002 -2.799 90)
			(layer "B.Fab")
			(effects
				(font
					(size 0.7 0.7)
					(thickness 0.15)
				)
				(justify left bottom mirror)
			)
		)
		(property "Author" "Antmicro"
			(at 24.35 190.15 0)
			(layer "B.Fab")
			(hide yes)
			(effects
				(font
					(size 1 1)
					(thickness 0.15)
				)
				(justify mirror)
			)
		)
		(property "License" "Apache-2.0"
			(at 24.35 190.15 0)
			(layer "B.Fab")
			(hide yes)
			(effects
				(font
					(size 1 1)
					(thickness 0.15)
				)
				(justify mirror)
			)
		)
		(property "MPN" "AT24CS01-ST"
			(at 24.35 190.15 0)
			(layer "B.Fab")
			(hide yes)
			(effects
				(font
					(size 1 1)
					(thickness 0.15)
				)
				(justify mirror)
			)
		)
		(property "Manufacturer" "Atmel"
			(at 24.35 190.15 0)
			(layer "B.Fab")
			(hide yes)
			(effects
				(font
					(size 1 1)
					(thickness 0.15)
				)
				(justify mirror)
			)
		)
		(sheetname "SODIMM")
		(sheetfile "sodim.kicad_sch")
		(attr smd)
		(fp_line
			(start -0.8 1.6)
			(end -0.5 1.6)
			(stroke
				(width 0.15)
				(type solid)
			)
			(layer "B.SilkS")
		)
		(fp_line
			(start -0.8 1.6)
			(end -0.8 1.3)
			(stroke
				(width 0.15)
				(type solid)
			)
			(layer "B.SilkS")
		)
		(fp_line
			(start 0.8 1.6)
			(end 0.5 1.6)
			(stroke
				(width 0.15)
				(type solid)
			)
			(layer "B.SilkS")
		)
		(fp_line
			(start 0.8 1.3)
			(end 0.8 1.6)
			(stroke
				(width 0.15)
				(type solid)
			)
			(layer "B.SilkS")
		)
		(fp_line
			(start 0.8 -0.55)
			(end 0.8 0.55)
			(stroke
				(width 0.15)
				(type solid)
			)
			(layer "B.SilkS")
		)
		(fp_line
			(start 0.8 -1.3)
			(end 0.8 -1.599)
			(stroke
				(width 0.15)
				(type solid)
			)
			(layer "B.SilkS")
		)
		(fp_line
			(start 0.8 -1.599)
			(end 0.549 -1.599)
			(stroke
				(width 0.15)
				(type solid)
			)
			(layer "B.SilkS")
		)
		(fp_line
			(start -0.85 -1.6)
			(end -0.85 -1.301)
			(stroke
				(width 0.15)
				(type solid)
			)
			(layer "B.SilkS")
		)
		(fp_line
			(start -0.55 -1.6)
			(end -0.85 -1.6)
			(stroke
				(width 0.15)
				(type solid)
			)
			(layer "B.SilkS")
		)
		(fp_circle
			(center -1.25 1.5)
			(end -1.2 1.5)
			(stroke
				(width 0.15)
				(type solid)
			)
			(fill yes)
			(layer "B.SilkS")
		)
		(fp_rect
			(start 1.9 1.76)
			(end -1.9 -1.75)
			(stroke
				(width 0.05)
				(type solid)
			)
			(fill no)
			(layer "B.CrtYd")
		)
		(fp_line
			(start -0.398 1.526)
			(end -0.874 1.05)
			(stroke
				(width 0.15)
				(type solid)
			)
			(layer "B.Fab")
		)
		(fp_rect
			(start 0.874 -1.523)
			(end -0.873 1.525)
			(stroke
				(width 0.15)
				(type solid)
			)
			(fill no)
			(layer "B.Fab")
		)
		(pad "1" smd rect
			(at -1.351 0.951)
			(size 0.55 1)
			(layers "B.Cu" "B.Mask" "B.Paste")
			(net 18 "/SODIMM/HSCL")
			(pinfunction "SCL")
			(pintype "passive")
		)
		(pad "2" smd rect
			(at -1.351 0)
			(size 0.55 1)
			(layers "B.Cu" "B.Mask" "B.Paste")
			(net 14 "GND")
			(pinfunction "GND")
			(pintype "passive")
		)
		(pad "3" smd rect
			(at -1.351 -0.949)
			(size 0.55 1)
			(layers "B.Cu" "B.Mask" "B.Paste")
			(net 19 "/SODIMM/HSDA")
			(pinfunction "SDA")
			(pintype "passive")
		)
		(pad "4" smd rect
			(at 1.35 -0.949)
			(size 0.55 1)
			(layers "B.Cu" "B.Mask" "B.Paste")
			(net 35 "+1V8")
			(pinfunction "VCC")
			(pintype "passive")
		)
		(pad "5" smd rect
			(at 1.35 0.951)
			(size 0.55 1)
			(layers "B.Cu" "B.Mask" "B.Paste")
			(net 14 "GND")
			(pinfunction "WP")
			(pintype "passive")
		)
	)
	(footprint "antmicro-footprints:C_0402_1005Metric"
		(layer "B.Cu")
		(at 134.775 78 -90)
		(descr "Capacitor SMD 0402")
		(tags "capacitor SMD 0402")
		(property "Reference" "C68"
			(at -1.1 0.675 90)
			(unlocked yes)
			(layer "B.SilkS")
			(effects
				(font
					(size 0.7 0.7)
					(thickness 0.15)
				)
				(justify left bottom mirror)
			)
		)
		(property "Value" "C_4u7_0402"
			(at -1.022927 -2.155213 90)
			(layer "B.Fab")
			(effects
				(font
					(size 0.7 0.7)
					(thickness 0.15)
				)
				(justify left bottom mirror)
			)
		)
		(property "Author" "Antmicro"
			(at 56.775 212.775 0)
			(layer "B.Fab")
			(hide yes)
			(effects
				(font
					(size 1 1)
					(thickness 0.15)
				)
				(justify mirror)
			)
		)
		(property "Dielectric" ""
			(at 56.775 212.775 0)
			(layer "B.Fab")
			(hide yes)
			(effects
				(font
					(size 1 1)
					(thickness 0.15)
				)
				(justify mirror)
			)
		)
		(property "License" "Apache-2.0"
			(at 56.775 212.775 0)
			(layer "B.Fab")
			(hide yes)
			(effects
				(font
					(size 1 1)
					(thickness 0.15)
				)
				(justify mirror)
			)
		)
		(property "MPN" "GRM155R61A475MEAAD"
			(at 56.775 212.775 0)
			(layer "B.Fab")
			(hide yes)
			(effects
				(font
					(size 1 1)
					(thickness 0.15)
				)
				(justify mirror)
			)
		)
		(property "Manufacturer" "Murata"
			(at 56.775 212.775 0)
			(layer "B.Fab")
			(hide yes)
			(effects
				(font
					(size 1 1)
					(thickness 0.15)
				)
				(justify mirror)
			)
		)
		(property "Val" "4u7"
			(at 56.775 212.775 0)
			(layer "B.Fab")
			(hide yes)
			(effects
				(font
					(size 1 1)
					(thickness 0.15)
				)
				(justify mirror)
			)
		)
		(property "Voltage" ""
			(at 56.775 212.775 0)
			(layer "B.Fab")
			(hide yes)
			(effects
				(font
					(size 1 1)
					(thickness 0.15)
				)
				(justify mirror)
			)
		)
		(sheetname "LPDDR5")
		(sheetfile "lpddr5.kicad_sch")
		(attr smd)
		(fp_rect
			(start -0.9659 0.481258)
			(end 0.9649 -0.458742)
			(stroke
				(width 0.05)
				(type solid)
			)
			(fill no)
			(layer "B.CrtYd")
		)
		(fp_line
			(start -0.499 0.25)
			(end 0.499 0.25)
			(stroke
				(width 0.15)
				(type solid)
			)
			(layer "B.Fab")
		)
		(fp_line
			(start 0.499 0.25)
			(end 0.499 -0.248)
			(stroke
				(width 0.15)
				(type solid)
			)
			(layer "B.Fab")
		)
		(fp_line
			(start -0.499 -0.248)
			(end -0.499 0.25)
			(stroke
				(width 0.15)
				(type solid)
			)
			(layer "B.Fab")
		)
		(fp_line
			(start 0.499 -0.248)
			(end -0.499 -0.248)
			(stroke
				(width 0.15)
				(type solid)
			)
			(layer "B.Fab")
		)
		(pad "1" smd roundrect
			(at -0.484 0 270)
			(size 0.59 0.64)
			(layers "B.Cu" "B.Mask" "B.Paste")
			(roundrect_rratio 0.25)
			(net 14 "GND")
			(pintype "passive")
		)
		(pad "2" smd roundrect
			(at 0.484 0 270)
			(size 0.59 0.64)
			(layers "B.Cu" "B.Mask" "B.Paste")
			(roundrect_rratio 0.25)
			(net 13 "+1V05")
			(pintype "passive")
		)
	)
	(footprint "antmicro-footprints:C_0402_1005Metric"
		(layer "B.Cu")
		(at 140.375 74.95)
		(descr "Capacitor SMD 0402")
		(tags "capacitor SMD 0402")
		(property "Reference" "C49"
			(at 1.125 0.35 0)
			(unlocked yes)
			(layer "B.SilkS")
			(effects
				(font
					(size 0.7 0.7)
					(thickness 0.15)
				)
				(justify right bottom mirror)
			)
		)
		(property "Value" "C_4u7_0402"
			(at -1.022927 -2.155213 0)
			(layer "B.Fab")
			(effects
				(font
					(size 0.7 0.7)
					(thickness 0.15)
				)
				(justify right bottom mirror)
			)
		)
		(property "Author" "Antmicro"
			(at 0 0 0)
			(layer "B.Fab")
			(hide yes)
			(effects
				(font
					(size 1 1)
					(thickness 0.15)
				)
				(justify mirror)
			)
		)
		(property "Dielectric" ""
			(at 0 0 0)
			(layer "B.Fab")
			(hide yes)
			(effects
				(font
					(size 1 1)
					(thickness 0.15)
				)
				(justify mirror)
			)
		)
		(property "License" "Apache-2.0"
			(at 0 0 0)
			(layer "B.Fab")
			(hide yes)
			(effects
				(font
					(size 1 1)
					(thickness 0.15)
				)
				(justify mirror)
			)
		)
		(property "MPN" "GRM155R61A475MEAAD"
			(at 0 0 0)
			(layer "B.Fab")
			(hide yes)
			(effects
				(font
					(size 1 1)
					(thickness 0.15)
				)
				(justify mirror)
			)
		)
		(property "Manufacturer" "Murata"
			(at 0 0 0)
			(layer "B.Fab")
			(hide yes)
			(effects
				(font
					(size 1 1)
					(thickness 0.15)
				)
				(justify mirror)
			)
		)
		(property "Val" "4u7"
			(at 0 0 0)
			(layer "B.Fab")
			(hide yes)
			(effects
				(font
					(size 1 1)
					(thickness 0.15)
				)
				(justify mirror)
			)
		)
		(property "Voltage" ""
			(at 0 0 0)
			(layer "B.Fab")
			(hide yes)
			(effects
				(font
					(size 1 1)
					(thickness 0.15)
				)
				(justify mirror)
			)
		)
		(sheetname "LPDDR5")
		(sheetfile "lpddr5.kicad_sch")
		(attr smd)
		(fp_rect
			(start -0.9659 0.481258)
			(end 0.9649 -0.458742)
			(stroke
				(width 0.05)
				(type solid)
			)
			(fill no)
			(layer "B.CrtYd")
		)
		(fp_line
			(start -0.499 -0.248)
			(end -0.499 0.25)
			(stroke
				(width 0.15)
				(type solid)
			)
			(layer "B.Fab")
		)
		(fp_line
			(start -0.499 0.25)
			(end 0.499 0.25)
			(stroke
				(width 0.15)
				(type solid)
			)
			(layer "B.Fab")
		)
		(fp_line
			(start 0.499 -0.248)
			(end -0.499 -0.248)
			(stroke
				(width 0.15)
				(type solid)
			)
			(layer "B.Fab")
		)
		(fp_line
			(start 0.499 0.25)
			(end 0.499 -0.248)
			(stroke
				(width 0.15)
				(type solid)
			)
			(layer "B.Fab")
		)
		(pad "1" smd roundrect
			(at -0.484 0)
			(size 0.59 0.64)
			(layers "B.Cu" "B.Mask" "B.Paste")
			(roundrect_rratio 0.25)
			(net 14 "GND")
			(pintype "passive")
		)
		(pad "2" smd roundrect
			(at 0.484 0)
			(size 0.59 0.64)
			(layers "B.Cu" "B.Mask" "B.Paste")
			(roundrect_rratio 0.25)
			(net 4 "+0V5")
			(pintype "passive")
		)
	)
	(footprint "antmicro-footprints:R_0402_1005Metric"
		(layer "B.Cu")
		(at 117.13 90.94 90)
		(descr "Resistor SMD 0402")
		(tags "resistor SMD 0402")
		(property "Reference" "R11"
			(at -0.16 -2.73 0)
			(unlocked yes)
			(layer "B.SilkS")
			(effects
				(font
					(size 0.7 0.7)
					(thickness 0.15)
				)
				(justify right bottom mirror)
			)
		)
		(property "Value" "R_100R_0402"
			(at -1.011843 -1.772047 90)
			(layer "B.Fab")
			(effects
				(font
					(size 0.7 0.7)
					(thickness 0.15)
				)
				(justify right bottom mirror)
			)
		)
		(property "Author" "Antmicro"
			(at 208.07 -26.19 0)
			(layer "B.Fab")
			(hide yes)
			(effects
				(font
					(size 1 1)
					(thickness 0.15)
				)
				(justify mirror)
			)
		)
		(property "License" "Apache-2.0"
			(at 208.07 -26.19 0)
			(layer "B.Fab")
			(hide yes)
			(effects
				(font
					(size 1 1)
					(thickness 0.15)
				)
				(justify mirror)
			)
		)
		(property "MPN" "CR0402-FX-1000GLF"
			(at 208.07 -26.19 0)
			(layer "B.Fab")
			(hide yes)
			(effects
				(font
					(size 1 1)
					(thickness 0.15)
				)
				(justify mirror)
			)
		)
		(property "Manufacturer" "Bourns"
			(at 208.07 -26.19 0)
			(layer "B.Fab")
			(hide yes)
			(effects
				(font
					(size 1 1)
					(thickness 0.15)
				)
				(justify mirror)
			)
		)
		(property "Tolerance" "1%"
			(at 208.07 -26.19 0)
			(layer "B.Fab")
			(hide yes)
			(effects
				(font
					(size 1 1)
					(thickness 0.15)
				)
				(justify mirror)
			)
		)
		(property "Val" "100R"
			(at 208.07 -26.19 0)
			(layer "B.Fab")
			(hide yes)
			(effects
				(font
					(size 1 1)
					(thickness 0.15)
				)
				(justify mirror)
			)
		)
		(sheetname "Translators")
		(sheetfile "translators.kicad_sch")
		(attr smd)
		(fp_rect
			(start -0.93 0.47)
			(end 0.93 -0.47)
			(stroke
				(width 0.05)
				(type solid)
			)
			(fill no)
			(layer "B.CrtYd")
		)
		(fp_rect
			(start -0.5 0.25)
			(end 0.5 -0.25)
			(stroke
				(width 0.15)
				(type solid)
			)
			(fill no)
			(layer "B.Fab")
		)
		(pad "1" smd roundrect
			(at -0.485 0 90)
			(size 0.59 0.64)
			(layers "B.Cu" "B.Mask" "B.Paste")
			(roundrect_rratio 0.25)
			(net 171 "/SODIMM/LPDDR5_IN_A.WCK0_N")
			(pintype "passive")
		)
		(pad "2" smd roundrect
			(at 0.485 0 90)
			(size 0.59 0.64)
			(layers "B.Cu" "B.Mask" "B.Paste")
			(roundrect_rratio 0.25)
			(net 46 "/LPDDR5/LPDDR5_A.WCK0_N")
			(pintype "passive")
		)
	)
	(footprint "antmicro-footprints:C_0402_1005Metric"
		(layer "B.Cu")
		(at 127.1 79.15)
		(descr "Capacitor SMD 0402")
		(tags "capacitor SMD 0402")
		(property "Reference" "C53"
			(at -3.2 0.3 0)
			(unlocked yes)
			(layer "B.SilkS")
			(effects
				(font
					(size 0.7 0.7)
					(thickness 0.15)
				)
				(justify right bottom mirror)
			)
		)
		(property "Value" "C_4u7_0402"
			(at -1.022927 -2.155213 0)
			(layer "B.Fab")
			(effects
				(font
					(size 0.7 0.7)
					(thickness 0.15)
				)
				(justify right bottom mirror)
			)
		)
		(property "Author" "Antmicro"
			(at 0 0 0)
			(layer "B.Fab")
			(hide yes)
			(effects
				(font
					(size 1 1)
					(thickness 0.15)
				)
				(justify mirror)
			)
		)
		(property "Dielectric" ""
			(at 0 0 0)
			(layer "B.Fab")
			(hide yes)
			(effects
				(font
					(size 1 1)
					(thickness 0.15)
				)
				(justify mirror)
			)
		)
		(property "License" "Apache-2.0"
			(at 0 0 0)
			(layer "B.Fab")
			(hide yes)
			(effects
				(font
					(size 1 1)
					(thickness 0.15)
				)
				(justify mirror)
			)
		)
		(property "MPN" "GRM155R61A475MEAAD"
			(at 0 0 0)
			(layer "B.Fab")
			(hide yes)
			(effects
				(font
					(size 1 1)
					(thickness 0.15)
				)
				(justify mirror)
			)
		)
		(property "Manufacturer" "Murata"
			(at 0 0 0)
			(layer "B.Fab")
			(hide yes)
			(effects
				(font
					(size 1 1)
					(thickness 0.15)
				)
				(justify mirror)
			)
		)
		(property "Val" "4u7"
			(at 0 0 0)
			(layer "B.Fab")
			(hide yes)
			(effects
				(font
					(size 1 1)
					(thickness 0.15)
				)
				(justify mirror)
			)
		)
		(property "Voltage" ""
			(at 0 0 0)
			(layer "B.Fab")
			(hide yes)
			(effects
				(font
					(size 1 1)
					(thickness 0.15)
				)
				(justify mirror)
			)
		)
		(sheetname "LPDDR5")
		(sheetfile "lpddr5.kicad_sch")
		(attr smd)
		(fp_rect
			(start -0.9659 0.481258)
			(end 0.9649 -0.458742)
			(stroke
				(width 0.05)
				(type solid)
			)
			(fill no)
			(layer "B.CrtYd")
		)
		(fp_line
			(start -0.499 -0.248)
			(end -0.499 0.25)
			(stroke
				(width 0.15)
				(type solid)
			)
			(layer "B.Fab")
		)
		(fp_line
			(start -0.499 0.25)
			(end 0.499 0.25)
			(stroke
				(width 0.15)
				(type solid)
			)
			(layer "B.Fab")
		)
		(fp_line
			(start 0.499 -0.248)
			(end -0.499 -0.248)
			(stroke
				(width 0.15)
				(type solid)
			)
			(layer "B.Fab")
		)
		(fp_line
			(start 0.499 0.25)
			(end 0.499 -0.248)
			(stroke
				(width 0.15)
				(type solid)
			)
			(layer "B.Fab")
		)
		(pad "1" smd roundrect
			(at -0.484 0)
			(size 0.59 0.64)
			(layers "B.Cu" "B.Mask" "B.Paste")
			(roundrect_rratio 0.25)
			(net 14 "GND")
			(pintype "passive")
		)
		(pad "2" smd roundrect
			(at 0.484 0)
			(size 0.59 0.64)
			(layers "B.Cu" "B.Mask" "B.Paste")
			(roundrect_rratio 0.25)
			(net 13 "+1V05")
			(pintype "passive")
		)
	)
	(footprint "antmicro-footprints:R_Array_4x0402_Panasonic_EXB28V"
		(layer "B.Cu")
		(at 119.35 93.8)
		(property "Reference" "R18"
			(at 0.95 1.7 0)
			(unlocked yes)
			(layer "B.SilkS")
			(effects
				(font
					(size 0.7 0.7)
					(thickness 0.15)
				)
				(justify left bottom mirror)
			)
		)
		(property "Value" "R_4x100R_0402_array"
			(at -1.5 -2 180)
			(layer "B.Fab")
			(effects
				(font
					(size 0.7 0.7)
					(thickness 0.15)
				)
				(justify left bottom mirror)
			)
		)
		(property "Author" "Antmicro"
			(at 0 0 0)
			(layer "B.Fab")
			(hide yes)
			(effects
				(font
					(size 1 1)
					(thickness 0.15)
				)
				(justify mirror)
			)
		)
		(property "License" "Apache-2.0"
			(at 0 0 0)
			(layer "B.Fab")
			(hide yes)
			(effects
				(font
					(size 1 1)
					(thickness 0.15)
				)
				(justify mirror)
			)
		)
		(property "MPN" "EXB-28V101JX"
			(at 0 0 0)
			(layer "B.Fab")
			(hide yes)
			(effects
				(font
					(size 1 1)
					(thickness 0.15)
				)
				(justify mirror)
			)
		)
		(property "Manufacturer" "Panasonic"
			(at 0 0 0)
			(layer "B.Fab")
			(hide yes)
			(effects
				(font
					(size 1 1)
					(thickness 0.15)
				)
				(justify mirror)
			)
		)
		(property "Val" "R_4x100R_0402"
			(at 0 0 0)
			(layer "B.Fab")
			(hide yes)
			(effects
				(font
					(size 1 1)
					(thickness 0.15)
				)
				(justify mirror)
			)
		)
		(sheetname "Translators")
		(sheetfile "translators.kicad_sch")
		(attr smd)
		(fp_line
			(start -1.25 0.5)
			(end -1.25 -0.498)
			(stroke
				(width 0.15)
				(type solid)
			)
			(layer "B.SilkS")
		)
		(fp_line
			(start 1.25 -0.499)
			(end 1.25 0.499)
			(stroke
				(width 0.15)
				(type solid)
			)
			(layer "B.SilkS")
		)
		(fp_rect
			(start -1.25 0.8)
			(end 1.25 -0.8)
			(stroke
				(width 0.05)
				(type solid)
			)
			(fill no)
			(layer "B.CrtYd")
		)
		(fp_line
			(start -1 -0.498)
			(end -1 0.5)
			(stroke
				(width 0.15)
				(type solid)
			)
			(layer "B.Fab")
		)
		(fp_line
			(start -1 0.5)
			(end 0.998 0.5)
			(stroke
				(width 0.15)
				(type solid)
			)
			(layer "B.Fab")
		)
		(fp_line
			(start 0.998 -0.498)
			(end -1 -0.498)
			(stroke
				(width 0.15)
				(type solid)
			)
			(layer "B.Fab")
		)
		(fp_line
			(start 0.998 0.5)
			(end 0.998 -0.498)
			(stroke
				(width 0.15)
				(type solid)
			)
			(layer "B.Fab")
		)
		(pad "1" smd roundrect
			(at -0.8875 -0.45)
			(size 0.525 0.5)
			(layers "B.Cu" "B.Mask" "B.Paste")
			(roundrect_rratio 0.25)
			(net 202 "/LPDDR5/LPDDR5_A.DQ3")
			(pinfunction "R1.1")
			(pintype "passive")
		)
		(pad "2" smd roundrect
			(at -0.25 -0.45)
			(size 0.25 0.5)
			(layers "B.Cu" "B.Mask" "B.Paste")
			(roundrect_rratio 0.25)
			(net 204 "/LPDDR5/LPDDR5_A.DQ1")
			(pinfunction "R2.1")
			(pintype "passive")
		)
		(pad "3" smd roundrect
			(at 0.25 -0.45)
			(size 0.25 0.5)
			(layers "B.Cu" "B.Mask" "B.Paste")
			(roundrect_rratio 0.25)
			(net 203 "/LPDDR5/LPDDR5_A.DQ2")
			(pinfunction "R3.1")
			(pintype "passive")
		)
		(pad "4" smd roundrect
			(at 0.8875 -0.45)
			(size 0.525 0.5)
			(layers "B.Cu" "B.Mask" "B.Paste")
			(roundrect_rratio 0.25)
			(net 205 "/LPDDR5/LPDDR5_A.DQ0")
			(pinfunction "R4.1")
			(pintype "passive")
		)
		(pad "5" smd roundrect
			(at 0.8875 0.45)
			(size 0.525 0.5)
			(layers "B.Cu" "B.Mask" "B.Paste")
			(roundrect_rratio 0.25)
			(net 14 "GND")
			(pinfunction "R4.2")
			(pintype "passive")
		)
		(pad "6" smd roundrect
			(at 0.25 0.45)
			(size 0.25 0.5)
			(layers "B.Cu" "B.Mask" "B.Paste")
			(roundrect_rratio 0.25)
			(net 14 "GND")
			(pinfunction "R3.2")
			(pintype "passive")
		)
		(pad "7" smd roundrect
			(at -0.25 0.45)
			(size 0.25 0.5)
			(layers "B.Cu" "B.Mask" "B.Paste")
			(roundrect_rratio 0.25)
			(net 14 "GND")
			(pinfunction "R2.2")
			(pintype "passive")
		)
		(pad "8" smd roundrect
			(at -0.8875 0.45)
			(size 0.525 0.5)
			(layers "B.Cu" "B.Mask" "B.Paste")
			(roundrect_rratio 0.25)
			(net 14 "GND")
			(pinfunction "R1.2")
			(pintype "passive")
		)
	)
	(footprint "antmicro-footprints:C_0402_1005Metric"
		(layer "B.Cu")
		(at 107.25 85.3)
		(descr "Capacitor SMD 0402")
		(tags "capacitor SMD 0402")
		(property "Reference" "C7"
			(at -2.55 0.5 0)
			(unlocked yes)
			(layer "B.SilkS")
			(effects
				(font
					(size 0.7 0.7)
					(thickness 0.15)
				)
				(justify right bottom mirror)
			)
		)
		(property "Value" "C_4u7_0402"
			(at -1.022927 -2.155213 0)
			(layer "B.Fab")
			(effects
				(font
					(size 0.7 0.7)
					(thickness 0.15)
				)
				(justify right bottom mirror)
			)
		)
		(property "Author" "Antmicro"
			(at 0 0 0)
			(layer "B.Fab")
			(hide yes)
			(effects
				(font
					(size 1 1)
					(thickness 0.15)
				)
				(justify mirror)
			)
		)
		(property "Dielectric" ""
			(at 0 0 0)
			(layer "B.Fab")
			(hide yes)
			(effects
				(font
					(size 1 1)
					(thickness 0.15)
				)
				(justify mirror)
			)
		)
		(property "License" "Apache-2.0"
			(at 0 0 0)
			(layer "B.Fab")
			(hide yes)
			(effects
				(font
					(size 1 1)
					(thickness 0.15)
				)
				(justify mirror)
			)
		)
		(property "MPN" "GRM155R61A475MEAAD"
			(at 0 0 0)
			(layer "B.Fab")
			(hide yes)
			(effects
				(font
					(size 1 1)
					(thickness 0.15)
				)
				(justify mirror)
			)
		)
		(property "Manufacturer" "Murata"
			(at 0 0 0)
			(layer "B.Fab")
			(hide yes)
			(effects
				(font
					(size 1 1)
					(thickness 0.15)
				)
				(justify mirror)
			)
		)
		(property "Val" "4u7"
			(at 0 0 0)
			(layer "B.Fab")
			(hide yes)
			(effects
				(font
					(size 1 1)
					(thickness 0.15)
				)
				(justify mirror)
			)
		)
		(property "Voltage" ""
			(at 0 0 0)
			(layer "B.Fab")
			(hide yes)
			(effects
				(font
					(size 1 1)
					(thickness 0.15)
				)
				(justify mirror)
			)
		)
		(sheetname "SODIMM")
		(sheetfile "sodim.kicad_sch")
		(attr smd)
		(fp_rect
			(start -0.9659 0.481258)
			(end 0.9649 -0.458742)
			(stroke
				(width 0.05)
				(type solid)
			)
			(fill no)
			(layer "B.CrtYd")
		)
		(fp_line
			(start -0.499 -0.248)
			(end -0.499 0.25)
			(stroke
				(width 0.15)
				(type solid)
			)
			(layer "B.Fab")
		)
		(fp_line
			(start -0.499 0.25)
			(end 0.499 0.25)
			(stroke
				(width 0.15)
				(type solid)
			)
			(layer "B.Fab")
		)
		(fp_line
			(start 0.499 -0.248)
			(end -0.499 -0.248)
			(stroke
				(width 0.15)
				(type solid)
			)
			(layer "B.Fab")
		)
		(fp_line
			(start 0.499 0.25)
			(end 0.499 -0.248)
			(stroke
				(width 0.15)
				(type solid)
			)
			(layer "B.Fab")
		)
		(pad "1" smd roundrect
			(at -0.484 0)
			(size 0.59 0.64)
			(layers "B.Cu" "B.Mask" "B.Paste")
			(roundrect_rratio 0.25)
			(net 14 "GND")
			(pintype "passive")
		)
		(pad "2" smd roundrect
			(at 0.484 0)
			(size 0.59 0.64)
			(layers "B.Cu" "B.Mask" "B.Paste")
			(roundrect_rratio 0.25)
			(net 35 "+1V8")
			(pintype "passive")
		)
	)
	(footprint "antmicro-footprints:C_0402_1005Metric"
		(layer "B.Cu")
		(at 134.775 82 90)
		(descr "Capacitor SMD 0402")
		(tags "capacitor SMD 0402")
		(property "Reference" "C70"
			(at -1.1 1.525 90)
			(unlocked yes)
			(layer "B.SilkS")
			(effects
				(font
					(size 0.7 0.7)
					(thickness 0.15)
				)
				(justify right bottom mirror)
			)
		)
		(property "Value" "C_4u7_0402"
			(at -1.022927 -2.155213 90)
			(layer "B.Fab")
			(effects
				(font
					(size 0.7 0.7)
					(thickness 0.15)
				)
				(justify right bottom mirror)
			)
		)
		(property "Author" "Antmicro"
			(at 216.775 -52.775 0)
			(layer "B.Fab")
			(hide yes)
			(effects
				(font
					(size 1 1)
					(thickness 0.15)
				)
				(justify mirror)
			)
		)
		(property "Dielectric" ""
			(at 216.775 -52.775 0)
			(layer "B.Fab")
			(hide yes)
			(effects
				(font
					(size 1 1)
					(thickness 0.15)
				)
				(justify mirror)
			)
		)
		(property "License" "Apache-2.0"
			(at 216.775 -52.775 0)
			(layer "B.Fab")
			(hide yes)
			(effects
				(font
					(size 1 1)
					(thickness 0.15)
				)
				(justify mirror)
			)
		)
		(property "MPN" "GRM155R61A475MEAAD"
			(at 216.775 -52.775 0)
			(layer "B.Fab")
			(hide yes)
			(effects
				(font
					(size 1 1)
					(thickness 0.15)
				)
				(justify mirror)
			)
		)
		(property "Manufacturer" "Murata"
			(at 216.775 -52.775 0)
			(layer "B.Fab")
			(hide yes)
			(effects
				(font
					(size 1 1)
					(thickness 0.15)
				)
				(justify mirror)
			)
		)
		(property "Val" "4u7"
			(at 216.775 -52.775 0)
			(layer "B.Fab")
			(hide yes)
			(effects
				(font
					(size 1 1)
					(thickness 0.15)
				)
				(justify mirror)
			)
		)
		(property "Voltage" ""
			(at 216.775 -52.775 0)
			(layer "B.Fab")
			(hide yes)
			(effects
				(font
					(size 1 1)
					(thickness 0.15)
				)
				(justify mirror)
			)
		)
		(sheetname "LPDDR5")
		(sheetfile "lpddr5.kicad_sch")
		(attr smd)
		(fp_rect
			(start -0.9659 0.481258)
			(end 0.9649 -0.458742)
			(stroke
				(width 0.05)
				(type solid)
			)
			(fill no)
			(layer "B.CrtYd")
		)
		(fp_line
			(start 0.499 -0.248)
			(end -0.499 -0.248)
			(stroke
				(width 0.15)
				(type solid)
			)
			(layer "B.Fab")
		)
		(fp_line
			(start -0.499 -0.248)
			(end -0.499 0.25)
			(stroke
				(width 0.15)
				(type solid)
			)
			(layer "B.Fab")
		)
		(fp_line
			(start 0.499 0.25)
			(end 0.499 -0.248)
			(stroke
				(width 0.15)
				(type solid)
			)
			(layer "B.Fab")
		)
		(fp_line
			(start -0.499 0.25)
			(end 0.499 0.25)
			(stroke
				(width 0.15)
				(type solid)
			)
			(layer "B.Fab")
		)
		(pad "1" smd roundrect
			(at -0.484 0 90)
			(size 0.59 0.64)
			(layers "B.Cu" "B.Mask" "B.Paste")
			(roundrect_rratio 0.25)
			(net 14 "GND")
			(pintype "passive")
		)
		(pad "2" smd roundrect
			(at 0.484 0 90)
			(size 0.59 0.64)
			(layers "B.Cu" "B.Mask" "B.Paste")
			(roundrect_rratio 0.25)
			(net 13 "+1V05")
			(pintype "passive")
		)
	)
	(footprint "antmicro-footprints:C_0402_1005Metric"
		(layer "B.Cu")
		(at 138.275 77.45)
		(descr "Capacitor SMD 0402")
		(tags "capacitor SMD 0402")
		(property "Reference" "C36"
			(at 1.525 1.35 0)
			(unlocked yes)
			(layer "B.SilkS")
			(effects
				(font
					(size 0.7 0.7)
					(thickness 0.15)
				)
				(justify right bottom mirror)
			)
		)
		(property "Value" "C_4u7_0402"
			(at -1.022927 -2.155213 0)
			(layer "B.Fab")
			(effects
				(font
					(size 0.7 0.7)
					(thickness 0.15)
				)
				(justify right bottom mirror)
			)
		)
		(property "Author" "Antmicro"
			(at 0 0 0)
			(layer "B.Fab")
			(hide yes)
			(effects
				(font
					(size 1 1)
					(thickness 0.15)
				)
				(justify mirror)
			)
		)
		(property "Dielectric" ""
			(at 0 0 0)
			(layer "B.Fab")
			(hide yes)
			(effects
				(font
					(size 1 1)
					(thickness 0.15)
				)
				(justify mirror)
			)
		)
		(property "License" "Apache-2.0"
			(at 0 0 0)
			(layer "B.Fab")
			(hide yes)
			(effects
				(font
					(size 1 1)
					(thickness 0.15)
				)
				(justify mirror)
			)
		)
		(property "MPN" "GRM155R61A475MEAAD"
			(at 0 0 0)
			(layer "B.Fab")
			(hide yes)
			(effects
				(font
					(size 1 1)
					(thickness 0.15)
				)
				(justify mirror)
			)
		)
		(property "Manufacturer" "Murata"
			(at 0 0 0)
			(layer "B.Fab")
			(hide yes)
			(effects
				(font
					(size 1 1)
					(thickness 0.15)
				)
				(justify mirror)
			)
		)
		(property "Val" "4u7"
			(at 0 0 0)
			(layer "B.Fab")
			(hide yes)
			(effects
				(font
					(size 1 1)
					(thickness 0.15)
				)
				(justify mirror)
			)
		)
		(property "Voltage" ""
			(at 0 0 0)
			(layer "B.Fab")
			(hide yes)
			(effects
				(font
					(size 1 1)
					(thickness 0.15)
				)
				(justify mirror)
			)
		)
		(sheetname "LPDDR5")
		(sheetfile "lpddr5.kicad_sch")
		(attr smd)
		(fp_rect
			(start -0.9659 0.481258)
			(end 0.9649 -0.458742)
			(stroke
				(width 0.05)
				(type solid)
			)
			(fill no)
			(layer "B.CrtYd")
		)
		(fp_line
			(start -0.499 -0.248)
			(end -0.499 0.25)
			(stroke
				(width 0.15)
				(type solid)
			)
			(layer "B.Fab")
		)
		(fp_line
			(start -0.499 0.25)
			(end 0.499 0.25)
			(stroke
				(width 0.15)
				(type solid)
			)
			(layer "B.Fab")
		)
		(fp_line
			(start 0.499 -0.248)
			(end -0.499 -0.248)
			(stroke
				(width 0.15)
				(type solid)
			)
			(layer "B.Fab")
		)
		(fp_line
			(start 0.499 0.25)
			(end 0.499 -0.248)
			(stroke
				(width 0.15)
				(type solid)
			)
			(layer "B.Fab")
		)
		(pad "1" smd roundrect
			(at -0.484 0)
			(size 0.59 0.64)
			(layers "B.Cu" "B.Mask" "B.Paste")
			(roundrect_rratio 0.25)
			(net 14 "GND")
			(pintype "passive")
		)
		(pad "2" smd roundrect
			(at 0.484 0)
			(size 0.59 0.64)
			(layers "B.Cu" "B.Mask" "B.Paste")
			(roundrect_rratio 0.25)
			(net 4 "+0V5")
			(pintype "passive")
		)
	)
	(footprint "antmicro-footprints:C_0402_1005Metric"
		(layer "B.Cu")
		(at 133.375 75.55 90)
		(descr "Capacitor SMD 0402")
		(tags "capacitor SMD 0402")
		(property "Reference" "C55"
			(at 1.25 0.699 90)
			(unlocked yes)
			(layer "B.SilkS")
			(effects
				(font
					(size 0.7 0.7)
					(thickness 0.15)
				)
				(justify right bottom mirror)
			)
		)
		(property "Value" "C_4u7_0402"
			(at -1.022927 -2.155213 90)
			(layer "B.Fab")
			(effects
				(font
					(size 0.7 0.7)
					(thickness 0.15)
				)
				(justify right bottom mirror)
			)
		)
		(property "Author" "Antmicro"
			(at 208.925 -57.825 0)
			(layer "B.Fab")
			(hide yes)
			(effects
				(font
					(size 1 1)
					(thickness 0.15)
				)
				(justify mirror)
			)
		)
		(property "Dielectric" ""
			(at 208.925 -57.825 0)
			(layer "B.Fab")
			(hide yes)
			(effects
				(font
					(size 1 1)
					(thickness 0.15)
				)
				(justify mirror)
			)
		)
		(property "License" "Apache-2.0"
			(at 208.925 -57.825 0)
			(layer "B.Fab")
			(hide yes)
			(effects
				(font
					(size 1 1)
					(thickness 0.15)
				)
				(justify mirror)
			)
		)
		(property "MPN" "GRM155R61A475MEAAD"
			(at 208.925 -57.825 0)
			(layer "B.Fab")
			(hide yes)
			(effects
				(font
					(size 1 1)
					(thickness 0.15)
				)
				(justify mirror)
			)
		)
		(property "Manufacturer" "Murata"
			(at 208.925 -57.825 0)
			(layer "B.Fab")
			(hide yes)
			(effects
				(font
					(size 1 1)
					(thickness 0.15)
				)
				(justify mirror)
			)
		)
		(property "Val" "4u7"
			(at 208.925 -57.825 0)
			(layer "B.Fab")
			(hide yes)
			(effects
				(font
					(size 1 1)
					(thickness 0.15)
				)
				(justify mirror)
			)
		)
		(property "Voltage" ""
			(at 208.925 -57.825 0)
			(layer "B.Fab")
			(hide yes)
			(effects
				(font
					(size 1 1)
					(thickness 0.15)
				)
				(justify mirror)
			)
		)
		(sheetname "LPDDR5")
		(sheetfile "lpddr5.kicad_sch")
		(attr smd)
		(fp_rect
			(start -0.9659 0.481258)
			(end 0.9649 -0.458742)
			(stroke
				(width 0.05)
				(type solid)
			)
			(fill no)
			(layer "B.CrtYd")
		)
		(fp_line
			(start 0.499 -0.248)
			(end -0.499 -0.248)
			(stroke
				(width 0.15)
				(type solid)
			)
			(layer "B.Fab")
		)
		(fp_line
			(start -0.499 -0.248)
			(end -0.499 0.25)
			(stroke
				(width 0.15)
				(type solid)
			)
			(layer "B.Fab")
		)
		(fp_line
			(start 0.499 0.25)
			(end 0.499 -0.248)
			(stroke
				(width 0.15)
				(type solid)
			)
			(layer "B.Fab")
		)
		(fp_line
			(start -0.499 0.25)
			(end 0.499 0.25)
			(stroke
				(width 0.15)
				(type solid)
			)
			(layer "B.Fab")
		)
		(pad "1" smd roundrect
			(at -0.484 0 90)
			(size 0.59 0.64)
			(layers "B.Cu" "B.Mask" "B.Paste")
			(roundrect_rratio 0.25)
			(net 14 "GND")
			(pintype "passive")
		)
		(pad "2" smd roundrect
			(at 0.484 0 90)
			(size 0.59 0.64)
			(layers "B.Cu" "B.Mask" "B.Paste")
			(roundrect_rratio 0.25)
			(net 12 "+0V9")
			(pintype "passive")
		)
	)
	(footprint "antmicro-footprints:R_Array_4x0402_Panasonic_EXB28V"
		(layer "B.Cu")
		(at 144.2 93.8 180)
		(property "Reference" "R60"
			(at -1.301 1.45 0)
			(unlocked yes)
			(layer "B.SilkS")
			(effects
				(font
					(size 0.7 0.7)
					(thickness 0.15)
				)
				(justify left bottom mirror)
			)
		)
		(property "Value" "R_4x100R_0402_array"
			(at -1.5 -2 0)
			(layer "B.Fab")
			(effects
				(font
					(size 0.7 0.7)
					(thickness 0.15)
				)
				(justify left bottom mirror)
			)
		)
		(property "Author" "Antmicro"
			(at 288.4 187.6 0)
			(layer "B.Fab")
			(hide yes)
			(effects
				(font
					(size 1 1)
					(thickness 0.15)
				)
				(justify mirror)
			)
		)
		(property "License" "Apache-2.0"
			(at 288.4 187.6 0)
			(layer "B.Fab")
			(hide yes)
			(effects
				(font
					(size 1 1)
					(thickness 0.15)
				)
				(justify mirror)
			)
		)
		(property "MPN" "EXB-28V101JX"
			(at 288.4 187.6 0)
			(layer "B.Fab")
			(hide yes)
			(effects
				(font
					(size 1 1)
					(thickness 0.15)
				)
				(justify mirror)
			)
		)
		(property "Manufacturer" "Panasonic"
			(at 288.4 187.6 0)
			(layer "B.Fab")
			(hide yes)
			(effects
				(font
					(size 1 1)
					(thickness 0.15)
				)
				(justify mirror)
			)
		)
		(property "Val" "R_4x100R_0402"
			(at 288.4 187.6 0)
			(layer "B.Fab")
			(hide yes)
			(effects
				(font
					(size 1 1)
					(thickness 0.15)
				)
				(justify mirror)
			)
		)
		(sheetname "Translators1")
		(sheetfile "translators.kicad_sch")
		(attr smd)
		(fp_line
			(start 1.25 -0.499)
			(end 1.25 0.499)
			(stroke
				(width 0.15)
				(type solid)
			)
			(layer "B.SilkS")
		)
		(fp_line
			(start -1.25 0.5)
			(end -1.25 -0.498)
			(stroke
				(width 0.15)
				(type solid)
			)
			(layer "B.SilkS")
		)
		(fp_rect
			(start -1.25 0.8)
			(end 1.25 -0.8)
			(stroke
				(width 0.05)
				(type solid)
			)
			(fill no)
			(layer "B.CrtYd")
		)
		(fp_line
			(start 0.998 0.5)
			(end 0.998 -0.498)
			(stroke
				(width 0.15)
				(type solid)
			)
			(layer "B.Fab")
		)
		(fp_line
			(start 0.998 -0.498)
			(end -1 -0.498)
			(stroke
				(width 0.15)
				(type solid)
			)
			(layer "B.Fab")
		)
		(fp_line
			(start -1 0.5)
			(end 0.998 0.5)
			(stroke
				(width 0.15)
				(type solid)
			)
			(layer "B.Fab")
		)
		(fp_line
			(start -1 -0.498)
			(end -1 0.5)
			(stroke
				(width 0.15)
				(type solid)
			)
			(layer "B.Fab")
		)
		(pad "1" smd roundrect
			(at -0.8875 -0.45 180)
			(size 0.525 0.5)
			(layers "B.Cu" "B.Mask" "B.Paste")
			(roundrect_rratio 0.25)
			(net 147 "/SODIMM/LPDDR5_IN_B.CS0")
			(pinfunction "R1.1")
			(pintype "passive")
		)
		(pad "2" smd roundrect
			(at -0.25 -0.45 180)
			(size 0.25 0.5)
			(layers "B.Cu" "B.Mask" "B.Paste")
			(roundrect_rratio 0.25)
			(net 144 "/SODIMM/LPDDR5_IN_B.CS1")
			(pinfunction "R2.1")
			(pintype "passive")
		)
		(pad "3" smd roundrect
			(at 0.25 -0.45 180)
			(size 0.25 0.5)
			(layers "B.Cu" "B.Mask" "B.Paste")
			(roundrect_rratio 0.25)
			(net 145 "/SODIMM/LPDDR5_IN_B.CA0")
			(pinfunction "R3.1")
			(pintype "passive")
		)
		(pad "4" smd roundrect
			(at 0.8875 -0.45 180)
			(size 0.525 0.5)
			(layers "B.Cu" "B.Mask" "B.Paste")
			(roundrect_rratio 0.25)
			(net 146 "/SODIMM/LPDDR5_IN_B.CA1")
			(pinfunction "R4.1")
			(pintype "passive")
		)
		(pad "5" smd roundrect
			(at 0.8875 0.45 180)
			(size 0.525 0.5)
			(layers "B.Cu" "B.Mask" "B.Paste")
			(roundrect_rratio 0.25)
			(net 103 "/LPDDR5/LPDDR5_B.CA1")
			(pinfunction "R4.2")
			(pintype "passive")
		)
		(pad "6" smd roundrect
			(at 0.25 0.45 180)
			(size 0.25 0.5)
			(layers "B.Cu" "B.Mask" "B.Paste")
			(roundrect_rratio 0.25)
			(net 102 "/LPDDR5/LPDDR5_B.CA0")
			(pinfunction "R3.2")
			(pintype "passive")
		)
		(pad "7" smd roundrect
			(at -0.25 0.45 180)
			(size 0.25 0.5)
			(layers "B.Cu" "B.Mask" "B.Paste")
			(roundrect_rratio 0.25)
			(net 107 "/LPDDR5/LPDDR5_B.CS1")
			(pinfunction "R2.2")
			(pintype "passive")
		)
		(pad "8" smd roundrect
			(at -0.8875 0.45 180)
			(size 0.525 0.5)
			(layers "B.Cu" "B.Mask" "B.Paste")
			(roundrect_rratio 0.25)
			(net 106 "/LPDDR5/LPDDR5_B.CS0")
			(pinfunction "R1.2")
			(pintype "passive")
		)
	)
	(footprint "antmicro-footprints:C_0402_1005Metric"
		(layer "B.Cu")
		(at 138.775 78.45 180)
		(descr "Capacitor SMD 0402")
		(tags "capacitor SMD 0402")
		(property "Reference" "C66"
			(at 1.375 0.65 0)
			(unlocked yes)
			(layer "B.SilkS")
			(effects
				(font
					(size 0.7 0.7)
					(thickness 0.15)
				)
				(justify left bottom mirror)
			)
		)
		(property "Value" "C_4u7_0402"
			(at -1.022927 -2.155213 0)
			(layer "B.Fab")
			(effects
				(font
					(size 0.7 0.7)
					(thickness 0.15)
				)
				(justify left bottom mirror)
			)
		)
		(property "Author" "Antmicro"
			(at 277.55 156.9 0)
			(layer "B.Fab")
			(hide yes)
			(effects
				(font
					(size 1 1)
					(thickness 0.15)
				)
				(justify mirror)
			)
		)
		(property "Dielectric" ""
			(at 277.55 156.9 0)
			(layer "B.Fab")
			(hide yes)
			(effects
				(font
					(size 1 1)
					(thickness 0.15)
				)
				(justify mirror)
			)
		)
		(property "License" "Apache-2.0"
			(at 277.55 156.9 0)
			(layer "B.Fab")
			(hide yes)
			(effects
				(font
					(size 1 1)
					(thickness 0.15)
				)
				(justify mirror)
			)
		)
		(property "MPN" "GRM155R61A475MEAAD"
			(at 277.55 156.9 0)
			(layer "B.Fab")
			(hide yes)
			(effects
				(font
					(size 1 1)
					(thickness 0.15)
				)
				(justify mirror)
			)
		)
		(property "Manufacturer" "Murata"
			(at 277.55 156.9 0)
			(layer "B.Fab")
			(hide yes)
			(effects
				(font
					(size 1 1)
					(thickness 0.15)
				)
				(justify mirror)
			)
		)
		(property "Val" "4u7"
			(at 277.55 156.9 0)
			(layer "B.Fab")
			(hide yes)
			(effects
				(font
					(size 1 1)
					(thickness 0.15)
				)
				(justify mirror)
			)
		)
		(property "Voltage" ""
			(at 277.55 156.9 0)
			(layer "B.Fab")
			(hide yes)
			(effects
				(font
					(size 1 1)
					(thickness 0.15)
				)
				(justify mirror)
			)
		)
		(sheetname "LPDDR5")
		(sheetfile "lpddr5.kicad_sch")
		(attr smd)
		(fp_rect
			(start -0.9659 0.481258)
			(end 0.9649 -0.458742)
			(stroke
				(width 0.05)
				(type solid)
			)
			(fill no)
			(layer "B.CrtYd")
		)
		(fp_line
			(start 0.499 0.25)
			(end 0.499 -0.248)
			(stroke
				(width 0.15)
				(type solid)
			)
			(layer "B.Fab")
		)
		(fp_line
			(start 0.499 -0.248)
			(end -0.499 -0.248)
			(stroke
				(width 0.15)
				(type solid)
			)
			(layer "B.Fab")
		)
		(fp_line
			(start -0.499 0.25)
			(end 0.499 0.25)
			(stroke
				(width 0.15)
				(type solid)
			)
			(layer "B.Fab")
		)
		(fp_line
			(start -0.499 -0.248)
			(end -0.499 0.25)
			(stroke
				(width 0.15)
				(type solid)
			)
			(layer "B.Fab")
		)
		(pad "1" smd roundrect
			(at -0.484 0 180)
			(size 0.59 0.64)
			(layers "B.Cu" "B.Mask" "B.Paste")
			(roundrect_rratio 0.25)
			(net 14 "GND")
			(pintype "passive")
		)
		(pad "2" smd roundrect
			(at 0.484 0 180)
			(size 0.59 0.64)
			(layers "B.Cu" "B.Mask" "B.Paste")
			(roundrect_rratio 0.25)
			(net 13 "+1V05")
			(pintype "passive")
		)
	)
	(footprint "antmicro-footprints:R_0402_1005Metric"
		(layer "B.Cu")
		(at 108.08 89.57)
		(descr "Resistor SMD 0402")
		(tags "resistor SMD 0402")
		(property "Reference" "R53"
			(at -0.88 -0.67 0)
			(unlocked yes)
			(layer "B.SilkS")
			(effects
				(font
					(size 0.7 0.7)
					(thickness 0.15)
				)
				(justify right bottom mirror)
			)
		)
		(property "Value" "R_100R_0402"
			(at -1.011843 -1.772047 0)
			(layer "B.Fab")
			(effects
				(font
					(size 0.7 0.7)
					(thickness 0.15)
				)
				(justify right bottom mirror)
			)
		)
		(property "Author" "Antmicro"
			(at 0 0 0)
			(layer "B.Fab")
			(hide yes)
			(effects
				(font
					(size 1 1)
					(thickness 0.15)
				)
				(justify mirror)
			)
		)
		(property "License" "Apache-2.0"
			(at 0 0 0)
			(layer "B.Fab")
			(hide yes)
			(effects
				(font
					(size 1 1)
					(thickness 0.15)
				)
				(justify mirror)
			)
		)
		(property "MPN" "CR0402-FX-1000GLF"
			(at 0 0 0)
			(layer "B.Fab")
			(hide yes)
			(effects
				(font
					(size 1 1)
					(thickness 0.15)
				)
				(justify mirror)
			)
		)
		(property "Manufacturer" "Bourns"
			(at 0 0 0)
			(layer "B.Fab")
			(hide yes)
			(effects
				(font
					(size 1 1)
					(thickness 0.15)
				)
				(justify mirror)
			)
		)
		(property "Tolerance" "1%"
			(at 0 0 0)
			(layer "B.Fab")
			(hide yes)
			(effects
				(font
					(size 1 1)
					(thickness 0.15)
				)
				(justify mirror)
			)
		)
		(property "Val" "100R"
			(at 0 0 0)
			(layer "B.Fab")
			(hide yes)
			(effects
				(font
					(size 1 1)
					(thickness 0.15)
				)
				(justify mirror)
			)
		)
		(sheetname "Translators")
		(sheetfile "translators.kicad_sch")
		(attr smd)
		(fp_rect
			(start -0.93 0.47)
			(end 0.93 -0.47)
			(stroke
				(width 0.05)
				(type solid)
			)
			(fill no)
			(layer "B.CrtYd")
		)
		(fp_rect
			(start -0.5 0.25)
			(end 0.5 -0.25)
			(stroke
				(width 0.15)
				(type solid)
			)
			(fill no)
			(layer "B.Fab")
		)
		(pad "1" smd roundrect
			(at -0.485 0)
			(size 0.59 0.64)
			(layers "B.Cu" "B.Mask" "B.Paste")
			(roundrect_rratio 0.25)
			(net 48 "/LPDDR5/LPDDR5_A.WCK1_P")
			(pintype "passive")
		)
		(pad "2" smd roundrect
			(at 0.485 0)
			(size 0.59 0.64)
			(layers "B.Cu" "B.Mask" "B.Paste")
			(roundrect_rratio 0.25)
			(net 14 "GND")
			(pintype "passive")
		)
	)
	(footprint "antmicro-footprints:R_0402_1005Metric"
		(layer "B.Cu")
		(at 165.4 89.465)
		(descr "Resistor SMD 0402")
		(tags "resistor SMD 0402")
		(property "Reference" "R80"
			(at -1 -0.765 0)
			(unlocked yes)
			(layer "B.SilkS")
			(effects
				(font
					(size 0.7 0.7)
					(thickness 0.15)
				)
				(justify right bottom mirror)
			)
		)
		(property "Value" "R_100R_0402"
			(at -1.011843 -1.772047 0)
			(layer "B.Fab")
			(effects
				(font
					(size 0.7 0.7)
					(thickness 0.15)
				)
				(justify right bottom mirror)
			)
		)
		(property "Author" "Antmicro"
			(at 0 0 0)
			(layer "B.Fab")
			(hide yes)
			(effects
				(font
					(size 1 1)
					(thickness 0.15)
				)
				(justify mirror)
			)
		)
		(property "License" "Apache-2.0"
			(at 0 0 0)
			(layer "B.Fab")
			(hide yes)
			(effects
				(font
					(size 1 1)
					(thickness 0.15)
				)
				(justify mirror)
			)
		)
		(property "MPN" "CR0402-FX-1000GLF"
			(at 0 0 0)
			(layer "B.Fab")
			(hide yes)
			(effects
				(font
					(size 1 1)
					(thickness 0.15)
				)
				(justify mirror)
			)
		)
		(property "Manufacturer" "Bourns"
			(at 0 0 0)
			(layer "B.Fab")
			(hide yes)
			(effects
				(font
					(size 1 1)
					(thickness 0.15)
				)
				(justify mirror)
			)
		)
		(property "Tolerance" "1%"
			(at 0 0 0)
			(layer "B.Fab")
			(hide yes)
			(effects
				(font
					(size 1 1)
					(thickness 0.15)
				)
				(justify mirror)
			)
		)
		(property "Val" "100R"
			(at 0 0 0)
			(layer "B.Fab")
			(hide yes)
			(effects
				(font
					(size 1 1)
					(thickness 0.15)
				)
				(justify mirror)
			)
		)
		(sheetname "Translators1")
		(sheetfile "translators.kicad_sch")
		(attr smd)
		(fp_rect
			(start -0.93 0.47)
			(end 0.93 -0.47)
			(stroke
				(width 0.05)
				(type solid)
			)
			(fill no)
			(layer "B.CrtYd")
		)
		(fp_rect
			(start -0.5 0.25)
			(end 0.5 -0.25)
			(stroke
				(width 0.15)
				(type solid)
			)
			(fill no)
			(layer "B.Fab")
		)
		(pad "1" smd roundrect
			(at -0.485 0)
			(size 0.59 0.64)
			(layers "B.Cu" "B.Mask" "B.Paste")
			(roundrect_rratio 0.25)
			(net 108 "/LPDDR5/LPDDR5_B.WCK0_P")
			(pintype "passive")
		)
		(pad "2" smd roundrect
			(at 0.485 0)
			(size 0.59 0.64)
			(layers "B.Cu" "B.Mask" "B.Paste")
			(roundrect_rratio 0.25)
			(net 14 "GND")
			(pintype "passive")
		)
	)
	(footprint "antmicro-footprints:C_0402_1005Metric"
		(layer "B.Cu")
		(at 130.775 78.45)
		(descr "Capacitor SMD 0402")
		(tags "capacitor SMD 0402")
		(property "Reference" "C54"
			(at -1.275 1.25 0)
			(unlocked yes)
			(layer "B.SilkS")
			(effects
				(font
					(size 0.7 0.7)
					(thickness 0.15)
				)
				(justify right bottom mirror)
			)
		)
		(property "Value" "C_4u7_0402"
			(at -1.022927 -2.155213 0)
			(layer "B.Fab")
			(effects
				(font
					(size 0.7 0.7)
					(thickness 0.15)
				)
				(justify right bottom mirror)
			)
		)
		(property "Author" "Antmicro"
			(at 0 0 0)
			(layer "B.Fab")
			(hide yes)
			(effects
				(font
					(size 1 1)
					(thickness 0.15)
				)
				(justify mirror)
			)
		)
		(property "Dielectric" ""
			(at 0 0 0)
			(layer "B.Fab")
			(hide yes)
			(effects
				(font
					(size 1 1)
					(thickness 0.15)
				)
				(justify mirror)
			)
		)
		(property "License" "Apache-2.0"
			(at 0 0 0)
			(layer "B.Fab")
			(hide yes)
			(effects
				(font
					(size 1 1)
					(thickness 0.15)
				)
				(justify mirror)
			)
		)
		(property "MPN" "GRM155R61A475MEAAD"
			(at 0 0 0)
			(layer "B.Fab")
			(hide yes)
			(effects
				(font
					(size 1 1)
					(thickness 0.15)
				)
				(justify mirror)
			)
		)
		(property "Manufacturer" "Murata"
			(at 0 0 0)
			(layer "B.Fab")
			(hide yes)
			(effects
				(font
					(size 1 1)
					(thickness 0.15)
				)
				(justify mirror)
			)
		)
		(property "Val" "4u7"
			(at 0 0 0)
			(layer "B.Fab")
			(hide yes)
			(effects
				(font
					(size 1 1)
					(thickness 0.15)
				)
				(justify mirror)
			)
		)
		(property "Voltage" ""
			(at 0 0 0)
			(layer "B.Fab")
			(hide yes)
			(effects
				(font
					(size 1 1)
					(thickness 0.15)
				)
				(justify mirror)
			)
		)
		(sheetname "LPDDR5")
		(sheetfile "lpddr5.kicad_sch")
		(attr smd)
		(fp_rect
			(start -0.9659 0.481258)
			(end 0.9649 -0.458742)
			(stroke
				(width 0.05)
				(type solid)
			)
			(fill no)
			(layer "B.CrtYd")
		)
		(fp_line
			(start -0.499 -0.248)
			(end -0.499 0.25)
			(stroke
				(width 0.15)
				(type solid)
			)
			(layer "B.Fab")
		)
		(fp_line
			(start -0.499 0.25)
			(end 0.499 0.25)
			(stroke
				(width 0.15)
				(type solid)
			)
			(layer "B.Fab")
		)
		(fp_line
			(start 0.499 -0.248)
			(end -0.499 -0.248)
			(stroke
				(width 0.15)
				(type solid)
			)
			(layer "B.Fab")
		)
		(fp_line
			(start 0.499 0.25)
			(end 0.499 -0.248)
			(stroke
				(width 0.15)
				(type solid)
			)
			(layer "B.Fab")
		)
		(pad "1" smd roundrect
			(at -0.484 0)
			(size 0.59 0.64)
			(layers "B.Cu" "B.Mask" "B.Paste")
			(roundrect_rratio 0.25)
			(net 14 "GND")
			(pintype "passive")
		)
		(pad "2" smd roundrect
			(at 0.484 0)
			(size 0.59 0.64)
			(layers "B.Cu" "B.Mask" "B.Paste")
			(roundrect_rratio 0.25)
			(net 13 "+1V05")
			(pintype "passive")
		)
	)
	(footprint "antmicro-footprints:R_0402_1005Metric"
		(layer "B.Cu")
		(at 116.68 89.5 180)
		(descr "Resistor SMD 0402")
		(tags "resistor SMD 0402")
		(property "Reference" "R25"
			(at -0.92 0.6 0)
			(unlocked yes)
			(layer "B.SilkS")
			(effects
				(font
					(size 0.7 0.7)
					(thickness 0.15)
				)
				(justify left bottom mirror)
			)
		)
		(property "Value" "R_100R_0402"
			(at -1.011843 -1.772047 0)
			(layer "B.Fab")
			(effects
				(font
					(size 0.7 0.7)
					(thickness 0.15)
				)
				(justify left bottom mirror)
			)
		)
		(property "Author" "Antmicro"
			(at 233.36 179 0)
			(layer "B.Fab")
			(hide yes)
			(effects
				(font
					(size 1 1)
					(thickness 0.15)
				)
				(justify mirror)
			)
		)
		(property "License" "Apache-2.0"
			(at 233.36 179 0)
			(layer "B.Fab")
			(hide yes)
			(effects
				(font
					(size 1 1)
					(thickness 0.15)
				)
				(justify mirror)
			)
		)
		(property "MPN" "CR0402-FX-1000GLF"
			(at 233.36 179 0)
			(layer "B.Fab")
			(hide yes)
			(effects
				(font
					(size 1 1)
					(thickness 0.15)
				)
				(justify mirror)
			)
		)
		(property "Manufacturer" "Bourns"
			(at 233.36 179 0)
			(layer "B.Fab")
			(hide yes)
			(effects
				(font
					(size 1 1)
					(thickness 0.15)
				)
				(justify mirror)
			)
		)
		(property "Tolerance" "1%"
			(at 233.36 179 0)
			(layer "B.Fab")
			(hide yes)
			(effects
				(font
					(size 1 1)
					(thickness 0.15)
				)
				(justify mirror)
			)
		)
		(property "Val" "100R"
			(at 233.36 179 0)
			(layer "B.Fab")
			(hide yes)
			(effects
				(font
					(size 1 1)
					(thickness 0.15)
				)
				(justify mirror)
			)
		)
		(sheetname "Translators")
		(sheetfile "translators.kicad_sch")
		(attr smd)
		(fp_rect
			(start -0.93 0.47)
			(end 0.93 -0.47)
			(stroke
				(width 0.05)
				(type solid)
			)
			(fill no)
			(layer "B.CrtYd")
		)
		(fp_rect
			(start -0.5 0.25)
			(end 0.5 -0.25)
			(stroke
				(width 0.15)
				(type solid)
			)
			(fill no)
			(layer "B.Fab")
		)
		(pad "1" smd roundrect
			(at -0.485 0 180)
			(size 0.59 0.64)
			(layers "B.Cu" "B.Mask" "B.Paste")
			(roundrect_rratio 0.25)
			(net 46 "/LPDDR5/LPDDR5_A.WCK0_N")
			(pintype "passive")
		)
		(pad "2" smd roundrect
			(at 0.485 0 180)
			(size 0.59 0.64)
			(layers "B.Cu" "B.Mask" "B.Paste")
			(roundrect_rratio 0.25)
			(net 14 "GND")
			(pintype "passive")
		)
	)
	(footprint "antmicro-footprints:R_Array_4x0402_Panasonic_EXB28V"
		(layer "B.Cu")
		(at 152.2 93.8)
		(property "Reference" "R77"
			(at -1.1 1.8 0)
			(unlocked yes)
			(layer "B.SilkS")
			(effects
				(font
					(size 0.7 0.7)
					(thickness 0.15)
				)
				(justify right bottom mirror)
			)
		)
		(property "Value" "R_4x100R_0402_array"
			(at -1.5 -2 0)
			(layer "B.Fab")
			(effects
				(font
					(size 0.7 0.7)
					(thickness 0.15)
				)
				(justify right bottom mirror)
			)
		)
		(property "Author" "Antmicro"
			(at 0 0 0)
			(layer "B.Fab")
			(hide yes)
			(effects
				(font
					(size 1 1)
					(thickness 0.15)
				)
				(justify mirror)
			)
		)
		(property "License" "Apache-2.0"
			(at 0 0 0)
			(layer "B.Fab")
			(hide yes)
			(effects
				(font
					(size 1 1)
					(thickness 0.15)
				)
				(justify mirror)
			)
		)
		(property "MPN" "EXB-28V101JX"
			(at 0 0 0)
			(layer "B.Fab")
			(hide yes)
			(effects
				(font
					(size 1 1)
					(thickness 0.15)
				)
				(justify mirror)
			)
		)
		(property "Manufacturer" "Panasonic"
			(at 0 0 0)
			(layer "B.Fab")
			(hide yes)
			(effects
				(font
					(size 1 1)
					(thickness 0.15)
				)
				(justify mirror)
			)
		)
		(property "Val" "R_4x100R_0402"
			(at 0 0 0)
			(layer "B.Fab")
			(hide yes)
			(effects
				(font
					(size 1 1)
					(thickness 0.15)
				)
				(justify mirror)
			)
		)
		(sheetname "Translators1")
		(sheetfile "translators.kicad_sch")
		(attr smd)
		(fp_line
			(start -1.25 0.5)
			(end -1.25 -0.498)
			(stroke
				(width 0.15)
				(type solid)
			)
			(layer "B.SilkS")
		)
		(fp_line
			(start 1.25 -0.499)
			(end 1.25 0.499)
			(stroke
				(width 0.15)
				(type solid)
			)
			(layer "B.SilkS")
		)
		(fp_rect
			(start -1.25 0.8)
			(end 1.25 -0.8)
			(stroke
				(width 0.05)
				(type solid)
			)
			(fill no)
			(layer "B.CrtYd")
		)
		(fp_line
			(start -1 -0.498)
			(end -1 0.5)
			(stroke
				(width 0.15)
				(type solid)
			)
			(layer "B.Fab")
		)
		(fp_line
			(start -1 0.5)
			(end 0.998 0.5)
			(stroke
				(width 0.15)
				(type solid)
			)
			(layer "B.Fab")
		)
		(fp_line
			(start 0.998 -0.498)
			(end -1 -0.498)
			(stroke
				(width 0.15)
				(type solid)
			)
			(layer "B.Fab")
		)
		(fp_line
			(start 0.998 0.5)
			(end 0.998 -0.498)
			(stroke
				(width 0.15)
				(type solid)
			)
			(layer "B.Fab")
		)
		(pad "1" smd roundrect
			(at -0.8875 -0.45)
			(size 0.525 0.5)
			(layers "B.Cu" "B.Mask" "B.Paste")
			(roundrect_rratio 0.25)
			(net 206 "/LPDDR5/LPDDR5_B.DQ8")
			(pinfunction "R1.1")
			(pintype "passive")
		)
		(pad "2" smd roundrect
			(at -0.25 -0.45)
			(size 0.25 0.5)
			(layers "B.Cu" "B.Mask" "B.Paste")
			(roundrect_rratio 0.25)
			(net 208 "/LPDDR5/LPDDR5_B.DQ10")
			(pinfunction "R2.1")
			(pintype "passive")
		)
		(pad "3" smd roundrect
			(at 0.25 -0.45)
			(size 0.25 0.5)
			(layers "B.Cu" "B.Mask" "B.Paste")
			(roundrect_rratio 0.25)
			(net 207 "/LPDDR5/LPDDR5_B.DQ9")
			(pinfunction "R3.1")
			(pintype "passive")
		)
		(pad "4" smd roundrect
			(at 0.8875 -0.45)
			(size 0.525 0.5)
			(layers "B.Cu" "B.Mask" "B.Paste")
			(roundrect_rratio 0.25)
			(net 209 "/LPDDR5/LPDDR5_B.DQ11")
			(pinfunction "R4.1")
			(pintype "passive")
		)
		(pad "5" smd roundrect
			(at 0.8875 0.45)
			(size 0.525 0.5)
			(layers "B.Cu" "B.Mask" "B.Paste")
			(roundrect_rratio 0.25)
			(net 14 "GND")
			(pinfunction "R4.2")
			(pintype "passive")
		)
		(pad "6" smd roundrect
			(at 0.25 0.45)
			(size 0.25 0.5)
			(layers "B.Cu" "B.Mask" "B.Paste")
			(roundrect_rratio 0.25)
			(net 14 "GND")
			(pinfunction "R3.2")
			(pintype "passive")
		)
		(pad "7" smd roundrect
			(at -0.25 0.45)
			(size 0.25 0.5)
			(layers "B.Cu" "B.Mask" "B.Paste")
			(roundrect_rratio 0.25)
			(net 14 "GND")
			(pinfunction "R2.2")
			(pintype "passive")
		)
		(pad "8" smd roundrect
			(at -0.8875 0.45)
			(size 0.525 0.5)
			(layers "B.Cu" "B.Mask" "B.Paste")
			(roundrect_rratio 0.25)
			(net 14 "GND")
			(pinfunction "R1.2")
			(pintype "passive")
		)
	)
	(footprint "antmicro-footprints:R_0402_1005Metric"
		(layer "B.Cu")
		(at 135.15 91.35 -90)
		(descr "Resistor SMD 0402")
		(tags "resistor SMD 0402")
		(property "Reference" "R55"
			(at -1.122484 0.772697 90)
			(unlocked yes)
			(layer "B.SilkS")
			(effects
				(font
					(size 0.7 0.7)
					(thickness 0.15)
				)
				(justify left bottom mirror)
			)
		)
		(property "Value" "R_100R_0402"
			(at -1.011843 -1.772047 90)
			(layer "B.Fab")
			(effects
				(font
					(size 0.7 0.7)
					(thickness 0.15)
				)
				(justify left bottom mirror)
			)
		)
		(property "Author" "Antmicro"
			(at 43.8 226.5 0)
			(layer "B.Fab")
			(hide yes)
			(effects
				(font
					(size 1 1)
					(thickness 0.15)
				)
				(justify mirror)
			)
		)
		(property "License" "Apache-2.0"
			(at 43.8 226.5 0)
			(layer "B.Fab")
			(hide yes)
			(effects
				(font
					(size 1 1)
					(thickness 0.15)
				)
				(justify mirror)
			)
		)
		(property "MPN" "CR0402-FX-1000GLF"
			(at 43.8 226.5 0)
			(layer "B.Fab")
			(hide yes)
			(effects
				(font
					(size 1 1)
					(thickness 0.15)
				)
				(justify mirror)
			)
		)
		(property "Manufacturer" "Bourns"
			(at 43.8 226.5 0)
			(layer "B.Fab")
			(hide yes)
			(effects
				(font
					(size 1 1)
					(thickness 0.15)
				)
				(justify mirror)
			)
		)
		(property "Tolerance" "1%"
			(at 43.8 226.5 0)
			(layer "B.Fab")
			(hide yes)
			(effects
				(font
					(size 1 1)
					(thickness 0.15)
				)
				(justify mirror)
			)
		)
		(property "Val" "100R"
			(at 43.8 226.5 0)
			(layer "B.Fab")
			(hide yes)
			(effects
				(font
					(size 1 1)
					(thickness 0.15)
				)
				(justify mirror)
			)
		)
		(sheetname "Translators")
		(sheetfile "translators.kicad_sch")
		(attr smd)
		(fp_rect
			(start -0.93 0.47)
			(end 0.93 -0.47)
			(stroke
				(width 0.05)
				(type solid)
			)
			(fill no)
			(layer "B.CrtYd")
		)
		(fp_rect
			(start -0.5 0.25)
			(end 0.5 -0.25)
			(stroke
				(width 0.15)
				(type solid)
			)
			(fill no)
			(layer "B.Fab")
		)
		(pad "1" smd roundrect
			(at -0.485 0 270)
			(size 0.59 0.64)
			(layers "B.Cu" "B.Mask" "B.Paste")
			(roundrect_rratio 0.25)
			(net 49 "/LPDDR5/LPDDR5_A.CK_P")
			(pintype "passive")
		)
		(pad "2" smd roundrect
			(at 0.485 0 270)
			(size 0.59 0.64)
			(layers "B.Cu" "B.Mask" "B.Paste")
			(roundrect_rratio 0.25)
			(net 14 "GND")
			(pintype "passive")
		)
	)
	(footprint "antmicro-footprints:Conn_JST_SH_1x4_SM04B-SRSS-TB-LF-SN"
		(layer "B.Cu")
		(at 118.975 62.95)
		(property "Reference" "J3"
			(at -3.475 3.25 0)
			(unlocked yes)
			(layer "B.SilkS")
			(effects
				(font
					(size 0.7 0.7)
					(thickness 0.15)
				)
				(justify right bottom mirror)
			)
		)
		(property "Value" "JST_SH_1x4_SM04B-SRSS-TB-LF-SN"
			(at 0 -3.9 0)
			(layer "B.Fab")
			(effects
				(font
					(size 0.7 0.7)
					(thickness 0.15)
				)
				(justify right bottom mirror)
			)
		)
		(property "Author" "Antmicro"
			(at 0 0 0)
			(layer "B.Fab")
			(hide yes)
			(effects
				(font
					(size 1 1)
					(thickness 0.15)
				)
				(justify mirror)
			)
		)
		(property "License" "Apache-2.0"
			(at 0 0 0)
			(layer "B.Fab")
			(hide yes)
			(effects
				(font
					(size 1 1)
					(thickness 0.15)
				)
				(justify mirror)
			)
		)
		(property "MPN" "SM04B-SRSS-TB(LF)(SN)"
			(at 0 0 0)
			(layer "B.Fab")
			(hide yes)
			(effects
				(font
					(size 1 1)
					(thickness 0.15)
				)
				(justify mirror)
			)
		)
		(property "Manufacturer" "JST Automotive Connectors"
			(at 0 0 0)
			(layer "B.Fab")
			(hide yes)
			(effects
				(font
					(size 1 1)
					(thickness 0.15)
				)
				(justify mirror)
			)
		)
		(sheetname "Power supply")
		(sheetfile "power_supply.kicad_sch")
		(attr smd)
		(fp_line
			(start -3.2 1.9)
			(end -3.2 -0.2)
			(stroke
				(width 0.15)
				(type solid)
			)
			(layer "B.SilkS")
		)
		(fp_line
			(start -2.1 1.9)
			(end -3.2 1.9)
			(stroke
				(width 0.15)
				(type solid)
			)
			(layer "B.SilkS")
		)
		(fp_line
			(start -2 -2.101)
			(end 1.999 -2.101)
			(stroke
				(width 0.15)
				(type solid)
			)
			(layer "B.SilkS")
		)
		(fp_line
			(start 2 1.9)
			(end 3.2 1.9)
			(stroke
				(width 0.15)
				(type solid)
			)
			(layer "B.SilkS")
		)
		(fp_line
			(start 3.2 1.9)
			(end 3.2 -0.2)
			(stroke
				(width 0.15)
				(type solid)
			)
			(layer "B.SilkS")
		)
		(fp_circle
			(center -2 2.2)
			(end -1.95 2.15)
			(stroke
				(width 0.15)
				(type solid)
			)
			(fill yes)
			(layer "B.SilkS")
		)
		(fp_line
			(start -3.6 -2.75)
			(end -3.6 2.2)
			(stroke
				(width 0.05)
				(type solid)
			)
			(layer "B.CrtYd")
		)
		(fp_line
			(start -3.6 2.2)
			(end -2.1 2.2)
			(stroke
				(width 0.05)
				(type solid)
			)
			(layer "B.CrtYd")
		)
		(fp_line
			(start -2.1 2.2)
			(end -2.1 3.45)
			(stroke
				(width 0.05)
				(type solid)
			)
			(layer "B.CrtYd")
		)
		(fp_line
			(start -2.1 3.45)
			(end 2.1 3.45)
			(stroke
				(width 0.05)
				(type solid)
			)
			(layer "B.CrtYd")
		)
		(fp_line
			(start 2.1 2.2)
			(end 3.6 2.2)
			(stroke
				(width 0.05)
				(type solid)
			)
			(layer "B.CrtYd")
		)
		(fp_line
			(start 2.1 3.45)
			(end 2.1 2.2)
			(stroke
				(width 0.05)
				(type solid)
			)
			(layer "B.CrtYd")
		)
		(fp_line
			(start 3.6 -2.75)
			(end -3.6 -2.75)
			(stroke
				(width 0.05)
				(type solid)
			)
			(layer "B.CrtYd")
		)
		(fp_line
			(start 3.6 2.2)
			(end 3.6 -2.75)
			(stroke
				(width 0.05)
				(type solid)
			)
			(layer "B.CrtYd")
		)
		(fp_line
			(start -3.5 -2.125)
			(end -3.5 2.125)
			(stroke
				(width 0.15)
				(type solid)
			)
			(layer "B.Fab")
		)
		(fp_line
			(start -3.5 -2.125)
			(end 3.499 -2.125)
			(stroke
				(width 0.15)
				(type solid)
			)
			(layer "B.Fab")
		)
		(fp_line
			(start 3.499 2.125)
			(end -3.5 2.125)
			(stroke
				(width 0.15)
				(type solid)
			)
			(layer "B.Fab")
		)
		(fp_line
			(start 3.499 2.125)
			(end 3.499 -2.125)
			(stroke
				(width 0.15)
				(type solid)
			)
			(layer "B.Fab")
		)
		(pad "1" smd roundrect
			(at -1.5 2.45 180)
			(size 0.6 1.55)
			(layers "B.Cu" "B.Mask" "B.Paste")
			(roundrect_rratio 0.25)
			(net 14 "GND")
			(pinfunction "1")
			(pintype "passive")
		)
		(pad "2" smd roundrect
			(at -0.5 2.45 180)
			(size 0.6 1.55)
			(layers "B.Cu" "B.Mask" "B.Paste")
			(roundrect_rratio 0.25)
			(net 15 "/Power supply/3.3V_QWIIC")
			(pinfunction "2")
			(pintype "passive")
		)
		(pad "3" smd roundrect
			(at 0.498 2.45 180)
			(size 0.6 1.55)
			(layers "B.Cu" "B.Mask" "B.Paste")
			(roundrect_rratio 0.25)
			(net 38 "/Power supply/I2C.SDA")
			(pinfunction "3")
			(pintype "passive")
		)
		(pad "4" smd roundrect
			(at 1.499 2.45 180)
			(size 0.6 1.55)
			(layers "B.Cu" "B.Mask" "B.Paste")
			(roundrect_rratio 0.25)
			(net 39 "/Power supply/I2C.SCL")
			(pinfunction "4")
			(pintype "passive")
		)
		(pad "SH1" smd roundrect
			(at -2.801 -1.426)
			(size 1.2 1.8)
			(layers "B.Cu" "B.Mask" "B.Paste")
			(roundrect_rratio 0.05)
			(net 14 "GND")
			(pinfunction "SH1")
			(pintype "passive")
		)
		(pad "SH2" smd roundrect
			(at 2.798 -1.426)
			(size 1.2 1.8)
			(layers "B.Cu" "B.Mask" "B.Paste")
			(roundrect_rratio 0.05)
			(net 14 "GND")
			(pinfunction "SH2")
			(pintype "passive")
		)
	)
	(footprint "antmicro-footprints:C_0402_1005Metric"
		(layer "B.Cu")
		(at 137.575 75.55 90)
		(descr "Capacitor SMD 0402")
		(tags "capacitor SMD 0402")
		(property "Reference" "C45"
			(at 1.35 0.025 90)
			(unlocked yes)
			(layer "B.SilkS")
			(effects
				(font
					(size 0.7 0.7)
					(thickness 0.15)
				)
				(justify right bottom mirror)
			)
		)
		(property "Value" "C_4u7_0402"
			(at -1.022927 -2.155213 90)
			(layer "B.Fab")
			(effects
				(font
					(size 0.7 0.7)
					(thickness 0.15)
				)
				(justify right bottom mirror)
			)
		)
		(property "Author" "Antmicro"
			(at 213.125 -62.025 0)
			(layer "B.Fab")
			(hide yes)
			(effects
				(font
					(size 1 1)
					(thickness 0.15)
				)
				(justify mirror)
			)
		)
		(property "Dielectric" ""
			(at 213.125 -62.025 0)
			(layer "B.Fab")
			(hide yes)
			(effects
				(font
					(size 1 1)
					(thickness 0.15)
				)
				(justify mirror)
			)
		)
		(property "License" "Apache-2.0"
			(at 213.125 -62.025 0)
			(layer "B.Fab")
			(hide yes)
			(effects
				(font
					(size 1 1)
					(thickness 0.15)
				)
				(justify mirror)
			)
		)
		(property "MPN" "GRM155R61A475MEAAD"
			(at 213.125 -62.025 0)
			(layer "B.Fab")
			(hide yes)
			(effects
				(font
					(size 1 1)
					(thickness 0.15)
				)
				(justify mirror)
			)
		)
		(property "Manufacturer" "Murata"
			(at 213.125 -62.025 0)
			(layer "B.Fab")
			(hide yes)
			(effects
				(font
					(size 1 1)
					(thickness 0.15)
				)
				(justify mirror)
			)
		)
		(property "Val" "4u7"
			(at 213.125 -62.025 0)
			(layer "B.Fab")
			(hide yes)
			(effects
				(font
					(size 1 1)
					(thickness 0.15)
				)
				(justify mirror)
			)
		)
		(property "Voltage" ""
			(at 213.125 -62.025 0)
			(layer "B.Fab")
			(hide yes)
			(effects
				(font
					(size 1 1)
					(thickness 0.15)
				)
				(justify mirror)
			)
		)
		(sheetname "LPDDR5")
		(sheetfile "lpddr5.kicad_sch")
		(attr smd)
		(fp_rect
			(start -0.9659 0.481258)
			(end 0.9649 -0.458742)
			(stroke
				(width 0.05)
				(type solid)
			)
			(fill no)
			(layer "B.CrtYd")
		)
		(fp_line
			(start 0.499 -0.248)
			(end -0.499 -0.248)
			(stroke
				(width 0.15)
				(type solid)
			)
			(layer "B.Fab")
		)
		(fp_line
			(start -0.499 -0.248)
			(end -0.499 0.25)
			(stroke
				(width 0.15)
				(type solid)
			)
			(layer "B.Fab")
		)
		(fp_line
			(start 0.499 0.25)
			(end 0.499 -0.248)
			(stroke
				(width 0.15)
				(type solid)
			)
			(layer "B.Fab")
		)
		(fp_line
			(start -0.499 0.25)
			(end 0.499 0.25)
			(stroke
				(width 0.15)
				(type solid)
			)
			(layer "B.Fab")
		)
		(pad "1" smd roundrect
			(at -0.484 0 90)
			(size 0.59 0.64)
			(layers "B.Cu" "B.Mask" "B.Paste")
			(roundrect_rratio 0.25)
			(net 14 "GND")
			(pintype "passive")
		)
		(pad "2" smd roundrect
			(at 0.484 0 90)
			(size 0.59 0.64)
			(layers "B.Cu" "B.Mask" "B.Paste")
			(roundrect_rratio 0.25)
			(net 4 "+0V5")
			(pintype "passive")
		)
	)
	(footprint "antmicro-footprints:R_0402_1005Metric"
		(layer "B.Cu")
		(at 152.985 89.31 180)
		(descr "Resistor SMD 0402")
		(tags "resistor SMD 0402")
		(property "Reference" "R81"
			(at -1.015 0.61 0)
			(unlocked yes)
			(layer "B.SilkS")
			(effects
				(font
					(size 0.7 0.7)
					(thickness 0.15)
				)
				(justify left bottom mirror)
			)
		)
		(property "Value" "R_100R_0402"
			(at -1.011843 -1.772047 0)
			(layer "B.Fab")
			(effects
				(font
					(size 0.7 0.7)
					(thickness 0.15)
				)
				(justify left bottom mirror)
			)
		)
		(property "Author" "Antmicro"
			(at 305.97 178.62 0)
			(layer "B.Fab")
			(hide yes)
			(effects
				(font
					(size 1 1)
					(thickness 0.15)
				)
				(justify mirror)
			)
		)
		(property "License" "Apache-2.0"
			(at 305.97 178.62 0)
			(layer "B.Fab")
			(hide yes)
			(effects
				(font
					(size 1 1)
					(thickness 0.15)
				)
				(justify mirror)
			)
		)
		(property "MPN" "CR0402-FX-1000GLF"
			(at 305.97 178.62 0)
			(layer "B.Fab")
			(hide yes)
			(effects
				(font
					(size 1 1)
					(thickness 0.15)
				)
				(justify mirror)
			)
		)
		(property "Manufacturer" "Bourns"
			(at 305.97 178.62 0)
			(layer "B.Fab")
			(hide yes)
			(effects
				(font
					(size 1 1)
					(thickness 0.15)
				)
				(justify mirror)
			)
		)
		(property "Tolerance" "1%"
			(at 305.97 178.62 0)
			(layer "B.Fab")
			(hide yes)
			(effects
				(font
					(size 1 1)
					(thickness 0.15)
				)
				(justify mirror)
			)
		)
		(property "Val" "100R"
			(at 305.97 178.62 0)
			(layer "B.Fab")
			(hide yes)
			(effects
				(font
					(size 1 1)
					(thickness 0.15)
				)
				(justify mirror)
			)
		)
		(sheetname "Translators1")
		(sheetfile "translators.kicad_sch")
		(attr smd)
		(fp_rect
			(start -0.93 0.47)
			(end 0.93 -0.47)
			(stroke
				(width 0.05)
				(type solid)
			)
			(fill no)
			(layer "B.CrtYd")
		)
		(fp_rect
			(start -0.5 0.25)
			(end 0.5 -0.25)
			(stroke
				(width 0.15)
				(type solid)
			)
			(fill no)
			(layer "B.Fab")
		)
		(pad "1" smd roundrect
			(at -0.485 0 180)
			(size 0.59 0.64)
			(layers "B.Cu" "B.Mask" "B.Paste")
			(roundrect_rratio 0.25)
			(net 110 "/LPDDR5/LPDDR5_B.WCK1_N")
			(pintype "passive")
		)
		(pad "2" smd roundrect
			(at 0.485 0 180)
			(size 0.59 0.64)
			(layers "B.Cu" "B.Mask" "B.Paste")
			(roundrect_rratio 0.25)
			(net 14 "GND")
			(pintype "passive")
		)
	)
	(footprint "antmicro-footprints:C_0402_1005Metric"
		(layer "B.Cu")
		(at 142.575 79.2 180)
		(descr "Capacitor SMD 0402")
		(tags "capacitor SMD 0402")
		(property "Reference" "C77"
			(at -3.125 -0.3 0)
			(unlocked yes)
			(layer "B.SilkS")
			(effects
				(font
					(size 0.7 0.7)
					(thickness 0.15)
				)
				(justify left bottom mirror)
			)
		)
		(property "Value" "C_4u7_0402"
			(at -1.022927 -2.155213 0)
			(layer "B.Fab")
			(effects
				(font
					(size 0.7 0.7)
					(thickness 0.15)
				)
				(justify left bottom mirror)
			)
		)
		(property "Author" "Antmicro"
			(at 285.15 158.4 0)
			(layer "B.Fab")
			(hide yes)
			(effects
				(font
					(size 1 1)
					(thickness 0.15)
				)
				(justify mirror)
			)
		)
		(property "Dielectric" ""
			(at 285.15 158.4 0)
			(layer "B.Fab")
			(hide yes)
			(effects
				(font
					(size 1 1)
					(thickness 0.15)
				)
				(justify mirror)
			)
		)
		(property "License" "Apache-2.0"
			(at 285.15 158.4 0)
			(layer "B.Fab")
			(hide yes)
			(effects
				(font
					(size 1 1)
					(thickness 0.15)
				)
				(justify mirror)
			)
		)
		(property "MPN" "GRM155R61A475MEAAD"
			(at 285.15 158.4 0)
			(layer "B.Fab")
			(hide yes)
			(effects
				(font
					(size 1 1)
					(thickness 0.15)
				)
				(justify mirror)
			)
		)
		(property "Manufacturer" "Murata"
			(at 285.15 158.4 0)
			(layer "B.Fab")
			(hide yes)
			(effects
				(font
					(size 1 1)
					(thickness 0.15)
				)
				(justify mirror)
			)
		)
		(property "Val" "4u7"
			(at 285.15 158.4 0)
			(layer "B.Fab")
			(hide yes)
			(effects
				(font
					(size 1 1)
					(thickness 0.15)
				)
				(justify mirror)
			)
		)
		(property "Voltage" ""
			(at 285.15 158.4 0)
			(layer "B.Fab")
			(hide yes)
			(effects
				(font
					(size 1 1)
					(thickness 0.15)
				)
				(justify mirror)
			)
		)
		(sheetname "LPDDR5")
		(sheetfile "lpddr5.kicad_sch")
		(attr smd)
		(fp_rect
			(start -0.9659 0.481258)
			(end 0.9649 -0.458742)
			(stroke
				(width 0.05)
				(type solid)
			)
			(fill no)
			(layer "B.CrtYd")
		)
		(fp_line
			(start 0.499 0.25)
			(end 0.499 -0.248)
			(stroke
				(width 0.15)
				(type solid)
			)
			(layer "B.Fab")
		)
		(fp_line
			(start 0.499 -0.248)
			(end -0.499 -0.248)
			(stroke
				(width 0.15)
				(type solid)
			)
			(layer "B.Fab")
		)
		(fp_line
			(start -0.499 0.25)
			(end 0.499 0.25)
			(stroke
				(width 0.15)
				(type solid)
			)
			(layer "B.Fab")
		)
		(fp_line
			(start -0.499 -0.248)
			(end -0.499 0.25)
			(stroke
				(width 0.15)
				(type solid)
			)
			(layer "B.Fab")
		)
		(pad "1" smd roundrect
			(at -0.484 0 180)
			(size 0.59 0.64)
			(layers "B.Cu" "B.Mask" "B.Paste")
			(roundrect_rratio 0.25)
			(net 14 "GND")
			(pintype "passive")
		)
		(pad "2" smd roundrect
			(at 0.484 0 180)
			(size 0.59 0.64)
			(layers "B.Cu" "B.Mask" "B.Paste")
			(roundrect_rratio 0.25)
			(net 13 "+1V05")
			(pintype "passive")
		)
	)
	(footprint "antmicro-footprints:R_0402_1005Metric"
		(layer "B.Cu")
		(at 154.45 90.785 90)
		(descr "Resistor SMD 0402")
		(tags "resistor SMD 0402")
		(property "Reference" "R67"
			(at -0.115 0.45 0)
			(unlocked yes)
			(layer "B.SilkS")
			(effects
				(font
					(size 0.7 0.7)
					(thickness 0.15)
				)
				(justify right bottom mirror)
			)
		)
		(property "Value" "R_100R_0402"
			(at -1.011843 -1.772047 90)
			(layer "B.Fab")
			(effects
				(font
					(size 0.7 0.7)
					(thickness 0.15)
				)
				(justify right bottom mirror)
			)
		)
		(property "Author" "Antmicro"
			(at 245.235 -63.665 0)
			(layer "B.Fab")
			(hide yes)
			(effects
				(font
					(size 1 1)
					(thickness 0.15)
				)
				(justify mirror)
			)
		)
		(property "License" "Apache-2.0"
			(at 245.235 -63.665 0)
			(layer "B.Fab")
			(hide yes)
			(effects
				(font
					(size 1 1)
					(thickness 0.15)
				)
				(justify mirror)
			)
		)
		(property "MPN" "CR0402-FX-1000GLF"
			(at 245.235 -63.665 0)
			(layer "B.Fab")
			(hide yes)
			(effects
				(font
					(size 1 1)
					(thickness 0.15)
				)
				(justify mirror)
			)
		)
		(property "Manufacturer" "Bourns"
			(at 245.235 -63.665 0)
			(layer "B.Fab")
			(hide yes)
			(effects
				(font
					(size 1 1)
					(thickness 0.15)
				)
				(justify mirror)
			)
		)
		(property "Tolerance" "1%"
			(at 245.235 -63.665 0)
			(layer "B.Fab")
			(hide yes)
			(effects
				(font
					(size 1 1)
					(thickness 0.15)
				)
				(justify mirror)
			)
		)
		(property "Val" "100R"
			(at 245.235 -63.665 0)
			(layer "B.Fab")
			(hide yes)
			(effects
				(font
					(size 1 1)
					(thickness 0.15)
				)
				(justify mirror)
			)
		)
		(sheetname "Translators1")
		(sheetfile "translators.kicad_sch")
		(attr smd)
		(fp_rect
			(start -0.93 0.47)
			(end 0.93 -0.47)
			(stroke
				(width 0.05)
				(type solid)
			)
			(fill no)
			(layer "B.CrtYd")
		)
		(fp_rect
			(start -0.5 0.25)
			(end 0.5 -0.25)
			(stroke
				(width 0.15)
				(type solid)
			)
			(fill no)
			(layer "B.Fab")
		)
		(pad "1" smd roundrect
			(at -0.485 0 90)
			(size 0.59 0.64)
			(layers "B.Cu" "B.Mask" "B.Paste")
			(roundrect_rratio 0.25)
			(net 137 "/SODIMM/LPDDR5_IN_B.WCK1_P")
			(pintype "passive")
		)
		(pad "2" smd roundrect
			(at 0.485 0 90)
			(size 0.59 0.64)
			(layers "B.Cu" "B.Mask" "B.Paste")
			(roundrect_rratio 0.25)
			(net 111 "/LPDDR5/LPDDR5_B.WCK1_P")
			(pintype "passive")
		)
	)
	(footprint "antmicro-footprints:C_0402_1005Metric"
		(layer "B.Cu")
		(at 136.175 75.55 90)
		(descr "Capacitor SMD 0402")
		(tags "capacitor SMD 0402")
		(property "Reference" "C64"
			(at 1.35 0.025 90)
			(unlocked yes)
			(layer "B.SilkS")
			(effects
				(font
					(size 0.7 0.7)
					(thickness 0.15)
				)
				(justify right bottom mirror)
			)
		)
		(property "Value" "C_4u7_0402"
			(at -1.022927 -2.155213 90)
			(layer "B.Fab")
			(effects
				(font
					(size 0.7 0.7)
					(thickness 0.15)
				)
				(justify right bottom mirror)
			)
		)
		(property "Author" "Antmicro"
			(at 211.725 -60.625 0)
			(layer "B.Fab")
			(hide yes)
			(effects
				(font
					(size 1 1)
					(thickness 0.15)
				)
				(justify mirror)
			)
		)
		(property "Dielectric" ""
			(at 211.725 -60.625 0)
			(layer "B.Fab")
			(hide yes)
			(effects
				(font
					(size 1 1)
					(thickness 0.15)
				)
				(justify mirror)
			)
		)
		(property "License" "Apache-2.0"
			(at 211.725 -60.625 0)
			(layer "B.Fab")
			(hide yes)
			(effects
				(font
					(size 1 1)
					(thickness 0.15)
				)
				(justify mirror)
			)
		)
		(property "MPN" "GRM155R61A475MEAAD"
			(at 211.725 -60.625 0)
			(layer "B.Fab")
			(hide yes)
			(effects
				(font
					(size 1 1)
					(thickness 0.15)
				)
				(justify mirror)
			)
		)
		(property "Manufacturer" "Murata"
			(at 211.725 -60.625 0)
			(layer "B.Fab")
			(hide yes)
			(effects
				(font
					(size 1 1)
					(thickness 0.15)
				)
				(justify mirror)
			)
		)
		(property "Val" "4u7"
			(at 211.725 -60.625 0)
			(layer "B.Fab")
			(hide yes)
			(effects
				(font
					(size 1 1)
					(thickness 0.15)
				)
				(justify mirror)
			)
		)
		(property "Voltage" ""
			(at 211.725 -60.625 0)
			(layer "B.Fab")
			(hide yes)
			(effects
				(font
					(size 1 1)
					(thickness 0.15)
				)
				(justify mirror)
			)
		)
		(sheetname "LPDDR5")
		(sheetfile "lpddr5.kicad_sch")
		(attr smd)
		(fp_rect
			(start -0.9659 0.481258)
			(end 0.9649 -0.458742)
			(stroke
				(width 0.05)
				(type solid)
			)
			(fill no)
			(layer "B.CrtYd")
		)
		(fp_line
			(start 0.499 -0.248)
			(end -0.499 -0.248)
			(stroke
				(width 0.15)
				(type solid)
			)
			(layer "B.Fab")
		)
		(fp_line
			(start -0.499 -0.248)
			(end -0.499 0.25)
			(stroke
				(width 0.15)
				(type solid)
			)
			(layer "B.Fab")
		)
		(fp_line
			(start 0.499 0.25)
			(end 0.499 -0.248)
			(stroke
				(width 0.15)
				(type solid)
			)
			(layer "B.Fab")
		)
		(fp_line
			(start -0.499 0.25)
			(end 0.499 0.25)
			(stroke
				(width 0.15)
				(type solid)
			)
			(layer "B.Fab")
		)
		(pad "1" smd roundrect
			(at -0.484 0 90)
			(size 0.59 0.64)
			(layers "B.Cu" "B.Mask" "B.Paste")
			(roundrect_rratio 0.25)
			(net 14 "GND")
			(pintype "passive")
		)
		(pad "2" smd roundrect
			(at 0.484 0 90)
			(size 0.59 0.64)
			(layers "B.Cu" "B.Mask" "B.Paste")
			(roundrect_rratio 0.25)
			(net 12 "+0V9")
			(pintype "passive")
		)
	)
	(footprint "antmicro-footprints:R_0402_1005Metric"
		(layer "B.Cu")
		(at 139.75 93.85 -90)
		(descr "Resistor SMD 0402")
		(tags "resistor SMD 0402")
		(property "Reference" "R92"
			(at 0.85 -0.35 90)
			(unlocked yes)
			(layer "B.SilkS")
			(effects
				(font
					(size 0.7 0.7)
					(thickness 0.15)
				)
				(justify left bottom mirror)
			)
		)
		(property "Value" "R_100R_0402"
			(at -1.011843 -1.772047 90)
			(layer "B.Fab")
			(effects
				(font
					(size 0.7 0.7)
					(thickness 0.15)
				)
				(justify left bottom mirror)
			)
		)
		(property "Author" "Antmicro"
			(at 45.9 233.6 0)
			(layer "B.Fab")
			(hide yes)
			(effects
				(font
					(size 1 1)
					(thickness 0.15)
				)
				(justify mirror)
			)
		)
		(property "License" "Apache-2.0"
			(at 45.9 233.6 0)
			(layer "B.Fab")
			(hide yes)
			(effects
				(font
					(size 1 1)
					(thickness 0.15)
				)
				(justify mirror)
			)
		)
		(property "MPN" "CR0402-FX-1000GLF"
			(at 45.9 233.6 0)
			(layer "B.Fab")
			(hide yes)
			(effects
				(font
					(size 1 1)
					(thickness 0.15)
				)
				(justify mirror)
			)
		)
		(property "Manufacturer" "Bourns"
			(at 45.9 233.6 0)
			(layer "B.Fab")
			(hide yes)
			(effects
				(font
					(size 1 1)
					(thickness 0.15)
				)
				(justify mirror)
			)
		)
		(property "Tolerance" "1%"
			(at 45.9 233.6 0)
			(layer "B.Fab")
			(hide yes)
			(effects
				(font
					(size 1 1)
					(thickness 0.15)
				)
				(justify mirror)
			)
		)
		(property "Val" "100R"
			(at 45.9 233.6 0)
			(layer "B.Fab")
			(hide yes)
			(effects
				(font
					(size 1 1)
					(thickness 0.15)
				)
				(justify mirror)
			)
		)
		(sheetname "Translators1")
		(sheetfile "translators.kicad_sch")
		(attr smd)
		(fp_rect
			(start -0.93 0.47)
			(end 0.93 -0.47)
			(stroke
				(width 0.05)
				(type solid)
			)
			(fill no)
			(layer "B.CrtYd")
		)
		(fp_rect
			(start -0.5 0.25)
			(end 0.5 -0.25)
			(stroke
				(width 0.15)
				(type solid)
			)
			(fill no)
			(layer "B.Fab")
		)
		(pad "1" smd roundrect
			(at -0.485 0 270)
			(size 0.59 0.64)
			(layers "B.Cu" "B.Mask" "B.Paste")
			(roundrect_rratio 0.25)
			(net 100 "/LPDDR5/LPDDR5_B.CA6")
			(pintype "passive")
		)
		(pad "2" smd roundrect
			(at 0.485 0 270)
			(size 0.59 0.64)
			(layers "B.Cu" "B.Mask" "B.Paste")
			(roundrect_rratio 0.25)
			(net 14 "GND")
			(pintype "passive")
		)
	)
	(footprint "antmicro-footprints:R_0402_1005Metric"
		(layer "B.Cu")
		(at 166.45 91.95)
		(descr "Resistor SMD 0402")
		(tags "resistor SMD 0402")
		(property "Reference" "R96"
			(at 0.85 -0.15 0)
			(unlocked yes)
			(layer "B.SilkS")
			(effects
				(font
					(size 0.7 0.7)
					(thickness 0.15)
				)
				(justify right bottom mirror)
			)
		)
		(property "Value" "R_100R_0402"
			(at -1.011843 -1.772047 0)
			(layer "B.Fab")
			(effects
				(font
					(size 0.7 0.7)
					(thickness 0.15)
				)
				(justify right bottom mirror)
			)
		)
		(property "Author" "Antmicro"
			(at 0 0 0)
			(layer "B.Fab")
			(hide yes)
			(effects
				(font
					(size 1 1)
					(thickness 0.15)
				)
				(justify mirror)
			)
		)
		(property "License" "Apache-2.0"
			(at 0 0 0)
			(layer "B.Fab")
			(hide yes)
			(effects
				(font
					(size 1 1)
					(thickness 0.15)
				)
				(justify mirror)
			)
		)
		(property "MPN" "CR0402-FX-1000GLF"
			(at 0 0 0)
			(layer "B.Fab")
			(hide yes)
			(effects
				(font
					(size 1 1)
					(thickness 0.15)
				)
				(justify mirror)
			)
		)
		(property "Manufacturer" "Bourns"
			(at 0 0 0)
			(layer "B.Fab")
			(hide yes)
			(effects
				(font
					(size 1 1)
					(thickness 0.15)
				)
				(justify mirror)
			)
		)
		(property "Tolerance" "1%"
			(at 0 0 0)
			(layer "B.Fab")
			(hide yes)
			(effects
				(font
					(size 1 1)
					(thickness 0.15)
				)
				(justify mirror)
			)
		)
		(property "Val" "100R"
			(at 0 0 0)
			(layer "B.Fab")
			(hide yes)
			(effects
				(font
					(size 1 1)
					(thickness 0.15)
				)
				(justify mirror)
			)
		)
		(sheetname "Translators1")
		(sheetfile "translators.kicad_sch")
		(attr smd)
		(fp_rect
			(start -0.93 0.47)
			(end 0.93 -0.47)
			(stroke
				(width 0.05)
				(type solid)
			)
			(fill no)
			(layer "B.CrtYd")
		)
		(fp_rect
			(start -0.5 0.25)
			(end 0.5 -0.25)
			(stroke
				(width 0.15)
				(type solid)
			)
			(fill no)
			(layer "B.Fab")
		)
		(pad "1" smd roundrect
			(at -0.485 0)
			(size 0.59 0.64)
			(layers "B.Cu" "B.Mask" "B.Paste")
			(roundrect_rratio 0.25)
			(net 212 "/LPDDR5/LPDDR5_B.DMI0")
			(pintype "passive")
		)
		(pad "2" smd roundrect
			(at 0.485 0)
			(size 0.59 0.64)
			(layers "B.Cu" "B.Mask" "B.Paste")
			(roundrect_rratio 0.25)
			(net 14 "GND")
			(pintype "passive")
		)
	)
	(footprint "antmicro-footprints:C_0402_1005Metric"
		(layer "B.Cu")
		(at 127.1 80.8)
		(descr "Capacitor SMD 0402")
		(tags "capacitor SMD 0402")
		(property "Reference" "C76"
			(at -3.2 0.3 0)
			(unlocked yes)
			(layer "B.SilkS")
			(effects
				(font
					(size 0.7 0.7)
					(thickness 0.15)
				)
				(justify right bottom mirror)
			)
		)
		(property "Value" "C_4u7_0402"
			(at -1.022927 -2.155213 0)
			(layer "B.Fab")
			(effects
				(font
					(size 0.7 0.7)
					(thickness 0.15)
				)
				(justify right bottom mirror)
			)
		)
		(property "Author" "Antmicro"
			(at 0 0 0)
			(layer "B.Fab")
			(hide yes)
			(effects
				(font
					(size 1 1)
					(thickness 0.15)
				)
				(justify mirror)
			)
		)
		(property "Dielectric" ""
			(at 0 0 0)
			(layer "B.Fab")
			(hide yes)
			(effects
				(font
					(size 1 1)
					(thickness 0.15)
				)
				(justify mirror)
			)
		)
		(property "License" "Apache-2.0"
			(at 0 0 0)
			(layer "B.Fab")
			(hide yes)
			(effects
				(font
					(size 1 1)
					(thickness 0.15)
				)
				(justify mirror)
			)
		)
		(property "MPN" "GRM155R61A475MEAAD"
			(at 0 0 0)
			(layer "B.Fab")
			(hide yes)
			(effects
				(font
					(size 1 1)
					(thickness 0.15)
				)
				(justify mirror)
			)
		)
		(property "Manufacturer" "Murata"
			(at 0 0 0)
			(layer "B.Fab")
			(hide yes)
			(effects
				(font
					(size 1 1)
					(thickness 0.15)
				)
				(justify mirror)
			)
		)
		(property "Val" "4u7"
			(at 0 0 0)
			(layer "B.Fab")
			(hide yes)
			(effects
				(font
					(size 1 1)
					(thickness 0.15)
				)
				(justify mirror)
			)
		)
		(property "Voltage" ""
			(at 0 0 0)
			(layer "B.Fab")
			(hide yes)
			(effects
				(font
					(size 1 1)
					(thickness 0.15)
				)
				(justify mirror)
			)
		)
		(sheetname "LPDDR5")
		(sheetfile "lpddr5.kicad_sch")
		(attr smd)
		(fp_rect
			(start -0.9659 0.481258)
			(end 0.9649 -0.458742)
			(stroke
				(width 0.05)
				(type solid)
			)
			(fill no)
			(layer "B.CrtYd")
		)
		(fp_line
			(start -0.499 -0.248)
			(end -0.499 0.25)
			(stroke
				(width 0.15)
				(type solid)
			)
			(layer "B.Fab")
		)
		(fp_line
			(start -0.499 0.25)
			(end 0.499 0.25)
			(stroke
				(width 0.15)
				(type solid)
			)
			(layer "B.Fab")
		)
		(fp_line
			(start 0.499 -0.248)
			(end -0.499 -0.248)
			(stroke
				(width 0.15)
				(type solid)
			)
			(layer "B.Fab")
		)
		(fp_line
			(start 0.499 0.25)
			(end 0.499 -0.248)
			(stroke
				(width 0.15)
				(type solid)
			)
			(layer "B.Fab")
		)
		(pad "1" smd roundrect
			(at -0.484 0)
			(size 0.59 0.64)
			(layers "B.Cu" "B.Mask" "B.Paste")
			(roundrect_rratio 0.25)
			(net 14 "GND")
			(pintype "passive")
		)
		(pad "2" smd roundrect
			(at 0.484 0)
			(size 0.59 0.64)
			(layers "B.Cu" "B.Mask" "B.Paste")
			(roundrect_rratio 0.25)
			(net 13 "+1V05")
			(pintype "passive")
		)
	)
	(gr_line
		(start 135.298439 60)
		(end 168.85 60)
		(stroke
			(width 0.15)
			(type solid)
		)
		(layer "Edge.Cuts")
	)
	(gr_line
		(start 100.748439 60)
		(end 135.298439 60)
		(stroke
			(width 0.15)
			(type solid)
		)
		(layer "Edge.Cuts")
	)
	(gr_arc
		(start 168.85 60)
		(mid 169.379322 60.220221)
		(end 169.598441 60.75)
		(stroke
			(width 0.15)
			(type solid)
		)
		(layer "Edge.Cuts")
	)
	(gr_line
		(start 99.975 70.75)
		(end 99.998439 60.75)
		(stroke
			(width 0.15)
			(type solid)
		)
		(layer "Edge.Cuts")
	)
	(gr_arc
		(start 99.998439 60.75)
		(mid 100.218109 60.21967)
		(end 100.748439 60)
		(stroke
			(width 0.15)
			(type solid)
		)
		(layer "Edge.Cuts")
	)
	(gr_line
		(start 169.575 70.75)
		(end 169.598441 60.75)
		(stroke
			(width 0.15)
			(type solid)
		)
		(layer "Edge.Cuts")
	)
	(gr_text "LPDDR5 Testbed\nRev. ${REVISION}  12/2023"
		(at 130.975 67.95 0)
		(layer "F.Cu")
		(effects
			(font
				(size 0.85 0.85)
				(thickness 0.18)
			)
			(justify left)
		)
	)
	(segment
		(start 163.325 65.615)
		(end 163.325 66.55)
		(width 0.09)
		(layer "F.Cu")
		(net 1)
	)
	(segment
		(start 163.59 65.35)
		(end 163.57 65.37)
		(width 0.09)
		(layer "F.Cu")
		(net 1)
	)
	(segment
		(start 163.57 65.37)
		(end 163.325 65.615)
		(width 0.09)
		(layer "F.Cu")
		(net 1)
	)
	(via
		(at 109.9 77.6)
		(size 0.4)
		(drill 0.15)
		(layers "F.Cu" "B.Cu")
		(free yes)
		(net 1)
	)
	(via
		(at 109.9 76.5)
		(size 0.4)
		(drill 0.15)
		(layers "F.Cu" "B.Cu")
		(free yes)
		(net 1)
	)
	(via
		(at 163.15 69.9)
		(size 0.4)
		(drill 0.15)
		(layers "F.Cu" "B.Cu")
		(free yes)
		(net 1)
	)
	(via
		(at 109.9 77)
		(size 0.4)
		(drill 0.15)
		(layers "F.Cu" "B.Cu")
		(free yes)
		(net 1)
	)
	(via
		(at 163.57 65.37)
		(size 0.4)
		(drill 0.2)
		(layers "F.Cu" "B.Cu")
		(net 1)
	)
	(via
		(at 165.49 65.35)
		(size 0.4)
		(drill 0.2)
		(layers "F.Cu" "B.Cu")
		(net 1)
	)
	(via
		(at 162.975 67.95)
		(size 0.4)
		(drill 0.15)
		(layers "F.Cu" "B.Cu")
		(free yes)
		(net 1)
	)
	(via
		(at 109.4 77.6)
		(size 0.4)
		(drill 0.15)
		(layers "F.Cu" "B.Cu")
		(free yes)
		(net 1)
	)
	(via
		(at 163.25 68.55)
		(size 0.4)
		(drill 0.15)
		(layers "F.Cu" "B.Cu")
		(free yes)
		(net 1)
	)
	(via
		(at 109.4 76.5)
		(size 0.4)
		(drill 0.15)
		(layers "F.Cu" "B.Cu")
		(free yes)
		(net 1)
	)
	(via
		(at 163.25 67.3)
		(size 0.4)
		(drill 0.15)
		(layers "F.Cu" "B.Cu")
		(free yes)
		(net 1)
	)
	(via
		(at 109.4 77)
		(size 0.4)
		(drill 0.15)
		(layers "F.Cu" "B.Cu")
		(free yes)
		(net 1)
	)
	(via
		(at 162.775 70.2)
		(size 0.4)
		(drill 0.15)
		(layers "F.Cu" "B.Cu")
		(free yes)
		(net 1)
	)
	(segment
		(start 165.47 65.37)
		(end 165.49 65.35)
		(width 0.15)
		(layer "B.Cu")
		(net 1)
	)
	(segment
		(start 163.57 65.37)
		(end 165.47 65.37)
		(width 0.15)
		(layer "B.Cu")
		(net 1)
	)
	(via
		(at 130.575 77.6)
		(size 0.4)
		(drill 0.15)
		(layers "F.Cu" "B.Cu")
		(net 4)
	)
	(via
		(at 138.275 74.4)
		(size 0.4)
		(drill 0.15)
		(layers "F.Cu" "B.Cu")
		(net 4)
	)
	(via
		(at 159 69.4)
		(size 0.4)
		(drill 0.15)
		(layers "F.Cu" "B.Cu")
		(free yes)
		(net 4)
	)
	(via
		(at 130.575 82.4)
		(size 0.4)
		(drill 0.15)
		(layers "F.Cu" "B.Cu")
		(net 4)
	)
	(via
		(at 139.675 83.2)
		(size 0.4)
		(drill 0.15)
		(layers "F.Cu" "B.Cu")
		(net 4)
	)
	(via
		(at 138.975 77.6)
		(size 0.4)
		(drill 0.15)
		(layers "F.Cu" "B.Cu")
		(net 4)
	)
	(via
		(at 138.275 83.2)
		(size 0.4)
		(drill 0.15)
		(layers "F.Cu" "B.Cu")
		(net 4)
	)
	(via
		(at 157.8 68.8)
		(size 0.4)
		(drill 0.15)
		(layers "F.Cu" "B.Cu")
		(free yes)
		(net 4)
	)
	(via
		(at 131.275 76)
		(size 0.4)
		(drill 0.15)
		(layers "F.Cu" "B.Cu")
		(net 4)
	)
	(via
		(at 131.275 85.6)
		(size 0.4)
		(drill 0.15)
		(layers "F.Cu" "B.Cu")
		(net 4)
	)
	(via
		(at 131.275 76.8)
		(size 0.4)
		(drill 0.15)
		(layers "F.Cu" "B.Cu")
		(net 4)
	)
	(via
		(at 157.8 67)
		(size 0.4)
		(drill 0.15)
		(layers "F.Cu" "B.Cu")
		(free yes)
		(net 4)
	)
	(via
		(at 128.475 75.2)
		(size 0.4)
		(drill 0.15)
		(layers "F.Cu" "B.Cu")
		(net 4)
	)
	(via
		(at 158.4 69.4)
		(size 0.4)
		(drill 0.15)
		(layers "F.Cu" "B.Cu")
		(free yes)
		(net 4)
	)
	(via
		(at 139.675 76.8)
		(size 0.4)
		(drill 0.15)
		(layers "F.Cu" "B.Cu")
		(net 4)
	)
	(via
		(at 159.6 68.8)
		(size 0.4)
		(drill 0.15)
		(layers "F.Cu" "B.Cu")
		(free yes)
		(net 4)
	)
	(via
		(at 159 68.8)
		(size 0.4)
		(drill 0.15)
		(layers "F.Cu" "B.Cu")
		(free yes)
		(net 4)
	)
	(via
		(at 137.575 85.6)
		(size 0.4)
		(drill 0.15)
		(layers "F.Cu" "B.Cu")
		(net 4)
	)
	(via
		(at 129.175 76)
		(size 0.4)
		(drill 0.15)
		(layers "F.Cu" "B.Cu")
		(net 4)
	)
	(via
		(at 131.975 74.4)
		(size 0.4)
		(drill 0.15)
		(layers "F.Cu" "B.Cu")
		(net 4)
	)
	(via
		(at 131.975 84.8)
		(size 0.4)
		(drill 0.15)
		(layers "F.Cu" "B.Cu")
		(net 4)
	)
	(via
		(at 157.8 67.6)
		(size 0.4)
		(drill 0.15)
		(layers "F.Cu" "B.Cu")
		(free yes)
		(net 4)
	)
	(via
		(at 158.4 67)
		(size 0.4)
		(drill 0.15)
		(layers "F.Cu" "B.Cu")
		(free yes)
		(net 4)
	)
	(via
		(at 138.275 84)
		(size 0.4)
		(drill 0.15)
		(layers "F.Cu" "B.Cu")
		(net 4)
	)
	(via
		(at 159.6 68.2)
		(size 0.4)
		(drill 0.15)
		(layers "F.Cu" "B.Cu")
		(free yes)
		(net 4)
	)
	(via
		(at 137.575 74.4)
		(size 0.4)
		(drill 0.15)
		(layers "F.Cu" "B.Cu")
		(net 4)
	)
	(via
		(at 127.775 76)
		(size 0.4)
		(drill 0.15)
		(layers "F.Cu" "B.Cu")
		(net 4)
	)
	(via
		(at 128.475 84.8)
		(size 0.4)
		(drill 0.15)
		(layers "F.Cu" "B.Cu")
		(net 4)
	)
	(via
		(at 129.875 83.2)
		(size 0.4)
		(drill 0.15)
		(layers "F.Cu" "B.Cu")
		(net 4)
	)
	(via
		(at 129.875 76.8)
		(size 0.4)
		(drill 0.15)
		(layers "F.Cu" "B.Cu")
		(net 4)
	)
	(via
		(at 137.575 84.8)
		(size 0.4)
		(drill 0.15)
		(layers "F.Cu" "B.Cu")
		(net 4)
	)
	(via
		(at 137.575 75.2)
		(size 0.4)
		(drill 0.15)
		(layers "F.Cu" "B.Cu")
		(net 4)
	)
	(via
		(at 158.4 67.6)
		(size 0.4)
		(drill 0.15)
		(layers "F.Cu" "B.Cu")
		(free yes)
		(net 4)
	)
	(via
		(at 159.6 69.4)
		(size 0.4)
		(drill 0.15)
		(layers "F.Cu" "B.Cu")
		(free yes)
		(net 4)
	)
	(via
		(at 138.275 85.6)
		(size 0.4)
		(drill 0.15)
		(layers "F.Cu" "B.Cu")
		(net 4)
	)
	(via
		(at 140.375 84)
		(size 0.4)
		(drill 0.15)
		(layers "F.Cu" "B.Cu")
		(net 4)
	)
	(via
		(at 131.975 75.2)
		(size 0.4)
		(drill 0.15)
		(layers "F.Cu" "B.Cu")
		(net 4)
	)
	(via
		(at 138.975 82.4)
		(size 0.4)
		(drill 0.15)
		(layers "F.Cu" "B.Cu")
		(net 4)
	)
	(via
		(at 158.4 68.2)
		(size 0.4)
		(drill 0.15)
		(layers "F.Cu" "B.Cu")
		(free yes)
		(net 4)
	)
	(via
		(at 157.8 69.4)
		(size 0.4)
		(drill 0.15)
		(layers "F.Cu" "B.Cu")
		(free yes)
		(net 4)
	)
	(via
		(at 141.775 84)
		(size 0.4)
		(drill 0.15)
		(layers "F.Cu" "B.Cu")
		(net 4)
	)
	(via
		(at 127.775 84)
		(size 0.4)
		(drill 0.15)
		(layers "F.Cu" "B.Cu")
		(net 4)
	)
	(via
		(at 131.275 84)
		(size 0.4)
		(drill 0.15)
		(layers "F.Cu" "B.Cu")
		(net 4)
	)
	(via
		(at 138.275 76.8)
		(size 0.4)
		(drill 0.15)
		(layers "F.Cu" "B.Cu")
		(net 4)
	)
	(via
		(at 131.275 83.2)
		(size 0.4)
		(drill 0.15)
		(layers "F.Cu" "B.Cu")
		(net 4)
	)
	(via
		(at 141.775 76)
		(size 0.4)
		(drill 0.15)
		(layers "F.Cu" "B.Cu")
		(net 4)
	)
	(via
		(at 141.075 75.2)
		(size 0.4)
		(drill 0.15)
		(layers "F.Cu" "B.Cu")
		(net 4)
	)
	(via
		(at 140.375 76)
		(size 0.4)
		(drill 0.15)
		(layers "F.Cu" "B.Cu")
		(net 4)
	)
	(via
		(at 131.975 85.6)
		(size 0.4)
		(drill 0.15)
		(layers "F.Cu" "B.Cu")
		(net 4)
	)
	(via
		(at 157.8 68.2)
		(size 0.4)
		(drill 0.15)
		(layers "F.Cu" "B.Cu")
		(free yes)
		(net 4)
	)
	(via
		(at 138.275 76)
		(size 0.4)
		(drill 0.15)
		(layers "F.Cu" "B.Cu")
		(net 4)
	)
	(via
		(at 141.075 84.8)
		(size 0.4)
		(drill 0.15)
		(layers "F.Cu" "B.Cu")
		(net 4)
	)
	(via
		(at 159 68.2)
		(size 0.4)
		(drill 0.15)
		(layers "F.Cu" "B.Cu")
		(free yes)
		(net 4)
	)
	(via
		(at 129.175 84)
		(size 0.4)
		(drill 0.15)
		(layers "F.Cu" "B.Cu")
		(net 4)
	)
	(via
		(at 131.275 74.4)
		(size 0.4)
		(drill 0.15)
		(layers "F.Cu" "B.Cu")
		(net 4)
	)
	(via
		(at 158.4 68.8)
		(size 0.4)
		(drill 0.15)
		(layers "F.Cu" "B.Cu")
		(free yes)
		(net 4)
	)
	(segment
		(start 129.875 83.8)
		(end 129.675 84)
		(width 0.5)
		(layer "B.Cu")
		(net 4)
	)
	(segment
		(start 139.675 83.2)
		(end 139.675 83.7)
		(width 0.5)
		(layer "B.Cu")
		(net 4)
	)
	(segment
		(start 129.875 83.2)
		(end 129.875 83.8)
		(width 0.5)
		(layer "B.Cu")
		(net 4)
	)
	(segment
		(start 129.875 76.3)
		(end 129.575 76)
		(width 0.5)
		(layer "B.Cu")
		(net 4)
	)
	(segment
		(start 139.975 84)
		(end 140.325 84)
		(width 0.5)
		(layer "B.Cu")
		(net 4)
	)
	(segment
		(start 139.675 76.8)
		(end 139.675 76.2)
		(width 0.5)
		(layer "B.Cu")
		(net 4)
	)
	(segment
		(start 129.575 76)
		(end 129.225 76)
		(width 0.5)
		(layer "B.Cu")
		(net 4)
	)
	(segment
		(start 139.675 83.7)
		(end 139.975 84)
		(width 0.5)
		(layer "B.Cu")
		(net 4)
	)
	(segment
		(start 139.675 76.2)
		(end 139.875 76)
		(width 0.5)
		(layer "B.Cu")
		(net 4)
	)
	(segment
		(start 139.875 76)
		(end 140.375 76)
		(width 0.5)
		(layer "B.Cu")
		(net 4)
	)
	(segment
		(start 129.875 76.8)
		(end 129.875 76.3)
		(width 0.5)
		(layer "B.Cu")
		(net 4)
	)
	(segment
		(start 129.675 84)
		(end 129.175 84)
		(width 0.5)
		(layer "B.Cu")
		(net 4)
	)
	(segment
		(start 141.775 76)
		(end 141.775 75.9)
		(width 0.3)
		(layer "In3.Cu")
		(net 4)
	)
	(segment
		(start 127.775 75.9)
		(end 128.475 75.2)
		(width 0.3)
		(layer "In3.Cu")
		(net 4)
	)
	(segment
		(start 127.775 76)
		(end 127.775 75.9)
		(width 0.3)
		(layer "In3.Cu")
		(net 4)
	)
	(segment
		(start 127.775 84)
		(end 127.775 84.1)
		(width 0.3)
		(layer "In3.Cu")
		(net 4)
	)
	(segment
		(start 141.775 84)
		(end 141.775 84.1)
		(width 0.3)
		(layer "In3.Cu")
		(net 4)
	)
	(segment
		(start 141.775 75.9)
		(end 141.075 75.2)
		(width 0.3)
		(layer "In3.Cu")
		(net 4)
	)
	(segment
		(start 141.775 84.1)
		(end 141.075 84.8)
		(width 0.3)
		(layer "In3.Cu")
		(net 4)
	)
	(segment
		(start 127.775 84.1)
		(end 128.475 84.8)
		(width 0.3)
		(layer "In3.Cu")
		(net 4)
	)
	(segment
		(start 168.1 60.6)
		(end 168.51 60.6)
		(width 0.15)
		(layer "F.Cu")
		(net 5)
	)
	(segment
		(start 168.51 60.6)
		(end 168.875 60.965)
		(width 0.15)
		(layer "F.Cu")
		(net 5)
	)
	(via
		(at 168.1 60.6)
		(size 0.4)
		(drill 0.15)
		(layers "F.Cu" "B.Cu")
		(net 5)
	)
	(via
		(at 101.25 96.4)
		(size 0.4)
		(drill 0.15)
		(layers "F.Cu" "B.Cu")
		(free yes)
		(net 5)
	)
	(via
		(at 101.85 97)
		(size 0.4)
		(drill 0.15)
		(layers "F.Cu" "B.Cu")
		(free yes)
		(net 5)
	)
	(via
		(at 108.5875 74.975)
		(size 0.4)
		(drill 0.15)
		(layers "F.Cu" "B.Cu")
		(free yes)
		(net 5)
	)
	(via
		(at 134.9 92.6)
		(size 0.4)
		(drill 0.15)
		(layers "F.Cu" "B.Cu")
		(net 5)
	)
	(via
		(at 108.5875 75.475)
		(size 0.4)
		(drill 0.15)
		(layers "F.Cu" "B.Cu")
		(free yes)
		(net 5)
	)
	(via
		(at 101.25 97)
		(size 0.4)
		(drill 0.15)
		(layers "F.Cu" "B.Cu")
		(free yes)
		(net 5)
	)
	(via
		(at 101.25 95.8)
		(size 0.4)
		(drill 0.15)
		(layers "F.Cu" "B.Cu")
		(free yes)
		(net 5)
	)
	(via
		(at 101.85 96.4)
		(size 0.4)
		(drill 0.15)
		(layers "F.Cu" "B.Cu")
		(free yes)
		(net 5)
	)
	(via
		(at 107 71.9)
		(size 0.4)
		(drill 0.15)
		(layers "F.Cu" "B.Cu")
		(net 5)
	)
	(via
		(at 108.5875 74.475)
		(size 0.4)
		(drill 0.15)
		(layers "F.Cu" "B.Cu")
		(free yes)
		(net 5)
	)
	(via
		(at 101.85 95.8)
		(size 0.4)
		(drill 0.15)
		(layers "F.Cu" "B.Cu")
		(free yes)
		(net 5)
	)
	(via
		(at 108.5875 73.975)
		(size 0.4)
		(drill 0.15)
		(layers "F.Cu" "B.Cu")
		(free yes)
		(net 5)
	)
	(segment
		(start 111.95 62.55)
		(end 111.85 62.55)
		(width 0.2)
		(layer "B.Cu")
		(net 5)
	)
	(segment
		(start 111.699 64)
		(end 111.699 62.701)
		(width 0.2)
		(layer "B.Cu")
		(net 5)
	)
	(segment
		(start 111.548 62.55)
		(end 111.699 62.701)
		(width 0.2)
		(layer "B.Cu")
		(net 5)
	)
	(segment
		(start 115.45 62.95)
		(end 122.7 62.95)
		(width 0.2)
		(layer "B.Cu")
		(net 5)
	)
	(segment
		(start 111.75 62.55)
		(end 111.95 62.55)
		(width 0.2)
		(layer "B.Cu")
		(net 5)
	)
	(segment
		(start 111.699 62.601)
		(end 111.75 62.55)
		(width 0.2)
		(layer "B.Cu")
		(net 5)
	)
	(segment
		(start 107 71.9)
		(end 107 70.65)
		(width 0.2)
		(layer "B.Cu")
		(net 5)
	)
	(segment
		(start 122.7 62.95)
		(end 124.75 60.9)
		(width 0.2)
		(layer "B.Cu")
		(net 5)
	)
	(segment
		(start 111.699 62.701)
		(end 111.699 62.601)
		(width 0.2)
		(layer "B.Cu")
		(net 5)
	)
	(segment
		(start 111.35 62.55)
		(end 111.75 62.55)
		(width 0.2)
		(layer "B.Cu")
		(net 5)
	)
	(segment
		(start 111.85 62.55)
		(end 111.699 62.701)
		(width 0.2)
		(layer "B.Cu")
		(net 5)
	)
	(segment
		(start 108.5 63.7)
		(end 109.65 62.55)
		(width 0.2)
		(layer "B.Cu")
		(net 5)
	)
	(segment
		(start 160.2 60.9)
		(end 167.8 60.9)
		(width 0.15)
		(layer "B.Cu")
		(net 5)
	)
	(segment
		(start 107 70.65)
		(end 108.5 69.15)
		(width 0.2)
		(layer "B.Cu")
		(net 5)
	)
	(segment
		(start 124.75 60.9)
		(end 160.2 60.9)
		(width 0.2)
		(layer "B.Cu")
		(net 5)
	)
	(segment
		(start 111.95 62.55)
		(end 115.05 62.55)
		(width 0.2)
		(layer "B.Cu")
		(net 5)
	)
	(segment
		(start 167.8 60.9)
		(end 168.1 60.6)
		(width 0.15)
		(layer "B.Cu")
		(net 5)
	)
	(segment
		(start 108.5 69.15)
		(end 108.5 63.7)
		(width 0.2)
		(layer "B.Cu")
		(net 5)
	)
	(segment
		(start 115.05 62.55)
		(end 115.45 62.95)
		(width 0.2)
		(layer "B.Cu")
		(net 5)
	)
	(segment
		(start 134.9 92.6425)
		(end 134.9 92.6)
		(width 0.15)
		(layer "B.Cu")
		(net 5)
	)
	(segment
		(start 111.35 62.55)
		(end 111.548 62.55)
		(width 0.2)
		(layer "B.Cu")
		(net 5)
	)
	(segment
		(start 134.9 93.3575)
		(end 134.9 92.6425)
		(width 0.15)
		(layer "B.Cu")
		(net 5)
	)
	(segment
		(start 109.65 62.55)
		(end 111.35 62.55)
		(width 0.2)
		(layer "B.Cu")
		(net 5)
	)
	(segment
		(start 131.550331 97.98)
		(end 102.83 97.98)
		(width 0.15)
		(layer "In2.Cu")
		(net 5)
	)
	(segment
		(start 132.4 97.130331)
		(end 131.550331 97.98)
		(width 0.15)
		(layer "In2.Cu")
		(net 5)
	)
	(segment
		(start 134.9 92.6)
		(end 132.4 95.1)
		(width 0.15)
		(layer "In2.Cu")
		(net 5)
	)
	(segment
		(start 102.83 97.98)
		(end 101.85 97)
		(width 0.15)
		(layer "In2.Cu")
		(net 5)
	)
	(segment
		(start 132.4 95.1)
		(end 132.4 97.130331)
		(width 0.15)
		(layer "In2.Cu")
		(net 5)
	)
	(segment
		(start 165.975 67.7)
		(end 166.412 67.7)
		(width 0.1524)
		(layer "F.Cu")
		(net 6)
	)
	(segment
		(start 166.662 67.45)
		(end 167.091 67.45)
		(width 0.1524)
		(layer "F.Cu")
		(net 6)
	)
	(segment
		(start 166.412 67.7)
		(end 166.662 67.45)
		(width 0.1524)
		(layer "F.Cu")
		(net 6)
	)
	(segment
		(start 103.2 62.2)
		(end 101.1 62.2)
		(width 0.15)
		(layer "F.Cu")
		(net 7)
	)
	(segment
		(start 104.725 61.075)
		(end 104.725 62.575)
		(width 0.4)
		(layer "F.Cu")
		(net 7)
	)
	(segment
		(start 100.775 62.525)
		(end 100.775 65.74)
		(width 0.15)
		(layer "F.Cu")
		(net 7)
	)
	(segment
		(start 101.1 62.2)
		(end 100.775 62.525)
		(width 0.15)
		(layer "F.Cu")
		(net 7)
	)
	(segment
		(start 112.225 62.5)
		(end 110.5 62.5)
		(width 0.15)
		(layer "F.Cu")
		(net 8)
	)
	(segment
		(start 110.2 62.2)
		(end 109.9 62.2)
		(width 0.15)
		(layer "F.Cu")
		(net 8)
	)
	(segment
		(start 112.525 62.8)
		(end 112.225 62.5)
		(width 0.15)
		(layer "F.Cu")
		(net 8)
	)
	(segment
		(start 110.5 62.5)
		(end 110.2 62.2)
		(width 0.15)
		(layer "F.Cu")
		(net 8)
	)
	(segment
		(start 112.525 65.14)
		(end 112.525 62.8)
		(width 0.15)
		(layer "F.Cu")
		(net 8)
	)
	(segment
		(start 110.4875 72.755)
		(end 110.4875 71.6375)
		(width 0.15)
		(layer "F.Cu")
		(net 9)
	)
	(segment
		(start 102.8025 72.725)
		(end 102.8025 71.7525)
		(width 0.15)
		(layer "F.Cu")
		(net 10)
	)
	(segment
		(start 102.8025 71.7525)
		(end 102.8 71.75)
		(width 0.15)
		(layer "F.Cu")
		(net 10)
	)
	(segment
		(start 160.775 67.28)
		(end 160.86 67.365)
		(width 0.2)
		(layer "F.Cu")
		(net 11)
	)
	(segment
		(start 161.575 64.35)
		(end 160.99 64.35)
		(width 0.2)
		(layer "F.Cu")
		(net 11)
	)
	(segment
		(start 160.99 64.35)
		(end 160.775 64.565)
		(width 0.2)
		(layer "F.Cu")
		(net 11)
	)
	(segment
		(start 160.775 64.565)
		(end 160.775 67.28)
		(width 0.2)
		(layer "F.Cu")
		(net 11)
	)
	(via
		(at 161.675 69.15)
		(size 0.4)
		(drill 0.15)
		(layers "F.Cu" "B.Cu")
		(free yes)
		(net 11)
	)
	(via
		(at 161.675 69.75)
		(size 0.4)
		(drill 0.15)
		(layers "F.Cu" "B.Cu")
		(free yes)
		(net 11)
	)
	(via
		(at 163.875 67.45)
		(size 0.4)
		(drill 0.15)
		(layers "F.Cu" "B.Cu")
		(free yes)
		(net 11)
	)
	(via
		(at 164.375 67.45)
		(size 0.4)
		(drill 0.15)
		(layers "F.Cu" "B.Cu")
		(free yes)
		(net 11)
	)
	(via
		(at 162.175 69.75)
		(size 0.4)
		(drill 0.15)
		(layers "F.Cu" "B.Cu")
		(free yes)
		(net 11)
	)
	(via
		(at 164.375 67.95)
		(size 0.4)
		(drill 0.15)
		(layers "F.Cu" "B.Cu")
		(free yes)
		(net 11)
	)
	(via
		(at 164.375 68.55)
		(size 0.4)
		(drill 0.15)
		(layers "F.Cu" "B.Cu")
		(free yes)
		(net 11)
	)
	(via
		(at 162.175 69.15)
		(size 0.4)
		(drill 0.15)
		(layers "F.Cu" "B.Cu")
		(free yes)
		(net 11)
	)
	(via
		(at 163.875 67.95)
		(size 0.4)
		(drill 0.15)
		(layers "F.Cu" "B.Cu")
		(free yes)
		(net 11)
	)
	(via
		(at 163.875 68.55)
		(size 0.4)
		(drill 0.15)
		(layers "F.Cu" "B.Cu")
		(free yes)
		(net 11)
	)
	(segment
		(start 143.55 78.4)
		(end 144.134 78.4)
		(width 0.3)
		(layer "F.Cu")
		(net 12)
	)
	(segment
		(start 142.65 81.6)
		(end 142.9 81.6)
		(width 0.3)
		(layer "F.Cu")
		(net 12)
	)
	(segment
		(start 127.775 78.4)
		(end 128.475 78.4)
		(width 0.3)
		(layer "F.Cu")
		(net 12)
	)
	(segment
		(start 125.741 81.6)
		(end 125.575 81.434)
		(width 0.3)
		(layer "F.Cu")
		(net 12)
	)
	(segment
		(start 125.6 78.466)
		(end 125.6 78.575)
		(width 0.3)
		(layer "F.Cu")
		(net 12)
	)
	(segment
		(start 142.65 81.6)
		(end 142.775 81.6)
		(width 0.3)
		(layer "F.Cu")
		(net 12)
	)
	(segment
		(start 141.775 78.4)
		(end 141.075 78.4)
		(width 0.3)
		(layer "F.Cu")
		(net 12)
	)
	(segment
		(start 111.325 61.1)
		(end 111.3 61.075)
		(width 0.3)
		(layer "F.Cu")
		(net 12)
	)
	(segment
		(start 144.109 81.6)
		(end 144.225 81.484)
		(width 0.3)
		(layer "F.Cu")
		(net 12)
	)
	(segment
		(start 141.775 81.6)
		(end 142.65 81.6)
		(width 0.3)
		(layer "F.Cu")
		(net 12)
	)
	(segment
		(start 136.875 84.8)
		(end 136.175 84.8)
		(width 0.3)
		(layer "F.Cu")
		(net 12)
	)
	(segment
		(start 125.666 78.4)
		(end 125.6 78.466)
		(width 0.3)
		(layer "F.Cu")
		(net 12)
	)
	(segment
		(start 127.775 78.4)
		(end 126.05 78.4)
		(width 0.3)
		(layer "F.Cu")
		(net 12)
	)
	(segment
		(start 136.875 75.2)
		(end 136.175 75.2)
		(width 0.3)
		(layer "F.Cu")
		(net 12)
	)
	(segment
		(start 144.134 78.4)
		(end 144.25 78.516)
		(width 0.3)
		(layer "F.Cu")
		(net 12)
	)
	(segment
		(start 143 78.4)
		(end 143.55 78.4)
		(width 0.3)
		(layer "F.Cu")
		(net 12)
	)
	(segment
		(start 132.675 84.8)
		(end 133.375 84.8)
		(width 0.3)
		(layer "F.Cu")
		(net 12)
	)
	(segment
		(start 112.2 61.1)
		(end 111.325 61.1)
		(width 0.3)
		(layer "F.Cu")
		(net 12)
	)
	(segment
		(start 132.675 75.2)
		(end 133.375 75.2)
		(width 0.3)
		(layer "F.Cu")
		(net 12)
	)
	(segment
		(start 141.775 81.6)
		(end 141.075 81.6)
		(width 0.3)
		(layer "F.Cu")
		(net 12)
	)
	(segment
		(start 125.6 78.575)
		(end 125.875 78.85)
		(width 0.3)
		(layer "F.Cu")
		(net 12)
	)
	(segment
		(start 127.775 81.6)
		(end 125.741 81.6)
		(width 0.3)
		(layer "F.Cu")
		(net 12)
	)
	(segment
		(start 142.9 81.6)
		(end 143.7 81.6)
		(width 0.3)
		(layer "F.Cu")
		(net 12)
	)
	(segment
		(start 142.825 78.4)
		(end 143 78.4)
		(width 0.3)
		(layer "F.Cu")
		(net 12)
	)
	(segment
		(start 126.05 78.4)
		(end 125.666 78.4)
		(width 0.3)
		(layer "F.Cu")
		(net 12)
	)
	(segment
		(start 127.775 81.6)
		(end 128.475 81.6)
		(width 0.3)
		(layer "F.Cu")
		(net 12)
	)
	(segment
		(start 143.7 81.6)
		(end 144.109 81.6)
		(width 0.3)
		(layer "F.Cu")
		(net 12)
	)
	(segment
		(start 141.775 78.4)
		(end 142.825 78.4)
		(width 0.3)
		(layer "F.Cu")
		(net 12)
	)
	(via
		(at 128.475 78.4)
		(size 0.4)
		(drill 0.2)
		(layers "F.Cu" "B.Cu")
		(net 12)
	)
	(via
		(at 136.175 84.8)
		(size 0.4)
		(drill 0.2)
		(layers "F.Cu" "B.Cu")
		(net 12)
	)
	(via
		(at 133.375 75.2)
		(size 0.4)
		(drill 0.2)
		(layers "F.Cu" "B.Cu")
		(net 12)
	)
	(via
		(at 136.175 75.2)
		(size 0.4)
		(drill 0.15)
		(layers "F.Cu" "B.Cu")
		(net 12)
	)
	(via
		(at 132.675 75.2)
		(size 0.4)
		(drill 0.15)
		(layers "F.Cu" "B.Cu")
		(net 12)
	)
	(via
		(at 136.875 75.2)
		(size 0.4)
		(drill 0.15)
		(layers "F.Cu" "B.Cu")
		(net 12)
	)
	(via
		(at 133.375 84.8)
		(size 0.4)
		(drill 0.15)
		(layers "F.Cu" "B.Cu")
		(net 12)
	)
	(via
		(at 125.875 78.85)
		(size 0.4)
		(drill 0.2)
		(layers "F.Cu" "B.Cu")
		(net 12)
	)
	(via
		(at 112.2 61.1)
		(size 0.4)
		(drill 0.15)
		(layers "F.Cu" "B.Cu")
		(net 12)
	)
	(via
		(at 141.075 78.4)
		(size 0.4)
		(drill 0.2)
		(layers "F.Cu" "B.Cu")
		(net 12)
	)
	(via
		(at 144.3 78.75)
		(size 0.4)
		(drill 0.2)
		(layers "F.Cu" "B.Cu")
		(net 12)
	)
	(via
		(at 128.475 81.6)
		(size 0.4)
		(drill 0.2)
		(layers "F.Cu" "B.Cu")
		(net 12)
	)
	(via
		(at 144.225 81.484)
		(size 0.4)
		(drill 0.2)
		(layers "F.Cu" "B.Cu")
		(net 12)
	)
	(via
		(at 141.075 81.6)
		(size 0.4)
		(drill 0.2)
		(layers "F.Cu" "B.Cu")
		(net 12)
	)
	(via
		(at 125.575 81.434)
		(size 0.4)
		(drill 0.2)
		(layers "F.Cu" "B.Cu")
		(net 12)
	)
	(segment
		(start 127.775 79.2)
		(end 128.475 79.2)
		(width 0.2)
		(layer "F.Cu")
		(net 13)
	)
	(via
		(at 127.775 79.2)
		(size 0.4)
		(drill 0.15)
		(layers "F.Cu" "B.Cu")
		(net 13)
	)
	(via
		(at 131.275 81.6)
		(size 0.4)
		(drill 0.15)
		(layers "F.Cu" "B.Cu")
		(net 13)
	)
	(via
		(at 138.275 81.6)
		(size 0.4)
		(drill 0.15)
		(layers "F.Cu" "B.Cu")
		(net 13)
	)
	(via
		(at 134.775 81.6)
		(size 0.4)
		(drill 0.15)
		(layers "F.Cu" "B.Cu")
		(net 13)
	)
	(via
		(at 134.775 78.4)
		(size 0.4)
		(drill 0.15)
		(layers "F.Cu" "B.Cu")
		(net 13)
	)
	(via
		(at 141.775 79.2)
		(size 0.4)
		(drill 0.15)
		(layers "F.Cu" "B.Cu")
		(net 13)
	)
	(via
		(at 131.275 78.4)
		(size 0.4)
		(drill 0.15)
		(layers "F.Cu" "B.Cu")
		(net 13)
	)
	(via
		(at 138.275 78.4)
		(size 0.4)
		(drill 0.15)
		(layers "F.Cu" "B.Cu")
		(net 13)
	)
	(via
		(at 141.775 80.8)
		(size 0.4)
		(drill 0.15)
		(layers "F.Cu" "B.Cu")
		(net 13)
	)
	(via
		(at 127.775 80.8)
		(size 0.4)
		(drill 0.15)
		(layers "F.Cu" "B.Cu")
		(net 13)
	)
	(segment
		(start 127.775 79.2)
		(end 127.459 79.2)
		(width 0.2)
		(layer "B.Cu")
		(net 13)
	)
	(segment
		(start 127.775 80.8)
		(end 127.584 80.8)
		(width 0.2)
		(layer "B.Cu")
		(net 13)
	)
	(segment
		(start 127.725 79.15)
		(end 127.775 79.2)
		(width 0.2)
		(layer "B.Cu")
		(net 13)
	)
	(segment
		(start 141.775 80.8)
		(end 142.091 80.8)
		(width 0.2)
		(layer "B.Cu")
		(net 13)
	)
	(segment
		(start 141.775 79.2)
		(end 142.091 79.2)
		(width 0.2)
		(layer "B.Cu")
		(net 13)
	)
	(segment
		(start 127.459 79.15)
		(end 127.725 79.15)
		(width 0.2)
		(layer "B.Cu")
		(net 13)
	)
	(segment
		(start 103.55 96.975)
		(end 103.425 97.1)
		(width 0.2)
		(layer "F.Cu")
		(net 14)
	)
	(segment
		(start 136.875 81.6)
		(end 136.175 81.6)
		(width 0.4)
		(layer "F.Cu")
		(net 14)
	)
	(segment
		(start 166.025 96.975)
		(end 165.9 97.1)
		(width 0.2)
		(layer "F.Cu")
		(net 14)
	)
	(segment
		(start 129.875 80.8)
		(end 129.875 81.6)
		(width 0.2)
		(layer "F.Cu")
		(net 14)
	)
	(segment
		(start 130.525 96.975)
		(end 130.4 97.1)
		(width 0.2)
		(layer "F.Cu")
		(net 14)
	)
	(segment
		(start 119.8 96.975)
		(end 119.925 97.1)
		(width 0.2)
		(layer "F.Cu")
		(net 14)
	)
	(segment
		(start 128.9 97.1)
		(end 128.9 98.625)
		(width 0.2)
		(layer "F.Cu")
		(net 14)
	)
	(segment
		(start 104.55 96.975)
		(end 104.425 97.1)
		(width 0.2)
		(layer "F.Cu")
		(net 14)
	)
	(segment
		(start 124.425 97.1)
		(end 124.425 98.625)
		(width 0.2)
		(layer "F.Cu")
		(net 14)
	)
	(segment
		(start 118.8 96.975)
		(end 118.925 97.1)
		(width 0.2)
		(layer "F.Cu")
		(net 14)
	)
	(segment
		(start 108.3 96.975)
		(end 108.425 97.1)
		(width 0.2)
		(layer "F.Cu")
		(net 14)
	)
	(segment
		(start 133.175 73.2)
		(end 133.191 73.184)
		(width 0.3)
		(layer "F.Cu")
		(net 14)
	)
	(segment
		(start 109.425 97.1)
		(end 109.425 98.625)
		(width 0.2)
		(layer "F.Cu")
		(net 14)
	)
	(segment
		(start 159.525 96.975)
		(end 159.4 97.1)
		(width 0.2)
		(layer "F.Cu")
		(net 14)
	)
	(segment
		(start 109.3 96.975)
		(end 109.425 97.1)
		(width 0.2)
		(layer "F.Cu")
		(net 14)
	)
	(segment
		(start 122.425 97.1)
		(end 122.425 98.625)
		(width 0.2)
		(layer "F.Cu")
		(net 14)
	)
	(segment
		(start 153.775 96.975)
		(end 153.9 97.1)
		(width 0.2)
		(layer "F.Cu")
		(net 14)
	)
	(segment
		(start 124.55 96.975)
		(end 124.425 97.1)
		(width 0.2)
		(layer "F.Cu")
		(net 14)
	)
	(segment
		(start 115.925 97.1)
		(end 115.925 98.625)
		(width 0.2)
		(layer "F.Cu")
		(net 14)
	)
	(segment
		(start 136.359 87.559)
		(end 136.359 88.275)
		(width 0.3)
		(layer "F.Cu")
		(net 14)
	)
	(segment
		(start 142.4875 94.25)
		(end 140.7125 94.25)
		(width 0.2)
		(layer "F.Cu")
		(net 14)
	)
	(segment
		(start 132.16 72.275)
		(end 133.191 72.275)
		(width 0.3)
		(layer "F.Cu")
		(net 14)
	)
	(segment
		(start 117.8 96.975)
		(end 117.925 97.1)
		(width 0.2)
		(layer "F.Cu")
		(net 14)
	)
	(segment
		(start 126.4 98.625)
		(end 126.4 97)
		(width 0.2)
		(layer "F.Cu")
		(net 14)
	)
	(segment
		(start 111.925 97.1)
		(end 111.925 98.625)
		(width 0.2)
		(layer "F.Cu")
		(net 14)
	)
	(segment
		(start 148.025 96.975)
		(end 147.9 97.1)
		(width 0.2)
		(layer "F.Cu")
		(net 14)
	)
	(segment
		(start 102.8025 73.725)
		(end 102.8025 74.3975)
		(width 0.15)
		(layer "F.Cu")
		(net 14)
	)
	(segment
		(start 134.9 97.15)
		(end 134.75 97)
		(width 0.2)
		(layer "F.Cu")
		(net 14)
	)
	(segment
		(start 119.925 97.1)
		(end 119.925 98.625)
		(width 0.2)
		(layer "F.Cu")
		(net 14)
	)
	(segment
		(start 158.4 97.1)
		(end 158.4 98.625)
		(width 0.2)
		(layer "F.Cu")
		(net 14)
	)
	(segment
		(start 114.925 97.1)
		(end 114.925 98.625)
		(width 0.2)
		(layer "F.Cu")
		(net 14)
	)
	(segment
		(start 161.275 96.975)
		(end 161.4 97.1)
		(width 0.2)
		(layer "F.Cu")
		(net 14)
	)
	(segment
		(start 117.925 97.1)
		(end 117.925 98.625)
		(width 0.2)
		(layer "F.Cu")
		(net 14)
	)
	(segment
		(start 120.8 96.975)
		(end 120.925 97.1)
		(width 0.2)
		(layer "F.Cu")
		(net 14)
	)
	(segment
		(start 142.4 97.1)
		(end 142.4 98.625)
		(width 0.2)
		(layer "F.Cu")
		(net 14)
	)
	(segment
		(start 136.525 96.975)
		(end 136.4 97.1)
		(width 0.2)
		(layer "F.Cu")
		(net 14)
	)
	(segment
		(start 120.925 97.1)
		(end 120.925 98.625)
		(width 0.2)
		(layer "F.Cu")
		(net 14)
	)
	(segment
		(start 129.025 96.975)
		(end 128.9 97.1)
		(width 0.2)
		(layer "F.Cu")
		(net 14)
	)
	(segment
		(start 108.425 97.1)
		(end 108.425 98.625)
		(width 0.2)
		(layer "F.Cu")
		(net 14)
	)
	(segment
		(start 129.875 78.4)
		(end 129.875 79.2)
		(width 0.2)
		(layer "F.Cu")
		(net 14)
	)
	(segment
		(start 144.4 97.1)
		(end 144.4 98.625)
		(width 0.2)
		(layer "F.Cu")
		(net 14)
	)
	(segment
		(start 168.025 96.975)
		(end 167.9 97.1)
		(width 0.2)
		(layer "F.Cu")
		(net 14)
	)
	(segment
		(start 125.4 97.1)
		(end 125.4 98.625)
		(width 0.2)
		(layer "F.Cu")
		(net 14)
	)
	(segment
		(start 150.9 97.1)
		(end 150.9 98.625)
		(width 0.2)
		(layer "F.Cu")
		(net 14)
	)
	(segment
		(start 136.359 72.55)
		(end 136.359 73.166)
		(width 0.3)
		(layer "F.Cu")
		(net 14)
	)
	(segment
		(start 146.9 97.1)
		(end 146.9 98.625)
		(width 0.2)
		(layer "F.Cu")
		(net 14)
	)
	(segment
		(start 160.4 98.625)
		(end 160.4 97)
		(width 0.2)
		(layer "F.Cu")
		(net 14)
	)
	(segment
		(start 140.9 97.1)
		(end 140.9 98.625)
		(width 0.2)
		(layer "F.Cu")
		(net 14)
	)
	(segment
		(start 162.275 96.975)
		(end 162.4 97.1)
		(width 0.2)
		(layer "F.Cu")
		(net 14)
	)
	(segment
		(start 147.025 96.975)
		(end 146.9 97.1)
		(width 0.2)
		(layer "F.Cu")
		(net 14)
	)
	(segment
		(start 150.775 96.975)
		(end 150.9 97.1)
		(width 0.2)
		(layer "F.Cu")
		(net 14)
	)
	(segment
		(start 134.075 80)
		(end 132.675 80)
		(width 0.4)
		(layer "F.Cu")
		(net 14)
	)
	(segment
		(start 144.275 96.975)
		(end 144.4 97.1)
		(width 0.2)
		(layer "F.Cu")
		(net 14)
	)
	(segment
		(start 108.2625 70.9875)
		(end 108.2625 71.85)
		(width 0.182)
		(layer "F.Cu")
		(net 14)
	)
	(segment
		(start 127.275 96.975)
		(end 127.4 97.1)
		(width 0.2)
		(layer "F.Cu")
		(net 14)
	)
	(segment
		(start 104.425 97.1)
		(end 104.425 98.625)
		(width 0.2)
		(layer "F.Cu")
		(net 14)
	)
	(segment
		(start 123.425 97.1)
		(end 123.425 98.625)
		(width 0.2)
		(layer "F.Cu")
		(net 14)
	)
	(segment
		(start 110.425 97.1)
		(end 110.425 98.625)
		(width 0.2)
		(layer "F.Cu")
		(net 14)
	)
	(segment
		(start 134.075 80.8)
		(end 133.375 80.8)
		(width 0.3)
		(layer "F.Cu")
		(net 14)
	)
	(segment
		(start 157.525 96.975)
		(end 157.4 97.1)
		(width 0.2)
		(layer "F.Cu")
		(net 14)
	)
	(segment
		(start 164.275 96.975)
		(end 164.4 97.1)
		(width 0.2)
		(layer "F.Cu")
		(net 14)
	)
	(segment
		(start 108.2625 71.85)
		(end 108.2875 71.875)
		(width 0.182)
		(layer "F.Cu")
		(net 14)
	)
	(segment
		(start 116.05 96.975)
		(end 115.925 97.1)
		(width 0.2)
		(layer "F.Cu")
		(net 14)
	)
	(segment
		(start 163.4 97.1)
		(end 163.4 98.625)
		(width 0.2)
		(layer "F.Cu")
		(net 14)
	)
	(segment
		(start 105.425 97.1)
		(end 105.425 98.625)
		(width 0.2)
		(layer "F.Cu")
		(net 14)
	)
	(segment
		(start 116.925 98.625)
		(end 116.925 97)
		(width 0.2)
		(layer "F.Cu")
		(net 14)
	)
	(segment
		(start 158.525 96.975)
		(end 158.4 97.1)
		(width 0.2)
		(layer "F.Cu")
		(net 14)
	)
	(segment
		(start 163.275 96.975)
		(end 163.4 97.1)
		(width 0.2)
		(layer "F.Cu")
		(net 14)
	)
	(segment
		(start 102.8025 74.3975)
		(end 102.8 74.4)
		(width 0.15)
		(layer "F.Cu")
		(net 14)
	)
	(segment
		(start 131.275 80)
		(end 130.575 80)
		(width 0.2)
		(layer "F.Cu")
		(net 14)
	)
	(segment
		(start 159.4 97.1)
		(end 159.4 98.625)
		(width 0.2)
		(layer "F.Cu")
		(net 14)
	)
	(segment
		(start 138.025 96.975)
		(end 137.9 97.1)
		(width 0.2)
		(layer "F.Cu")
		(net 14)
	)
	(segment
		(start 149.9 98.625)
		(end 149.9 97)
		(width 0.2)
		(layer "F.Cu")
		(net 14)
	)
	(segment
		(start 127.4 97.1)
		(end 127.4 98.625)
		(width 0.2)
		(layer "F.Cu")
		(net 14)
	)
	(segment
		(start 153.9 97.1)
		(end 153.9 98.625)
		(width 0.2)
		(layer "F.Cu")
		(net 14)
	)
	(segment
		(start 131.9 97.1)
		(end 131.9 98.625)
		(width 0.2)
		(layer "F.Cu")
		(net 14)
	)
	(segment
		(start 141.025 96.975)
		(end 140.9 97.1)
		(width 0.2)
		(layer "F.Cu")
		(net 14)
	)
	(segment
		(start 166.9 97.1)
		(end 166.9 98.625)
		(width 0.2)
		(layer "F.Cu")
		(net 14)
	)
	(segment
		(start 115.05 96.975)
		(end 114.925 97.1)
		(width 0.2)
		(layer "F.Cu")
		(net 14)
	)
	(segment
		(start 113.925 97.1)
		(end 113.925 98.625)
		(width 0.2)
		(layer "F.Cu")
		(net 14)
	)
	(segment
		(start 156.525 96.975)
		(end 156.4 97.1)
		(width 0.2)
		(layer "F.Cu")
		(net 14)
	)
	(segment
		(start 145.0875 94.3875)
		(end 145.6 94.9)
		(width 0.2)
		(layer "F.Cu")
		(net 14)
	)
	(segment
		(start 106.425 98.625)
		(end 106.425 97)
		(width 0.2)
		(layer "F.Cu")
		(net 14)
	)
	(segment
		(start 139.525 96.975)
		(end 139.4 97.1)
		(width 0.2)
		(layer "F.Cu")
		(net 14)
	)
	(segment
		(start 140.7125 94.25)
		(end 140.7125 94.6875)
		(width 0.2)
		(layer "F.Cu")
		(net 14)
	)
	(segment
		(start 133.225 86.975)
		(end 133.225 88.241)
		(width 0.3)
		(layer "F.Cu")
		(net 14)
	)
	(segment
		(start 132.675 84)
		(end 133.375 84)
		(width 0.3)
		(layer "F.Cu")
		(net 14)
	)
	(segment
		(start 151.9 97.1)
		(end 151.9 98.625)
		(width 0.2)
		(layer "F.Cu")
		(net 14)
	)
	(segment
		(start 123.55 96.975)
		(end 123.425 97.1)
		(width 0.2)
		(layer "F.Cu")
		(net 14)
	)
	(segment
		(start 136.875 83.2)
		(end 136.175 83.2)
		(width 0.3)
		(layer "F.Cu")
		(net 14)
	)
	(segment
		(start 110.4875 74.3875)
		(end 110.4875 73.75)
		(width 0.09)
		(layer "F.Cu")
		(net 14)
	)
	(segment
		(start 103.425 97.1)
		(end 103.425 98.625)
		(width 0.2)
		(layer "F.Cu")
		(net 14)
	)
	(segment
		(start 137.9 97.1)
		(end 137.9 98.625)
		(width 0.2)
		(layer "F.Cu")
		(net 14)
	)
	(segment
		(start 165.9 97.1)
		(end 165.9 98.625)
		(width 0.2)
		(layer "F.Cu")
		(net 14)
	)
	(segment
		(start 114.05 96.975)
		(end 113.925 97.1)
		(width 0.2)
		(layer "F.Cu")
		(net 14)
	)
	(segment
		(start 141.075 80)
		(end 141.075 79.95)
		(width 0.1)
		(layer "F.Cu")
		(net 14)
	)
	(segment
		(start 149.025 96.975)
		(end 148.9 97.1)
		(width 0.2)
		(layer "F.Cu")
		(net 14)
	)
	(segment
		(start 134.9 98.625)
		(end 134.9 97.15)
		(width 0.2)
		(layer "F.Cu")
		(net 14)
	)
	(segment
		(start 118.925 97.1)
		(end 118.925 98.625)
		(width 0.2)
		(layer "F.Cu")
		(net 14)
	)
	(segment
		(start 128.475 80)
		(end 129.175 80)
		(width 0.2)
		(layer "F.Cu")
		(net 14)
	)
	(segment
		(start 141.075 79.95)
		(end 140.725 79.6)
		(width 0.1)
		(layer "F.Cu")
		(net 14)
	)
	(segment
		(start 147.9 97.1)
		(end 147.9 98.625)
		(width 0.2)
		(layer "F.Cu")
		(net 14)
	)
	(segment
		(start 161.4 97.1)
		(end 161.4 98.625)
		(width 0.2)
		(layer "F.Cu")
		(net 14)
	)
	(segment
		(start 112.05 96.975)
		(end 111.925 97.1)
		(width 0.2)
		(layer "F.Cu")
		(net 14)
	)
	(segment
		(start 143.3125 94.25)
		(end 145.0875 94.25)
		(width 0.2)
		(layer "F.Cu")
		(net 14)
	)
	(segment
		(start 112.925 97.1)
		(end 112.925 98.625)
		(width 0.2)
		(layer "F.Cu")
		(net 14)
	)
	(segment
		(start 113.05 96.975)
		(end 112.925 97.1)
		(width 0.2)
		(layer "F.Cu")
		(net 14)
	)
	(segment
		(start 130.4 97.1)
		(end 130.4 98.625)
		(width 0.2)
		(layer "F.Cu")
		(net 14)
	)
	(segment
		(start 132.025 96.975)
		(end 131.9 97.1)
		(width 0.2)
		(layer "F.Cu")
		(net 14)
	)
	(segment
		(start 156.4 97.1)
		(end 156.4 98.625)
		(width 0.2)
		(layer "F.Cu")
		(net 14)
	)
	(segment
		(start 145.0875 94.25)
		(end 145.0875 94.3875)
		(width 0.2)
		(layer "F.Cu")
		(net 14)
	)
	(segment
		(start 136.4 97.1)
		(end 136.4 98.625)
		(width 0.2)
		(layer "F.Cu")
		(net 14)
	)
	(segment
		(start 107.425 97.1)
		(end 107.425 98.625)
		(width 0.2)
		(layer "F.Cu")
		(net 14)
	)
	(segment
		(start 155.4 97.1)
		(end 155.4 98.625)
		(width 0.2)
		(layer "F.Cu")
		(net 14)
	)
	(segment
		(start 140.7125 94.6875)
		(end 140.35 95.05)
		(width 0.2)
		(layer "F.Cu")
		(net 14)
	)
	(segment
		(start 136.359 73.166)
		(end 136.35 73.175)
		(width 0.3)
		(layer "F.Cu")
		(net 14)
	)
	(segment
		(start 107.3 96.975)
		(end 107.425 97.1)
		(width 0.2)
		(layer "F.Cu")
		(net 14)
	)
	(segment
		(start 151.775 96.975)
		(end 151.9 97.1)
		(width 0.2)
		(layer "F.Cu")
		(net 14)
	)
	(segment
		(start 133.191 73.184)
		(end 133.191 72.275)
		(width 0.3)
		(layer "F.Cu")
		(net 14)
	)
	(segment
		(start 164.4 97.1)
		(end 164.4 98.625)
		(width 0.2)
		(layer "F.Cu")
		(net 14)
	)
	(segment
		(start 155.525 96.975)
		(end 155.4 97.1)
		(width 0.2)
		(layer "F.Cu")
		(net 14)
	)
	(segment
		(start 110.3 96.975)
		(end 110.425 97.1)
		(width 0.2)
		(layer "F.Cu")
		(net 14)
	)
	(segment
		(start 133.225 88.241)
		(end 133.191 88.275)
		(width 0.3)
		(layer "F.Cu")
		(net 14)
	)
	(segment
		(start 148.9 97.1)
		(end 148.9 98.625)
		(width 0.2)
		(layer "F.Cu")
		(net 14)
	)
	(segment
		(start 152.775 96.975)
		(end 152.9 97.1)
		(width 0.2)
		(layer "F.Cu")
		(net 14)
	)
	(segment
		(start 152.9 97.1)
		(end 152.9 98.625)
		(width 0.2)
		(layer "F.Cu")
		(net 14)
	)
	(segment
		(start 167.9 97.1)
		(end 167.9 98.625)
		(width 0.2)
		(layer "F.Cu")
		(net 14)
	)
	(segment
		(start 162.4 97.1)
		(end 162.4 98.625)
		(width 0.2)
		(layer "F.Cu")
		(net 14)
	)
	(segment
		(start 105.55 96.975)
		(end 105.425 97.1)
		(width 0.2)
		(layer "F.Cu")
		(net 14)
	)
	(segment
		(start 167.025 96.975)
		(end 166.9 97.1)
		(width 0.2)
		(layer "F.Cu")
		(net 14)
	)
	(segment
		(start 133 86.75)
		(end 133.225 86.975)
		(width 0.3)
		(layer "F.Cu")
		(net 14)
	)
	(segment
		(start 145.9 97.1)
		(end 145.9 98.625)
		(width 0.2)
		(layer "F.Cu")
		(net 14)
	)
	(segment
		(start 122.55 96.975)
		(end 122.425 97.1)
		(width 0.2)
		(layer "F.Cu")
		(net 14)
	)
	(segment
		(start 157.4 97.1)
		(end 157.4 98.625)
		(width 0.2)
		(layer "F.Cu")
		(net 14)
	)
	(segment
		(start 139.4 97.1)
		(end 139.4 98.625)
		(width 0.2)
		(layer "F.Cu")
		(net 14)
	)
	(via
		(at 129.175 80)
		(size 0.4)
		(drill 0.15)
		(layers "F.Cu" "B.Cu")
		(net 14)
	)
	(via
		(at 166.575 71.75)
		(size 0.4)
		(drill 0.15)
		(layers "F.Cu" "B.Cu")
		(free yes)
		(net 14)
	)
	(via
		(at 138.975 80)
		(size 0.4)
		(drill 0.15)
		(layers "F.Cu" "B.Cu")
		(net 14)
	)
	(via
		(at 131.975 79.2)
		(size 0.4)
		(drill 0.15)
		(layers "F.Cu" "B.Cu")
		(net 14)
	)
	(via
		(at 110.775 66.925)
		(size 0.45)
		(drill 0.2)
		(layers "F.Cu" "B.Cu")
		(net 14)
	)
	(via
		(at 117.5 66.5)
		(size 0.4)
		(drill 0.15)
		(layers "F.Cu" "B.Cu")
		(net 14)
	)
	(via
		(at 130.575 74.4)
		(size 0.4)
		(drill 0.15)
		(layers "F.Cu" "B.Cu")
		(net 14)
	)
	(via
		(at 134.075 79.2)
		(size 0.4)
		(drill 0.15)
		(layers "F.Cu" "B.Cu")
		(net 14)
	)
	(via
		(at 126.6 75.6)
		(size 0.4)
		(drill 0.2)
		(layers "F.Cu" "B.Cu")
		(free yes)
		(net 14)
	)
	(via
		(at 112.05 96.975)
		(size 0.4)
		(drill 0.15)
		(layers "F.Cu" "B.Cu")
		(net 14)
	)
	(via
		(at 135.475 80.8)
		(size 0.4)
		(drill 0.15)
		(layers "F.Cu" "B.Cu")
		(net 14)
	)
	(via
		(at 134.45 91.85)
		(size 0.4)
		(drill 0.2)
		(layers "F.Cu" "B.Cu")
		(net 14)
	)
	(via
		(at 108.2875 71.875)
		(size 0.45)
		(drill 0.2)
		(layers "F.Cu" "B.Cu")
		(net 14)
	)
	(via
		(at 106.425 97)
		(size 0.4)
		(drill 0.15)
		(layers "F.Cu" "B.Cu")
		(net 14)
	)
	(via
		(at 133 86.75)
		(size 0.4)
		(drill 0.15)
		(layers "F.Cu" "B.Cu")
		(net 14)
	)
	(via
		(at 130.575 85.6)
		(size 0.4)
		(drill 0.15)
		(layers "F.Cu" "B.Cu")
		(net 14)
	)
	(via
		(at 110.4875 74.3875)
		(size 0.4)
		(drill 0.15)
		(layers "F.Cu" "B.Cu")
		(net 14)
	)
	(via
		(at 134.775 84)
		(size 0.4)
		(drill 0.15)
		(layers "F.Cu" "B.Cu")
		(net 14)
	)
	(via
		(at 139.1 94.35)
		(size 0.4)
		(drill 0.2)
		(layers "F.Cu" "B.Cu")
		(net 14)
	)
	(via
		(at 129.875 81.6)
		(size 0.4)
		(drill 0.15)
		(layers "F.Cu" "B.Cu")
		(net 14)
	)
	(via
		(at 110.0495 89.6)
		(size 0.4)
		(drill 0.2)
		(layers "F.Cu" "B.Cu")
		(net 14)
	)
	(via
		(at 133.375 76)
		(size 0.4)
		(drill 0.15)
		(layers "F.Cu" "B.Cu")
		(net 14)
	)
	(via
		(at 110.475 63.825)
		(size 0.45)
		(drill 0.2)
		(layers "F.Cu" "B.Cu")
		(net 14)
	)
	(via
		(at 134.075 80.8)
		(size 0.4)
		(drill 0.15)
		(layers "F.Cu" "B.Cu")
		(net 14)
	)
	(via
		(at 126.6 85)
		(size 0.4)
		(drill 0.2)
		(layers "F.Cu" "B.Cu")
		(free yes)
		(net 14)
	)
	(via
		(at 125.6 79.434)
		(size 0.4)
		(drill 0.2)
		(layers "F.Cu" "B.Cu")
		(net 14)
	)
	(via
		(at 138.975 74.4)
		(size 0.4)
		(drill 0.15)
		(layers "F.Cu" "B.Cu")
		(net 14)
	)
	(via
		(at 161.15 71.75)
		(size 0.4)
		(drill 0.15)
		(layers "F.Cu" "B.Cu")
		(free yes)
		(net 14)
	)
	(via
		(at 113.05 96.975)
		(size 0.4)
		(drill 0.15)
		(layers "F.Cu" "B.Cu")
		(net 14)
	)
	(via
		(at 135.475 80)
		(size 0.4)
		(drill 0.15)
		(layers "F.Cu" "B.Cu")
		(net 14)
	)
	(via
		(at 136.875 81.6)
		(size 0.4)
		(drill 0.15)
		(layers "F.Cu" "B.Cu")
		(net 14)
	)
	(via
		(at 105.5875 69.025)
		(size 0.45)
		(drill 0.2)
		(layers "F.Cu" "B.Cu")
		(net 14)
	)
	(via
		(at 105.5875 67.85)
		(size 0.45)
		(drill 0.2)
		(layers "F.Cu" "B.Cu")
		(net 14)
	)
	(via
		(at 102.475 68.125)
		(size 0.45)
		(drill 0.2)
		(layers "F.Cu" "B.Cu")
		(net 14)
	)
	(via
		(at 139.675 78.4)
		(size 0.4)
		(drill 0.15)
		(layers "F.Cu" "B.Cu")
		(net 14)
	)
	(via
		(at 138.975 84)
		(size 0.4)
		(drill 0.15)
		(layers "F.Cu" "B.Cu")
		(net 14)
	)
	(via
		(at 131.975 80.8)
		(size 0.4)
		(drill 0.15)
		(layers "F.Cu" "B.Cu")
		(net 14)
	)
	(via
		(at 110.3 96.975)
		(size 0.4)
		(drill 0.15)
		(layers "F.Cu" "B.Cu")
		(net 14)
	)
	(via
		(at 139.675 81.6)
		(size 0.4)
		(drill 0.15)
		(layers "F.Cu" "B.Cu")
		(net 14)
	)
	(via
		(at 120.725 95.1245)
		(size 0.4)
		(drill 0.15)
		(layers "F.Cu" "B.Cu")
		(net 14)
	)
	(via
		(at 129.875 75.2)
		(size 0.4)
		(drill 0.15)
		(layers "F.Cu" "B.Cu")
		(net 14)
	)
	(via
		(at 136.875 83.2)
		(size 0.4)
		(drill 0.15)
		(layers "F.Cu" "B.Cu")
		(net 14)
	)
	(via
		(at 107.25 80.7)
		(size 0.4)
		(drill 0.15)
		(layers "F.Cu" "B.Cu")
		(net 14)
	)
	(via
		(at 143 85)
		(size 0.4)
		(drill 0.2)
		(layers "F.Cu" "B.Cu")
		(free yes)
		(net 14)
	)
	(via
		(at 104.4 74.6)
		(size 0.45)
		(drill 0.2)
		(layers "F.Cu" "B.Cu")
		(free yes)
		(net 14)
	)
	(via
		(at 142.75 79.17)
		(size 0.4)
		(drill 0.2)
		(layers "F.Cu" "B.Cu")
		(free yes)
		(net 14)
	)
	(via
		(at 141.775 82.4)
		(size 0.4)
		(drill 0.15)
		(layers "F.Cu" "B.Cu")
		(net 14)
	)
	(via
		(at 136.525 96.975)
		(size 0.4)
		(drill 0.15)
		(layers "F.Cu" "B.Cu")
		(net 14)
	)
	(via
		(at 112.398099 86.71)
		(size 0.4)
		(drill 0.2)
		(layers "F.Cu" "B.Cu")
		(free yes)
		(net 14)
	)
	(via
		(at 134.775 76.8)
		(size 0.4)
		(drill 0.15)
		(layers "F.Cu" "B.Cu")
		(net 14)
	)
	(via
		(at 158.95 92.69)
		(size 0.4)
		(drill 0.2)
		(layers "F.Cu" "B.Cu")
		(free yes)
		(net 14)
	)
	(via
		(at 140.375 82.4)
		(size 0.4)
		(drill 0.15)
		(layers "F.Cu" "B.Cu")
		(net 14)
	)
	(via
		(at 121.8 61.5)
		(size 0.4)
		(drill 0.15)
		(layers "F.Cu" "B.Cu")
		(net 14)
	)
	(via
		(at 136.875 76)
		(size 0.4)
		(drill 0.15)
		(layers "F.Cu" "B.Cu")
		(net 14)
	)
	(via
		(at 129.025 96.975)
		(size 0.4)
		(drill 0.15)
		(layers "F.Cu" "B.Cu")
		(net 14)
	)
	(via
		(at 102.675 65.625)
		(size 0.45)
		(drill 0.2)
		(layers "F.Cu" "B.Cu")
		(free yes)
		(net 14)
	)
	(via
		(at 114.375 94.3)
		(size 0.4)
		(drill 0.15)
		(layers "F.Cu" "B.Cu")
		(net 14)
	)
	(via
		(at 117.8 96.975)
		(size 0.4)
		(drill 0.15)
		(layers "F.Cu" "B.Cu")
		(net 14)
	)
	(via
		(at 111.175 97)
		(size 0.4)
		(drill 0.15)
		(layers "F.Cu" "B.Cu")
		(net 14)
	)
	(via
		(at 102.675 65.025)
		(size 0.45)
		(drill 0.2)
		(layers "F.Cu" "B.Cu")
		(net 14)
	)
	(via
		(at 104.4 75.8)
		(size 0.45)
		(drill 0.2)
		(layers "F.Cu" "B.Cu")
		(free yes)
		(net 14)
	)
	(via
		(at 133.375 84)
		(size 0.4)
		(drill 0.15)
		(layers "F.Cu" "B.Cu")
		(net 14)
	)
	(via
		(at 136.875 78.4)
		(size 0.4)
		(drill 0.15)
		(layers "F.Cu" "B.Cu")
		(net 14)
	)
	(via
		(at 105.68 83.98)
		(size 0.4)
		(drill 0.15)
		(layers "F.Cu" "B.Cu")
		(net 14)
	)
	(via
		(at 134.775 77.6)
		(size 0.4)
		(drill 0.15)
		(layers "F.Cu" "B.Cu")
		(net 14)
	)
	(via
		(at 106.095 68.425)
		(size 0.45)
		(drill 0.2)
		(layers "F.Cu" "B.Cu")
		(net 14)
	)
	(via
		(at 134.775 76)
		(size 0.4)
		(drill 0.15)
		(layers "F.Cu" "B.Cu")
		(net 14)
	)
	(via
		(at 139.4 69.9)
		(size 0.4)
		(drill 0.2)
		(layers "F.Cu" "B.Cu")
		(free yes)
		(net 14)
	)
	(via
		(at 141.075 83.2)
		(size 0.4)
		(drill 0.15)
		(layers "F.Cu" "B.Cu")
		(net 14)
	)
	(via
		(at 128.475 76.8)
		(size 0.4)
		(drill 0.15)
		(layers "F.Cu" "B.Cu")
		(net 14)
	)
	(via
		(at 142.525 96.975)
		(size 0.4)
		(drill 0.15)
		(layers "F.Cu" "B.Cu")
		(net 14)
	)
	(via
		(at 156.9 89.3)
		(size 0.4)
		(drill 0.2)
		(layers "F.Cu" "B.Cu")
		(net 14)
	)
	(via
		(at 166.575 70.25)
		(size 0.4)
		(drill 0.15)
		(layers "F.Cu" "B.Cu")
		(free yes)
		(net 14)
	)
	(via
		(at 102.475 68.725)
		(size 0.45)
		(drill 0.2)
		(layers "F.Cu" "B.Cu")
		(net 14)
	)
	(via
		(at 103.8 75.2)
		(size 0.45)
		(drill 0.2)
		(layers "F.Cu" "B.Cu")
		(free yes)
		(net 14)
	)
	(via
		(at 141.075 76.8)
		(size 0.4)
		(drill 0.15)
		(layers "F.Cu" "B.Cu")
		(net 14)
	)
	(via
		(at 133.175 73.2)
		(size 0.4)
		(drill 0.15)
		(layers "F.Cu" "B.Cu")
		(net 14)
	)
	(via
		(at 161.5255 89.45)
		(size 0.4)
		(drill 0.2)
		(layers "F.Cu" "B.Cu")
		(net 14)
	)
	(via
		(at 131.975 84)
		(size 0.4)
		(drill 0.15)
		(layers "F.Cu" "B.Cu")
		(net 14)
	)
	(via
		(at 110.475 64.425)
		(size 0.45)
		(drill 0.2)
		(layers "F.Cu" "B.Cu")
		(net 14)
	)
	(via
		(at 159.72 91.93)
		(size 0.4)
		(drill 0.2)
		(layers "F.Cu" "B.Cu")
		(free yes)
		(net 14)
	)
	(via
		(at 131.275 84.8)
		(size 0.4)
		(drill 0.15)
		(layers "F.Cu" "B.Cu")
		(net 14)
	)
	(via
		(at 130 67.7)
		(size 0.4)
		(drill 0.2)
		(layers "F.Cu" "B.Cu")
		(free yes)
		(net 14)
	)
	(via
		(at 118.8 96.975)
		(size 0.4)
		(drill 0.15)
		(layers "F.Cu" "B.Cu")
		(net 14)
	)
	(via
		(at 164.275 96.975)
		(size 0.4)
		(drill 0.15)
		(layers "F.Cu" "B.Cu")
		(net 14)
	)
	(via
		(at 103.8 74.6)
		(size 0.45)
		(drill 0.2)
		(layers "F.Cu" "B.Cu")
		(free yes)
		(net 14)
	)
	(via
		(at 133.375 76.8)
		(size 0.4)
		(drill 0.15)
		(layers "F.Cu" "B.Cu")
		(net 14)
	)
	(via
		(at 107.6875 69.025)
		(size 0.45)
		(drill 0.2)
		(layers "F.Cu" "B.Cu")
		(net 14)
	)
	(via
		(at 136.175 80)
		(size 0.4)
		(drill 0.15)
		(layers "F.Cu" "B.Cu")
		(net 14)
	)
	(via
		(at 165.075 67.95)
		(size 0.4)
		(drill 0.15)
		(layers "F.Cu" "B.Cu")
		(free yes)
		(net 14)
	)
	(via
		(at 165.775 71.75)
		(size 0.4)
		(drill 0.15)
		(layers "F.Cu" "B.Cu")
		(free yes)
		(net 14)
	)
	(via
		(at 144.225 80.516)
		(size 0.4)
		(drill 0.2)
		(layers "F.Cu" "B.Cu")
		(net 14)
	)
	(via
		(at 136.175 76)
		(size 0.4)
		(drill 0.15)
		(layers "F.Cu" "B.Cu")
		(net 14)
	)
	(via
		(at 129.175 82.4)
		(size 0.4)
		(drill 0.15)
		(layers "F.Cu" "B.Cu")
		(net 14)
	)
	(via
		(at 136.175 74.4)
		(size 0.4)
		(drill 0.15)
		(layers "F.Cu" "B.Cu")
		(net 14)
	)
	(via
		(at 126.625 80.8)
		(size 0.4)
		(drill 0.2)
		(layers "F.Cu" "B.Cu")
		(net 14)
	)
	(via
		(at 165.775 71.05)
		(size 0.4)
		(drill 0.15)
		(layers "F.Cu" "B.Cu")
		(free yes)
		(net 14)
	)
	(via
		(at 128.475 83.2)
		(size 0.4)
		(drill 0.15)
		(layers "F.Cu" "B.Cu")
		(net 14)
	)
	(via
		(at 167.3745 89.45)
		(size 0.4)
		(drill 0.2)
		(layers "F.Cu" "B.Cu")
		(net 14)
	)
	(via
		(at 105.825 63.525)
		(size 0.45)
		(drill 0.2)
		(layers "F.Cu" "B.Cu")
		(net 14)
	)
	(via
		(at 135.475 79.2)
		(size 0.4)
		(drill 0.15)
		(layers "F.Cu" "B.Cu")
		(net 14)
	)
	(via
		(at 120.5495 89.6)
		(size 0.4)
		(drill 0.2)
		(layers "F.Cu" "B.Cu")
		(net 14)
	)
	(via
		(at 102.8 74.4)
		(size 0.4)
		(drill 0.15)
		(layers "F.Cu" "B.Cu")
		(net 14)
	)
	(via
		(at 130 69.3)
		(size 0.4)
		(drill 0.2)
		(layers "F.Cu" "B.Cu")
		(free yes)
		(net 14)
	)
	(via
		(at 165.075 68.55)
		(size 0.4)
		(drill 0.15)
		(layers "F.Cu" "B.Cu")
		(free yes)
		(net 14)
	)
	(via
		(at 104.2005 91.95)
		(size 0.4)
		(drill 0.15)
		(layers "F.Cu" "B.Cu")
		(net 14)
	)
	(via
		(at 134.297259 92.687259)
		(size 0.4)
		(drill 0.15)
		(layers "F.Cu" "B.Cu")
		(net 14)
	)
	(via
		(at 106.6375 67.85)
		(size 0.45)
		(drill 0.2)
		(layers "F.Cu" "B.Cu")
		(net 14)
	)
	(via
		(at 138.275 80)
		(size 0.4)
		(drill 0.15)
		(layers "F.Cu" "B.Cu")
		(net 14)
	)
	(via
		(at 138.975 76)
		(size 0.4)
		(drill 0.15)
		(layers "F.Cu" "B.Cu")
		(net 14)
	)
	(via
		(at 134.775 74.4)
		(size 0.4)
		(drill 0.15)
		(layers "F.Cu" "B.Cu")
		(net 14)
	)
	(via
		(at 150.775 96.975)
		(size 0.4)
		(drill 0.15)
		(layers "F.Cu" "B.Cu")
		(net 14)
	)
	(via
		(at 108.3 96.975)
		(size 0.4)
		(drill 0.15)
		(layers "F.Cu" "B.Cu")
		(net 14)
	)
	(via
		(at 141.025 96.975)
		(size 0.4)
		(drill 0.15)
		(layers "F.Cu" "B.Cu")
		(net 14)
	)
	(via
		(at 130.525 96.975)
		(size 0.4)
		(drill 0.15)
		(layers "F.Cu" "B.Cu")
		(net 14)
	)
	(via
		(at 138.275 75.2)
		(size 0.4)
		(drill 0.15)
		(layers "F.Cu" "B.Cu")
		(net 14)
	)
	(via
		(at 138.275 84.8)
		(size 0.4)
		(drill 0.15)
		(layers "F.Cu" "B.Cu")
		(net 14)
	)
	(via
		(at 163.275 96.975)
		(size 0.4)
		(drill 0.15)
		(layers "F.Cu" "B.Cu")
		(net 14)
	)
	(via
		(at 127.775 77.6)
		(size 0.4)
		(drill 0.15)
		(layers "F.Cu" "B.Cu")
		(net 14)
	)
	(via
		(at 104.55 96.975)
		(size 0.4)
		(drill 0.15)
		(layers "F.Cu" "B.Cu")
		(net 14)
	)
	(via
		(at 139.675 79.2)
		(size 0.4)
		(drill 0.15)
		(layers "F.Cu" "B.Cu")
		(net 14)
	)
	(via
		(at 136.6 62.6)
		(size 0.4)
		(drill 0.2)
		(layers "F.Cu" "B.Cu")
		(free yes)
		(net 14)
	)
	(via
		(at 104.2 89.6)
		(size 0.4)
		(drill 0.2)
		(layers "F.Cu" "B.Cu")
		(net 14)
	)
	(via
		(at 140.375 77.6)
		(size 0.4)
		(drill 0.15)
		(layers "F.Cu" "B.Cu")
		(net 14)
	)
	(via
		(at 134.775 85.6)
		(size 0.4)
		(drill 0.15)
		(layers "F.Cu" "B.Cu")
		(net 14)
	)
	(via
		(at 134.775 84.8)
		(size 0.4)
		(drill 0.15)
		(layers "F.Cu" "B.Cu")
		(net 14)
	)
	(via
		(at 150.85 95.1245)
		(size 0.4)
		(drill 0.15)
		(layers "F.Cu" "B.Cu")
		(net 14)
	)
	(via
		(at 106.325 63.525)
		(size 0.45)
		(drill 0.2)
		(layers "F.Cu" "B.Cu")
		(net 14)
	)
	(via
		(at 136.175 79.2)
		(size 0.4)
		(drill 0.15)
		(layers "F.Cu" "B.Cu")
		(net 14)
	)
	(via
		(at 145.6 94.9)
		(size 0.4)
		(drill 0.2)
		(layers "F.Cu" "B.Cu")
		(net 14)
	)
	(via
		(at 125.575 80.466)
		(size 0.4)
		(drill 0.2)
		(layers "F.Cu" "B.Cu")
		(net 14)
	)
	(via
		(at 139.675 80.8)
		(size 0.4)
		(drill 0.15)
		(layers "F.Cu" "B.Cu")
		(net 14)
	)
	(via
		(at 119.8 96.975)
		(size 0.4)
		(drill 0.15)
		(layers "F.Cu" "B.Cu")
		(net 14)
	)
	(via
		(at 166.025 96.975)
		(size 0.4)
		(drill 0.15)
		(layers "F.Cu" "B.Cu")
		(net 14)
	)
	(via
		(at 110.225 95.1245)
		(size 0.4)
		(drill 0.15)
		(layers "F.Cu" "B.Cu")
		(net 14)
	)
	(via
		(at 140.35 95.05)
		(size 0.4)
		(drill 0.2)
		(layers "F.Cu" "B.Cu")
		(net 14)
	)
	(via
		(at 144.25 79.484)
		(size 0.4)
		(drill 0.2)
		(layers "F.Cu" "B.Cu")
		(net 14)
	)
	(via
		(at 136.175 76.8)
		(size 0.4)
		(drill 0.15)
		(layers "F.Cu" "B.Cu")
		(net 14)
	)
	(via
		(at 103.875 94.3)
		(size 0.4)
		(drill 0.15)
		(layers "F.Cu" "B.Cu")
		(net 14)
	)
	(via
		(at 160.4 97)
		(size 0.4)
		(drill 0.15)
		(layers "F.Cu" "B.Cu")
		(net 14)
	)
	(via
		(at 116.2 61.5)
		(size 0.4)
		(drill 0.15)
		(layers "F.Cu" "B.Cu")
		(net 14)
	)
	(via
		(at 120.8 96.975)
		(size 0.4)
		(drill 0.15)
		(layers "F.Cu" "B.Cu")
		(net 14)
	)
	(via
		(at 139.675 84.8)
		(size 0.4)
		(drill 0.15)
		(layers "F.Cu" "B.Cu")
		(net 14)
	)
	(via
		(at 140.725 79.6)
		(size 0.4)
		(drill 0.15)
		(layers "F.Cu" "B.Cu")
		(net 14)
	)
	(via
		(at 160.675 71.05)
		(size 0.4)
		(drill 0.15)
		(layers "F.Cu" "B.Cu")
		(free yes)
		(net 14)
	)
	(via
		(at 129.175 77.6)
		(size 0.4)
		(drill 0.15)
		(layers "F.Cu" "B.Cu")
		(net 14)
	)
	(via
		(at 149.025 96.975)
		(size 0.4)
		(drill 0.15)
		(layers "F.Cu" "B.Cu")
		(net 14)
	)
	(via
		(at 144.275 96.975)
		(size 0.4)
		(drill 0.15)
		(layers "F.Cu" "B.Cu")
		(net 14)
	)
	(via
		(at 167.025 96.975)
		(size 0.4)
		(drill 0.15)
		(layers "F.Cu" "B.Cu")
		(net 14)
	)
	(via
		(at 121.675 97)
		(size 0.4)
		(drill 0.15)
		(layers "F.Cu" "B.Cu")
		(net 14)
	)
	(via
		(at 160.675 70.425)
		(size 0.4)
		(drill 0.15)
		(layers "F.Cu" "B.Cu")
		(free yes)
		(net 14)
	)
	(via
		(at 162.275 96.975)
		(size 0.4)
		(drill 0.15)
		(layers "F.Cu" "B.Cu")
		(net 14)
	)
	(via
		(at 138.45 94.35)
		(size 0.4)
		(drill 0.2)
		(layers "F.Cu" "B.Cu")
		(net 14)
	)
	(via
		(at 136.175 78.4)
		(size 0.4)
		(drill 0.15)
		(layers "F.Cu" "B.Cu")
		(net 14)
	)
	(via
		(at 133.375 78.4)
		(size 0.4)
		(drill 0.15)
		(layers "F.Cu" "B.Cu")
		(net 14)
	)
	(via
		(at 110.775 68.825)
		(size 0.45)
		(drill 0.2)
		(layers "F.Cu" "B.Cu")
		(net 14)
	)
	(via
		(at 161.275 96.975)
		(size 0.4)
		(drill 0.15)
		(layers "F.Cu" "B.Cu")
		(net 14)
	)
	(via
		(at 130.575 80)
		(size 0.4)
		(drill 0.15)
		(layers "F.Cu" "B.Cu")
		(net 14)
	)
	(via
		(at 147.025 96.975)
		(size 0.4)
		(drill 0.15)
		(layers "F.Cu" "B.Cu")
		(net 14)
	)
	(via
		(at 129.875 84.8)
		(size 0.4)
		(drill 0.15)
		(layers "F.Cu" "B.Cu")
		(net 14)
	)
	(via
		(at 135.8 62.8)
		(size 0.4)
		(drill 0.2)
		(layers "F.Cu" "B.Cu")
		(free yes)
		(net 14)
	)
	(via
		(at 136.7 71.5)
		(size 0.4)
		(drill 0.2)
		(layers "F.Cu" "B.Cu")
		(free yes)
		(net 14)
	)
	(via
		(at 116.05 96.975)
		(size 0.4)
		(drill 0.15)
		(layers "F.Cu" "B.Cu")
		(net 14)
	)
	(via
		(at 105.55 96.975)
		(size 0.4)
		(drill 0.15)
		(layers "F.Cu" "B.Cu")
		(net 14)
	)
	(via
		(at 161.15 71.05)
		(size 0.4)
		(drill 0.15)
		(layers "F.Cu" "B.Cu")
		(free yes)
		(net 14)
	)
	(via
		(at 125.525 96.975)
		(size 0.4)
		(drill 0.15)
		(layers "F.Cu" "B.Cu")
		(net 14)
	)
	(via
		(at 157.9 86.7)
		(size 0.4)
		(drill 0.2)
		(layers "F.Cu" "B.Cu")
		(free yes)
		(net 14)
	)
	(via
		(at 137.575 76)
		(size 0.4)
		(drill 0.15)
		(layers "F.Cu" "B.Cu")
		(net 14)
	)
	(via
		(at 140.375 80)
		(size 0.4)
		(drill 0.15)
		(layers "F.Cu" "B.Cu")
		(net 14)
	)
	(via
		(at 114.7005 89.6)
		(size 0.4)
		(drill 0.2)
		(layers "F.Cu" "B.Cu")
		(net 14)
	)
	(via
		(at 142.76 80.75)
		(size 0.4)
		(drill 0.2)
		(layers "F.Cu" "B.Cu")
		(free yes)
		(net 14)
	)
	(via
		(at 166.575 71.05)
		(size 0.4)
		(drill 0.15)
		(layers "F.Cu" "B.Cu")
		(free yes)
		(net 14)
	)
	(via
		(at 132.675 83.2)
		(size 0.4)
		(drill 0.15)
		(layers "F.Cu" "B.Cu")
		(net 14)
	)
	(via
		(at 165.15 97)
		(size 0.4)
		(drill 0.15)
		(layers "F.Cu" "B.Cu")
		(net 14)
	)
	(via
		(at 133.375 74.4)
		(size 0.4)
		(drill 0.15)
		(layers "F.Cu" "B.Cu")
		(net 14)
	)
	(via
		(at 129.875 78.4)
		(size 0.4)
		(drill 0.15)
		(layers "F.Cu" "B.Cu")
		(net 14)
	)
	(via
		(at 126.6 79.15)
		(size 0.4)
		(drill 0.2)
		(layers "F.Cu" "B.Cu")
		(net 14)
	)
	(via
		(at 115.05 96.975)
		(size 0.4)
		(drill 0.15)
		(layers "F.Cu" "B.Cu")
		(net 14)
	)
	(via
		(at 107.6875 66.625)
		(size 0.45)
		(drill 0.2)
		(layers "F.Cu" "B.Cu")
		(net 14)
	)
	(via
		(at 136.359 87.559)
		(size 0.4)
		(drill 0.15)
		(layers "F.Cu" "B.Cu")
		(net 14)
	)
	(via
		(at 102.675 63.825)
		(size 0.45)
		(drill 0.2)
		(layers "F.Cu" "B.Cu")
		(free yes)
		(net 14)
	)
	(via
		(at 122.3 92.71)
		(size 0.4)
		(drill 0.2)
		(layers "F.Cu" "B.Cu")
		(free yes)
		(net 14)
	)
	(via
		(at 129 94.7)
		(size 0.4)
		(drill 0.2)
		(layers "F.Cu" "B.Cu")
		(net 14)
	)
	(via
		(at 136.875 76.8)
		(size 0.4)
		(drill 0.15)
		(layers "F.Cu" "B.Cu")
		(net 14)
	)
	(via
		(at 132.025 96.975)
		(size 0.4)
		(drill 0.15)
		(layers "F.Cu" "B.Cu")
		(net 14)
	)
	(via
		(at 134.775 83.2)
		(size 0.4)
		(drill 0.15)
		(layers "F.Cu" "B.Cu")
		(net 14)
	)
	(via
		(at 166.275 69.65)
		(size 0.4)
		(drill 0.15)
		(layers "F.Cu" "B.Cu")
		(free yes)
		(net 14)
	)
	(via
		(at 136.175 85.6)
		(size 0.4)
		(drill 0.15)
		(layers "F.Cu" "B.Cu")
		(net 14)
	)
	(via
		(at 116.925 97)
		(size 0.4)
		(drill 0.15)
		(layers "F.Cu" "B.Cu")
		(net 14)
	)
	(via
		(at 107.3 96.975)
		(size 0.4)
		(drill 0.15)
		(layers "F.Cu" "B.Cu")
		(net 14)
	)
	(via
		(at 103.8 75.8)
		(size 0.45)
		(drill 0.2)
		(layers "F.Cu" "B.Cu")
		(free yes)
		(net 14)
	)
	(via
		(at 134.775 75.2)
		(size 0.4)
		(drill 0.15)
		(layers "F.Cu" "B.Cu")
		(net 14)
	)
	(via
		(at 131.275 75.2)
		(size 0.4)
		(drill 0.15)
		(layers "F.Cu" "B.Cu")
		(net 14)
	)
	(via
		(at 124.55 96.975)
		(size 0.4)
		(drill 0.15)
		(layers "F.Cu" "B.Cu")
		(net 14)
	)
	(via
		(at 142.935436 75.584939)
		(size 0.4)
		(drill 0.2)
		(layers "F.Cu" "B.Cu")
		(free yes)
		(net 14)
	)
	(via
		(at 105.5875 66.625)
		(size 0.45)
		(drill 0.2)
		(layers "F.Cu" "B.Cu")
		(net 14)
	)
	(via
		(at 134.75 97)
		(size 0.4)
		(drill 0.15)
		(layers "F.Cu" "B.Cu")
		(net 14)
	)
	(via
		(at 167.6 95.1)
		(size 0.4)
		(drill 0.15)
		(layers "F.Cu" "B.Cu")
		(net 14)
	)
	(via
		(at 109.3 96.975)
		(size 0.4)
		(drill 0.15)
		(layers "F.Cu" "B.Cu")
		(net 14)
	)
	(via
		(at 157.2 94.3)
		(size 0.4)
		(drill 0.15)
		(layers "F.Cu" "B.Cu")
		(net 14)
	)
	(via
		(at 137.575 77.6)
		(size 0.4)
		(drill 0.15)
		(layers "F.Cu" "B.Cu")
		(net 14)
	)
	(via
		(at 107.6875 67.85)
		(size 0.45)
		(drill 0.2)
		(layers "F.Cu" "B.Cu")
		(net 14)
	)
	(via
		(at 167.5 92)
		(size 0.4)
		(drill 0.15)
		(layers "F.Cu" "B.Cu")
		(net 14)
	)
	(via
		(at 134.075 80)
		(size 0.4)
		(drill 0.15)
		(layers "F.Cu" "B.Cu")
		(net 14)
	)
	(via
		(at 130.575 76)
		(size 0.4)
		(drill 0.15)
		(layers "F.Cu" "B.Cu")
		(net 14)
	)
	(via
		(at 138.025 96.975)
		(size 0.4)
		(drill 0.15)
		(layers "F.Cu" "B.Cu")
		(net 14)
	)
	(via
		(at 134.775 82.4)
		(size 0.4)
		(drill 0.15)
		(layers "F.Cu" "B.Cu")
		(net 14)
	)
	(via
		(at 133.375 85.6)
		(size 0.4)
		(drill 0.15)
		(layers "F.Cu" "B.Cu")
		(net 14)
	)
	(via
		(at 126.4 97)
		(size 0.4)
		(drill 0.15)
		(layers "F.Cu" "B.Cu")
		(net 14)
	)
	(via
		(at 155.525 96.975)
		(size 0.4)
		(drill 0.15)
		(layers "F.Cu" "B.Cu")
		(net 14)
	)
	(via
		(at 106.6375 66.625)
		(size 0.45)
		(drill 0.2)
		(layers "F.Cu" "B.Cu")
		(net 14)
	)
	(via
		(at 137.575 80.8)
		(size 0.4)
		(drill 0.15)
		(layers "F.Cu" "B.Cu")
		(net 14)
	)
	(via
		(at 139.675 75.2)
		(size 0.4)
		(drill 0.15)
		(layers "F.Cu" "B.Cu")
		(net 14)
	)
	(via
		(at 132.675 81.6)
		(size 0.4)
		(drill 0.15)
		(layers "F.Cu" "B.Cu")
		(net 14)
	)
	(via
		(at 127.775 82.4)
		(size 0.4)
		(drill 0.15)
		(layers "F.Cu" "B.Cu")
		(net 14)
	)
	(via
		(at 114.7005 92.02)
		(size 0.4)
		(drill 0.2)
		(layers "F.Cu" "B.Cu")
		(net 14)
	)
	(via
		(at 148.025 96.975)
		(size 0.4)
		(drill 0.15)
		(layers "F.Cu" "B.Cu")
		(net 14)
	)
	(via
		(at 107.525 63.525)
		(size 0.45)
		(drill 0.2)
		(layers "F.Cu" "B.Cu")
		(net 14)
	)
	(via
		(at 103.55 96.975)
		(size 0.4)
		(drill 0.15)
		(layers "F.Cu" "B.Cu")
		(net 14)
	)
	(via
		(at 107.195 67.255)
		(size 0.45)
		(drill 0.2)
		(layers "F.Cu" "B.Cu")
		(net 14)
	)
	(via
		(at 106.6375 69.025)
		(size 0.45)
		(drill 0.2)
		(layers "F.Cu" "B.Cu")
		(net 14)
	)
	(via
		(at 159.38 87.47)
		(size 0.4)
		(drill 0.2)
		(layers "F.Cu" "B.Cu")
		(free yes)
		(net 14)
	)
	(via
		(at 161.15 70.425)
		(size 0.4)
		(drill 0.15)
		(layers "F.Cu" "B.Cu")
		(free yes)
		(net 14)
	)
	(via
		(at 136.35 73.175)
		(size 0.4)
		(drill 0.15)
		(layers "F.Cu" "B.Cu")
		(net 14)
	)
	(via
		(at 139.525 96.975)
		(size 0.4)
		(drill 0.15)
		(layers "F.Cu" "B.Cu")
		(net 14)
	)
	(via
		(at 157.525 96.975)
		(size 0.4)
		(drill 0.15)
		(layers "F.Cu" "B.Cu")
		(net 14)
	)
	(via
		(at 130.575 84)
		(size 0.4)
		(drill 0.15)
		(layers "F.Cu" "B.Cu")
		(net 14)
	)
	(via
		(at 137.575 79.2)
		(size 0.4)
		(drill 0.15)
		(layers "F.Cu" "B.Cu")
		(net 14)
	)
	(via
		(at 161.3 95.1245)
		(size 0.4)
		(drill 0.15)
		(layers "F.Cu" "B.Cu")
		(net 14)
	)
	(via
		(at 123.55 96.975)
		(size 0.4)
		(drill 0.15)
		(layers "F.Cu" "B.Cu")
		(net 14)
	)
	(via
		(at 104.4 75.2)
		(size 0.45)
		(drill 0.2)
		(layers "F.Cu" "B.Cu")
		(free yes)
		(net 14)
	)
	(via
		(at 137.5 69.8)
		(size 0.4)
		(drill 0.2)
		(layers "F.Cu" "B.Cu")
		(free yes)
		(net 14)
	)
	(via
		(at 131.975 77.6)
		(size 0.4)
		(drill 0.15)
		(layers "F.Cu" "B.Cu")
		(net 14)
	)
	(via
		(at 152.775 96.975)
		(size 0.4)
		(drill 0.15)
		(layers "F.Cu" "B.Cu")
		(net 14)
	)
	(via
		(at 145.275 96.975)
		(size 0.4)
		(drill 0.15)
		(layers "F.Cu" "B.Cu")
		(net 14)
	)
	(via
		(at 154.65 97)
		(size 0.4)
		(drill 0.15)
		(layers "F.Cu" "B.Cu")
		(net 14)
	)
	(via
		(at 114.05 96.975)
		(size 0.4)
		(drill 0.15)
		(layers "F.Cu" "B.Cu")
		(net 14)
	)
	(via
		(at 131.975 76)
		(size 0.4)
		(drill 0.15)
		(layers "F.Cu" "B.Cu")
		(net 14)
	)
	(via
		(at 131.975 82.4)
		(size 0.4)
		(drill 0.15)
		(layers "F.Cu" "B.Cu")
		(net 14)
	)
	(via
		(at 110.475 65.025)
		(size 0.45)
		(drill 0.2)
		(layers "F.Cu" "B.Cu")
		(net 14)
	)
	(via
		(at 136.875 80)
		(size 0.4)
		(drill 0.15)
		(layers "F.Cu" "B.Cu")
		(net 14)
	)
	(via
		(at 107.025 63.525)
		(size 0.45)
		(drill 0.2)
		(layers "F.Cu" "B.Cu")
		(net 14)
	)
	(via
		(at 165.875 69.25)
		(size 0.4)
		(drill 0.15)
		(layers "F.Cu" "B.Cu")
		(free yes)
		(net 14)
	)
	(via
		(at 136.175 84)
		(size 0.4)
		(drill 0.15)
		(layers "F.Cu" "B.Cu")
		(net 14)
	)
	(via
		(at 149.9 97)
		(size 0.4)
		(drill 0.15)
		(layers "F.Cu" "B.Cu")
		(net 14)
	)
	(via
		(at 106.075 72.325)
		(size 0.45)
		(drill 0.2)
		(layers "F.Cu" "B.Cu")
		(net 14)
	)
	(via
		(at 158.525 96.975)
		(size 0.4)
		(drill 0.15)
		(layers "F.Cu" "B.Cu")
		(net 14)
	)
	(via
		(at 160.675 71.75)
		(size 0.4)
		(drill 0.15)
		(layers "F.Cu" "B.Cu")
		(free yes)
		(net 14)
	)
	(via
		(at 153.775 96.975)
		(size 0.4)
		(drill 0.15)
		(layers "F.Cu" "B.Cu")
		(net 14)
	)
	(via
		(at 165.075 67.35)
		(size 0.4)
		(drill 0.15)
		(layers "F.Cu" "B.Cu")
		(free yes)
		(net 14)
	)
	(via
		(at 132.675 78.4)
		(size 0.4)
		(drill 0.15)
		(layers "F.Cu" "B.Cu")
		(net 14)
	)
	(via
		(at 151 89.3)
		(size 0.4)
		(drill 0.2)
		(layers "F.Cu" "B.Cu")
		(net 14)
	)
	(via
		(at 106.125 67.225)
		(size 0.45)
		(drill 0.2)
		(layers "F.Cu" "B.Cu")
		(net 14)
	)
	(via
		(at 102.675 64.425)
		(size 0.45)
		(drill 0.2)
		(layers "F.Cu" "B.Cu")
		(free yes)
		(net 14)
	)
	(via
		(at 156.525 96.975)
		(size 0.4)
		(drill 0.15)
		(layers "F.Cu" "B.Cu")
		(net 14)
	)
	(via
		(at 151.775 96.975)
		(size 0.4)
		(drill 0.15)
		(layers "F.Cu" "B.Cu")
		(net 14)
	)
	(via
		(at 132.675 76.8)
		(size 0.4)
		(drill 0.15)
		(layers "F.Cu" "B.Cu")
		(net 14)
	)
	(via
		(at 146.025 96.975)
		(size 0.4)
		(drill 0.15)
		(layers "F.Cu" "B.Cu")
		(net 14)
	)
	(via
		(at 107.165 68.445)
		(size 0.45)
		(drill 0.2)
		(layers "F.Cu" "B.Cu")
		(net 14)
	)
	(via
		(at 137.575 82.4)
		(size 0.4)
		(drill 0.15)
		(layers "F.Cu" "B.Cu")
		(net 14)
	)
	(via
		(at 165.775 70.25)
		(size 0.4)
		(drill 0.15)
		(layers "F.Cu" "B.Cu")
		(free yes)
		(net 14)
	)
	(via
		(at 137.575 84)
		(size 0.4)
		(drill 0.15)
		(layers "F.Cu" "B.Cu")
		(net 14)
	)
	(via
		(at 141.775 77.6)
		(size 0.4)
		(drill 0.15)
		(layers "F.Cu" "B.Cu")
		(net 14)
	)
	(via
		(at 168.025 96.975)
		(size 0.4)
		(drill 0.15)
		(layers "F.Cu" "B.Cu")
		(net 14)
	)
	(via
		(at 110.475 65.625)
		(size 0.45)
		(drill 0.2)
		(layers "F.Cu" "B.Cu")
		(net 14)
	)
	(via
		(at 121.12 92.65)
		(size 0.4)
		(drill 0.2)
		(layers "F.Cu" "B.Cu")
		(free yes)
		(net 14)
	)
	(via
		(at 122.55 96.975)
		(size 0.4)
		(drill 0.15)
		(layers "F.Cu" "B.Cu")
		(net 14)
	)
	(via
		(at 127.275 96.975)
		(size 0.4)
		(drill 0.15)
		(layers "F.Cu" "B.Cu")
		(net 14)
	)
	(via
		(at 156.95 92)
		(size 0.4)
		(drill 0.15)
		(layers "F.Cu" "B.Cu")
		(net 14)
	)
	(via
		(at 138.975 85.6)
		(size 0.4)
		(drill 0.15)
		(layers "F.Cu" "B.Cu")
		(net 14)
	)
	(via
		(at 159.525 96.975)
		(size 0.4)
		(drill 0.15)
		(layers "F.Cu" "B.Cu")
		(net 14)
	)
	(segment
		(start 111.175 98.625)
		(end 111.175 97)
		(width 0.2)
		(layer "B.Cu")
		(net 14)
	)
	(segment
		(start 129.659 73.8)
		(end 129.675 73.8)
		(width 0.2)
		(layer "B.Cu")
		(net 14)
	)
	(segment
		(start 116.195 89.5)
		(end 114.8005 89.5)
		(width 0.15)
		(layer "B.Cu")
		(net 14)
	)
	(segment
		(start 104.23 89.57)
		(end 104.2 89.6)
		(width 0.15)
		(layer "B.Cu")
		(net 14)
	)
	(segment
		(start 103.675 97.1)
		(end 103.675 98.625)
		(width 0.2)
		(layer "B.Cu")
		(net 14)
	)
	(segment
		(start 116.174 61.524)
		(end 116.176 61.524)
		(width 0.15)
		(layer "B.Cu")
		(net 14)
	)
	(segment
		(start 124.55 96.975)
		(end 124.675 97.1)
		(width 0.2)
		(layer "B.Cu")
		(net 14)
	)
	(segment
		(start 165.885 89.465)
		(end 167.3595 89.465)
		(width 0.15)
		(layer "B.Cu")
		(net 14)
	)
	(segment
		(start 130.175 85.6)
		(end 130.575 85.6)
		(width 0.2)
		(layer "B.Cu")
		(net 14)
	)
	(segment
		(start 136.525 96.975)
		(end 136.65 97.1)
		(width 0.2)
		(layer "B.Cu")
		(net 14)
	)
	(segment
		(start 104.525 94.3)
		(end 103.875 94.3)
		(width 0.15)
		(layer "B.Cu")
		(net 14)
	)
	(segment
		(start 120.2625 94.25)
		(end 120.2625 94.662)
		(width 0.15)
		(layer "B.Cu")
		(net 14)
	)
	(segment
		(start 168.025 96.975)
		(end 168.15 97.1)
		(width 0.2)
		(layer "B.Cu")
		(net 14)
	)
	(segment
		(start 124.675 97.1)
		(end 124.675 98.625)
		(width 0.2)
		(layer "B.Cu")
		(net 14)
	)
	(segment
		(start 108.175 97.1)
		(end 108.175 98.625)
		(width 0.2)
		(layer "B.Cu")
		(net 14)
	)
	(segment
		(start 145.15 97.1)
		(end 145.15 98.625)
		(width 0.2)
		(layer "B.Cu")
		(net 14)
	)
	(segment
		(start 129.975 81.5)
		(end 129.875 81.6)
		(width 0.2)
		(layer "B.Cu")
		(net 14)
	)
	(segment
		(start 104.875 69.7375)
		(end 105.5875 69.025)
		(width 0.15)
		(layer "B.Cu")
		(net 14)
	)
	(segment
		(start 106.3 94.3)
		(end 104.525 94.3)
		(width 0.15)
		(layer "B.Cu")
		(net 14)
	)
	(segment
		(start 129.975 78.5)
		(end 129.875 78.4)
		(width 0.2)
		(layer "B.Cu")
		(net 14)
	)
	(segment
		(start 107.9875 94.25)
		(end 109.7625 94.25)
		(width 0.15)
		(layer "B.Cu")
		(net 14)
	)
	(segment
		(start 139.575 81.5)
		(end 139.675 81.6)
		(width 0.2)
		(layer "B.Cu")
		(net 14)
	)
	(segment
		(start 159.525 96.975)
		(end 159.65 97.1)
		(width 0.2)
		(layer "B.Cu")
		(net 14)
	)
	(segment
		(start 120.2625 94.662)
		(end 120.725 95.1245)
		(width 0.15)
		(layer "B.Cu")
		(net 14)
	)
	(segment
		(start 162.275 96.975)
		(end 162.15 97.1)
		(width 0.2)
		(layer "B.Cu")
		(net 14)
	)
	(segment
		(start 104.675 97.1)
		(end 104.675 98.625)
		(width 0.2)
		(layer "B.Cu")
		(net 14)
	)
	(segment
		(start 106.766 84.717)
		(end 106.299 84.25)
		(width 0.15)
		(layer "B.Cu")
		(net 14)
	)
	(segment
		(start 109.7625 94.25)
		(end 109.7625 94.662)
		(width 0.15)
		(layer "B.Cu")
		(net 14)
	)
	(segment
		(start 137.65 94.335)
		(end 138.435 94.335)
		(width 0.2)
		(layer "B.Cu")
		(net 14)
	)
	(segment
		(start 113.175 97.1)
		(end 113.175 98.625)
		(width 0.2)
		(layer "B.Cu")
		(net 14)
	)
	(segment
		(start 137.675 82.5)
		(end 137.575 82.4)
		(width 0.2)
		(layer "B.Cu")
		(net 14)
	)
	(segment
		(start 112.05 96.975)
		(end 112.175 97.1)
		(width 0.2)
		(layer "B.Cu")
		(net 14)
	)
	(segment
		(start 118.4875 94.25)
		(end 120.2625 94.25)
		(width 0.15)
		(layer "B.Cu")
		(net 14)
	)
	(segment
		(start 135.15 91.835)
		(end 134.465 91.835)
		(width 0.2)
		(layer "B.Cu")
		(net 14)
	)
	(segment
		(start 163.015 89.465)
		(end 161.5405 89.465)
		(width 0.15)
		(layer "B.Cu")
		(net 14)
	)
	(segment
		(start 109.3 96.975)
		(end 109.175 97.1)
		(width 0.2)
		(layer "B.Cu")
		(net 14)
	)
	(segment
		(start 151.3125 94.25)
		(end 151.3125 94.662)
		(width 0.15)
		(layer "B.Cu")
		(net 14)
	)
	(segment
		(start 136.65 94.335)
		(end 137.65 94.335)
		(width 0.2)
		(layer "B.Cu")
		(net 14)
	)
	(segment
		(start 129 94.7)
		(end 129 94.6625)
		(width 0.2)
		(layer "B.Cu")
		(net 14)
	)
	(segment
		(start 167.6 95.1)
		(end 167.0875 94.5875)
		(width 0.2)
		(layer "B.Cu")
		(net 14)
	)
	(segment
		(start 151.3125 94.662)
		(end 150.85 95.1245)
		(width 0.15)
		(layer "B.Cu")
		(net 14)
	)
	(segment
		(start 166.025 96.975)
		(end 166.15 97.1)
		(width 0.2)
		(layer "B.Cu")
		(net 14)
	)
	(segment
		(start 139.375 74.4)
		(end 138.975 74.4)
		(width 0.2)
		(layer "B.Cu")
		(net 14)
	)
	(segment
		(start 152.775 96.975)
		(end 152.65 97.1)
		(width 0.2)
		(layer "B.Cu")
		(net 14)
	)
	(segment
		(start 139.575 78.5)
		(end 139.675 78.4)
		(width 0.2)
		(layer "B.Cu")
		(net 14)
	)
	(segment
		(start 168.15 97.1)
		(end 168.15 98.625)
		(width 0.2)
		(layer "B.Cu")
		(net 14)
	)
	(segment
		(start 110.0195 89.57)
		(end 110.0495 89.6)
		(width 0.15)
		(layer "B.Cu")
		(net 14)
	)
	(segment
		(start 156.89 89.31)
		(end 156.9 89.3)
		(width 0.15)
		(layer "B.Cu")
		(net 14)
	)
	(segment
		(start 104.875 70.157)
		(end 104.875 69.7375)
		(width 0.15)
		(layer "B.Cu")
		(net 14)
	)
	(segment
		(start 105.95 84.25)
		(end 105.68 83.98)
		(width 0.15)
		(layer "B.Cu")
		(net 14)
	)
	(segment
		(start 166.935 91.95)
		(end 167.45 91.95)
		(width 0.2)
		(layer "B.Cu")
		(net 14)
	)
	(segment
		(start 138.15 97.1)
		(end 138.15 98.625)
		(width 0.2)
		(layer "B.Cu")
		(net 14)
	)
	(segment
		(start 137.791 77.5)
		(end 137.675 77.5)
		(width 0.2)
		(layer "B.Cu")
		(net 14)
	)
	(segment
		(start 132.025 96.975)
		(end 132.15 97.1)
		(width 0.2)
		(layer "B.Cu")
		(net 14)
	)
	(segment
		(start 121.776 61.524)
		(end 121.8 61.5)
		(width 0.15)
		(layer "B.Cu")
		(net 14)
	)
	(segment
		(start 118.675 97.1)
		(end 118.675 98.625)
		(width 0.2)
		(layer "B.Cu")
		(net 14)
	)
	(segment
		(start 130.275 74.4)
		(end 130.575 74.4)
		(width 0.2)
		(layer "B.Cu")
		(net 14)
	)
	(segment
		(start 138.025 96.975)
		(end 138.15 97.1)
		(width 0.2)
		(layer "B.Cu")
		(net 14)
	)
	(segment
		(start 150.775 96.975)
		(end 150.65 97.1)
		(width 0.2)
		(layer "B.Cu")
		(net 14)
	)
	(segment
		(start 117.675 97.1)
		(end 117.675 98.625)
		(width 0.2)
		(layer "B.Cu")
		(net 14)
	)
	(segment
		(start 144.15 97.1)
		(end 144.15 98.625)
		(width 0.2)
		(layer "B.Cu")
		(net 14)
	)
	(segment
		(start 112.175 97.1)
		(end 112.175 98.625)
		(width 0.2)
		(layer "B.Cu")
		(net 14)
	)
	(segment
		(start 107.25 81.549)
		(end 107.25 80.7)
		(width 0.09)
		(layer "B.Cu")
		(net 14)
	)
	(segment
		(start 139.525 96.975)
		(end 139.65 97.1)
		(width 0.2)
		(layer "B.Cu")
		(net 14)
	)
	(segment
		(start 145.6 94.735)
		(end 146.05 94.285)
		(width 0.2)
		(layer "B.Cu")
		(net 14)
	)
	(segment
		(start 123.675 97.1)
		(end 123.675 98.625)
		(width 0.2)
		(layer "B.Cu")
		(net 14)
	)
	(segment
		(start 145.275 96.975)
		(end 145.15 97.1)
		(width 0.2)
		(layer "B.Cu")
		(net 14)
	)
	(segment
		(start 158.525 96.975)
		(end 158.65 97.1)
		(width 0.2)
		(layer "B.Cu")
		(net 14)
	)
	(segment
		(start 129.15 97.1)
		(end 129.15 98.625)
		(width 0.2)
		(layer "B.Cu")
		(net 14)
	)
	(segment
		(start 130.65 97.1)
		(end 130.65 98.625)
		(width 0.2)
		(layer "B.Cu")
		(net 14)
	)
	(segment
		(start 146.15 97.1)
		(end 146.15 98.625)
		(width 0.2)
		(layer "B.Cu")
		(net 14)
	)
	(segment
		(start 129.675 73.8)
		(end 130.275 74.4)
		(width 0.2)
		(layer "B.Cu")
		(net 14)
	)
	(segment
		(start 167.45 91.95)
		(end 167.5 92)
		(width 0.2)
		(layer "B.Cu")
		(net 14)
	)
	(segment
		(start 130.525 96.975)
		(end 130.65 97.1)
		(width 0.2)
		(layer "B.Cu")
		(net 14)
	)
	(segment
		(start 129.025 96.975)
		(end 129.15 97.1)
		(width 0.2)
		(layer "B.Cu")
		(net 14)
	)
	(segment
		(start 152.65 97.1)
		(end 152.65 98.625)
		(width 0.2)
		(layer "B.Cu")
		(net 14)
	)
	(segment
		(start 131.759 77.5)
		(end 131.875 77.5)
		(width 0.2)
		(layer "B.Cu")
		(net 14)
	)
	(segment
		(start 156.65 97.1)
		(end 156.65 98.625)
		(width 0.2)
		(layer "B.Cu")
		(net 14)
	)
	(segment
		(start 151.01 89.31)
		(end 151 89.3)
		(width 0.15)
		(layer "B.Cu")
		(net 14)
	)
	(segment
		(start 107.175 97.1)
		(end 107.175 98.625)
		(width 0.2)
		(layer "B.Cu")
		(net 14)
	)
	(segment
		(start 113.05 96.975)
		(end 113.175 97.1)
		(width 0.2)
		(layer "B.Cu")
		(net 14)
	)
	(segment
		(start 129.659 86.116)
		(end 130.175 85.6)
		(width 0.2)
		(layer "B.Cu")
		(net 14)
	)
	(segment
		(start 161.825 94.5995)
		(end 161.3 95.1245)
		(width 0.2)
		(layer "B.Cu")
		(net 14)
	)
	(segment
		(start 149.15 97.1)
		(end 149.15 98.625)
		(width 0.2)
		(layer "B.Cu")
		(net 14)
	)
	(segment
		(start 128.5875 94.2875)
		(end 129 94.7)
		(width 0.2)
		(layer "B.Cu")
		(net 14)
	)
	(segment
		(start 139.891 73.884)
		(end 139.375 74.4)
		(width 0.2)
		(layer "B.Cu")
		(net 14)
	)
	(segment
		(start 108.565 89.57)
		(end 110.0195 89.57)
		(width 0.15)
		(layer "B.Cu")
		(net 14)
	)
	(segment
		(start 131.875 82.5)
		(end 131.975 82.4)
		(width 0.2)
		(layer "B.Cu")
		(net 14)
	)
	(segment
		(start 139.259 78.5)
		(end 139.575 78.5)
		(width 0.2)
		(layer "B.Cu")
		(net 14)
	)
	(segment
		(start 147.025 96.975)
		(end 147.15 97.1)
		(width 0.2)
		(layer "B.Cu")
		(net 14)
	)
	(segment
		(start 104.55 96.975)
		(end 104.675 97.1)
		(width 0.2)
		(layer "B.Cu")
		(net 14)
	)
	(segment
		(start 159.65 97.1)
		(end 159.65 98.625)
		(width 0.2)
		(layer "B.Cu")
		(net 14)
	)
	(segment
		(start 129 94.6625)
		(end 129.4125 94.25)
		(width 0.2)
		(layer "B.Cu")
		(net 14)
	)
	(segment
		(start 137.675 77.5)
		(end 137.575 77.6)
		(width 0.2)
		(layer "B.Cu")
		(net 14)
	)
	(segment
		(start 139.875 86.2)
		(end 139.275 85.6)
		(width 0.2)
		(layer "B.Cu")
		(net 14)
	)
	(segment
		(start 114.175 97.1)
		(end 114.175 98.625)
		(width 0.2)
		(layer "B.Cu")
		(net 14)
	)
	(segment
		(start 118.8 96.975)
		(end 118.675 97.1)
		(width 0.2)
		(layer "B.Cu")
		(net 14)
	)
	(segment
		(start 131.875 77.5)
		(end 131.975 77.6)
		(width 0.2)
		(layer "B.Cu")
		(net 14)
	)
	(segment
		(start 115.025 94.3)
		(end 114.375 94.3)
		(width 0.15)
		(layer "B.Cu")
		(net 14)
	)
	(segment
		(start 110.175 97.1)
		(end 110.175 98.625)
		(width 0.2)
		(layer "B.Cu")
		(net 14)
	)
	(segment
		(start 139.891 86.2)
		(end 139.875 86.2)
		(width 0.2)
		(layer "B.Cu")
		(net 14)
	)
	(segment
		(start 114.05 96.975)
		(end 114.175 97.1)
		(width 0.2)
		(layer "B.Cu")
		(net 14)
	)
	(segment
		(start 156.55 94.3)
		(end 157.2 94.3)
		(width 0.15)
		(layer "B.Cu")
		(net 14)
	)
	(segment
		(start 109.175 97.1)
		(end 109.175 98.625)
		(width 0.2)
		(layer "B.Cu")
		(net 14)
	)
	(segment
		(start 105.55 96.975)
		(end 105.675 97.1)
		(width 0.2)
		(layer "B.Cu")
		(net 14)
	)
	(segment
		(start 125.65 97.1)
		(end 125.65 98.625)
		(width 0.2)
		(layer "B.Cu")
		(net 14)
	)
	(segment
		(start 164.275 96.975)
		(end 164.15 97.1)
		(width 0.2)
		(layer "B.Cu")
		(net 14)
	)
	(segment
		(start 120.4495 89.5)
		(end 119.065 89.5)
		(width 0.15)
		(layer "B.Cu")
		(net 14)
	)
	(segment
		(start 132.15 97.1)
		(end 132.15 98.625)
		(width 0.2)
		(layer "B.Cu")
		(net 14)
	)
	(segment
		(start 139.65 97.1)
		(end 139.65 98.625)
		(width 0.2)
		(layer "B.Cu")
		(net 14)
	)
	(segment
		(start 162.15 97.1)
		(end 162.15 98.625)
		(width 0.2)
		(layer "B.Cu")
		(net 14)
	)
	(segment
		(start 110.3 96.975)
		(end 110.175 97.1)
		(width 0.2)
		(layer "B.Cu")
		(net 14)
	)
	(segment
		(start 164.15 97.1)
		(end 164.15 98.625)
		(width 0.2)
		(layer "B.Cu")
		(net 14)
	)
	(segment
		(start 155.65 97.1)
		(end 155.65 98.625)
		(width 0.2)
		(layer "B.Cu")
		(net 14)
	)
	(segment
		(start 117.8 96.975)
		(end 117.675 97.1)
		(width 0.2)
		(layer "B.Cu")
		(net 14)
	)
	(segment
		(start 134.465 91.835)
		(end 134.45 91.85)
		(width 0.2)
		(layer "B.Cu")
		(net 14)
	)
	(segment
		(start 116.8 94.3)
		(end 115.025 94.3)
		(width 0.15)
		(layer "B.Cu")
		(net 14)
	)
	(segment
		(start 121.773 61.524)
		(end 121.776 61.524)
		(width 0.15)
		(layer "B.Cu")
		(net 14)
	)
	(segment
		(start 120.675 97.1)
		(end 120.675 98.625)
		(width 0.2)
		(layer "B.Cu")
		(net 14)
	)
	(segment
		(start 166.15 97.1)
		(end 166.15 98.625)
		(width 0.2)
		(layer "B.Cu")
		(net 14)
	)
	(segment
		(start 156.525 96.975)
		(end 156.65 97.1)
		(width 0.2)
		(layer "B.Cu")
		(net 14)
	)
	(segment
		(start 133.9 93.084518)
		(end 133.9 93.3575)
		(width 0.2)
		(layer "B.Cu")
		(net 14)
	)
	(segment
		(start 115.175 97.1)
		(end 115.175 98.625)
		(width 0.2)
		(layer "B.Cu")
		(net 14)
	)
	(segment
		(start 103.55 96.975)
		(end 103.675 97.1)
		(width 0.2)
		(layer "B.Cu")
		(net 14)
	)
	(segment
		(start 139.75 94.335)
		(end 139.115 94.335)
		(width 0.2)
		(layer "B.Cu")
		(net 14)
	)
	(segment
		(start 167.0875 94.25)
		(end 165.3125 94.25)
		(width 0.2)
		(layer "B.Cu")
		(net 14)
	)
	(segment
		(start 123.55 96.975)
		(end 123.675 97.1)
		(width 0.2)
		(layer "B.Cu")
		(net 14)
	)
	(segment
		(start 154.775 94.3)
		(end 156.55 94.3)
		(width 0.15)
		(layer "B.Cu")
		(net 14)
	)
	(segment
		(start 114.8005 89.5)
		(end 114.7005 89.6)
		(width 0.15)
		(layer "B.Cu")
		(net 14)
	)
	(segment
		(start 122.675 97.1)
		(end 122.675 98.625)
		(width 0.2)
		(layer "B.Cu")
		(net 14)
	)
	(segment
		(start 156.385 92)
		(end 156.95 92)
		(width 0.15)
		(layer "B.Cu")
		(net 14)
	)
	(segment
		(start 130.291 78.5)
		(end 129.975 78.5)
		(width 0.2)
		(layer "B.Cu")
		(net 14)
	)
	(segment
		(start 105.695 89.57)
		(end 104.23 89.57)
		(width 0.15)
		(layer "B.Cu")
		(net 14)
	)
	(segment
		(start 106.766 85.3)
		(end 106.766 84.717)
		(width 0.15)
		(layer "B.Cu")
		(net 14)
	)
	(segment
		(start 139.259 81.5)
		(end 139.575 81.5)
		(width 0.2)
		(layer "B.Cu")
		(net 14)
	)
	(segment
		(start 127.15 97.1)
		(end 127.15 98.625)
		(width 0.2)
		(layer "B.Cu")
		(net 14)
	)
	(segment
		(start 128.5875 94.25)
		(end 128.5875 94.2875)
		(width 0.2)
		(layer "B.Cu")
		(net 14)
	)
	(segment
		(start 153.0875 94.25)
		(end 151.3125 94.25)
		(width 0.15)
		(layer "B.Cu")
		(net 14)
	)
	(segment
		(start 161.5405 89.465)
		(end 161.5255 89.45)
		(width 0.15)
		(layer "B.Cu")
		(net 14)
	)
	(segment
		(start 167.15 97.1)
		(end 167.15 98.625)
		(width 0.2)
		(layer "B.Cu")
		(net 14)
	)
	(segment
		(start 115.05 96.975)
		(end 115.175 97.1)
		(width 0.2)
		(layer "B.Cu")
		(net 14)
	)
	(segment
		(start 106.299 84.25)
		(end 105.95 84.25)
		(width 0.15)
		(layer "B.Cu")
		(net 14)
	)
	(segment
		(start 117.475 66.475)
		(end 117.5 66.5)
		(width 0.15)
		(layer "B.Cu")
		(net 14)
	)
	(segment
		(start 132.065 94.25)
		(end 132.1 94.285)
		(width 0.2)
		(layer "B.Cu")
		(net 14)
	)
	(segment
		(start 117.475 65.4)
		(end 117.475 66.475)
		(width 0.15)
		(layer "B.Cu")
		(net 14)
	)
	(segment
		(start 134.297259 92.687259)
		(end 133.9 93.084518)
		(width 0.2)
		(layer "B.Cu")
		(net 14)
	)
	(segment
		(start 141.025 96.975)
		(end 141.15 97.1)
		(width 0.2)
		(layer "B.Cu")
		(net 14)
	)
	(segment
		(start 119.8 96.975)
		(end 119.675 97.1)
		(width 0.2)
		(layer "B.Cu")
		(net 14)
	)
	(segment
		(start 161.15 97.1)
		(end 161.15 98.625)
		(width 0.2)
		(layer "B.Cu")
		(net 14)
	)
	(segment
		(start 130.291 81.5)
		(end 129.975 81.5)
		(width 0.2)
		(layer "B.Cu")
		(net 14)
	)
	(segment
		(start 145.6 94.9)
		(end 145.6 94.735)
		(width 0.2)
		(layer "B.Cu")
		(net 14)
	)
	(segment
		(start 105.675 97.1)
		(end 105.675 98.625)
		(width 0.2)
		(layer "B.Cu")
		(net 14)
	)
	(segment
		(start 115.195 92.02)
		(end 114.7005 92.02)
		(width 0.15)
		(layer "B.Cu")
		(net 14)
	)
	(segment
		(start 161.825 94.25)
		(end 161.825 94.5995)
		(width 0.2)
		(layer "B.Cu")
		(net 14)
	)
	(segment
		(start 128.5875 94.25)
		(end 126.8125 94.25)
		(width 0.2)
		(layer "B.Cu")
		(net 14)
	)
	(segment
		(start 108.3 96.975)
		(end 108.175 97.1)
		(width 0.2)
		(layer "B.Cu")
		(net 14)
	)
	(segment
		(start 167.025 96.975)
		(end 167.15 97.1)
		(width 0.2)
		(layer "B.Cu")
		(net 14)
	)
	(segment
		(start 167.0875 94.5875)
		(end 167.0875 94.25)
		(width 0.2)
		(layer "B.Cu")
		(net 14)
	)
	(segment
		(start 165.15 98.625)
		(end 165.15 97)
		(width 0.2)
		(layer "B.Cu")
		(net 14)
	)
	(segment
		(start 116.175 97.1)
		(end 116.175 98.625)
		(width 0.2)
		(layer "B.Cu")
		(net 14)
	)
	(segment
		(start 141.15 97.1)
		(end 141.15 98.625)
		(width 0.2)
		(layer "B.Cu")
		(net 14)
	)
	(segment
		(start 129.4125 94.25)
		(end 132.065 94.25)
		(width 0.2)
		(layer "B.Cu")
		(net 14)
	)
	(segment
		(start 163.15 97.1)
		(end 163.15 98.625)
		(width 0.2)
		(layer "B.Cu")
		(net 14)
	)
	(segment
		(start 142.65 97.1)
		(end 142.65 98.625)
		(width 0.2)
		(layer "B.Cu")
		(net 14)
	)
	(segment
		(start 107.3 96.975)
		(end 107.175 97.1)
		(width 0.2)
		(layer "B.Cu")
		(net 14)
	)
	(segment
		(start 109.7625 94.662)
		(end 110.225 95.1245)
		(width 0.15)
		(layer "B.Cu")
		(net 14)
	)
	(segment
		(start 167.3595 89.465)
		(end 167.3745 89.45)
		(width 0.15)
		(layer "B.Cu")
		(net 14)
	)
	(segment
		(start 163.275 96.975)
		(end 163.15 97.1)
		(width 0.2)
		(layer "B.Cu")
		(net 14)
	)
	(segment
		(start 144.275 96.975)
		(end 144.15 97.1)
		(width 0.2)
		(layer "B.Cu")
		(net 14)
	)
	(segment
		(start 153.65 97.1)
		(end 153.65 98.625)
		(width 0.2)
		(layer "B.Cu")
		(net 14)
	)
	(segment
		(start 157.525 96.975)
		(end 157.65 97.1)
		(width 0.2)
		(layer "B.Cu")
		(net 14)
	)
	(segment
		(start 158.65 97.1)
		(end 158.65 98.625)
		(width 0.2)
		(layer "B.Cu")
		(net 14)
	)
	(segment
		(start 104.2005 91.95)
		(end 104.64 91.95)
		(width 0.2)
		(layer "B.Cu")
		(net 14)
	)
	(segment
		(start 155.385 89.31)
		(end 156.89 89.31)
		(width 0.15)
		(layer "B.Cu")
		(net 14)
	)
	(segment
		(start 138.435 94.335)
		(end 138.45 94.35)
		(width 0.2)
		(layer "B.Cu")
		(net 14)
	)
	(segment
		(start 155.525 96.975)
		(end 155.65 97.1)
		(width 0.2)
		(layer "B.Cu")
		(net 14)
	)
	(segment
		(start 119.675 97.1)
		(end 119.675 98.625)
		(width 0.2)
		(layer "B.Cu")
		(net 14)
	)
	(segment
		(start 127.275 96.975)
		(end 127.15 97.1)
		(width 0.2)
		(layer "B.Cu")
		(net 14)
	)
	(segment
		(start 131.759 82.5)
		(end 131.875 82.5)
		(width 0.2)
		(layer "B.Cu")
		(net 14)
	)
	(segment
		(start 116.176 61.524)
		(end 116.2 61.5)
		(width 0.15)
		(layer "B.Cu")
		(net 14)
	)
	(segment
		(start 136.65 97.1)
		(end 136.65 98.625)
		(width 0.2)
		(layer "B.Cu")
		(net 14)
	)
	(segment
		(start 120.5495 89.6)
		(end 120.4495 89.5)
		(width 0.15)
		(layer "B.Cu")
		(net 14)
	)
	(segment
		(start 149.025 96.975)
		(end 149.15 97.1)
		(width 0.2)
		(layer "B.Cu")
		(net 14)
	)
	(segment
		(start 139.275 85.6)
		(end 138.975 85.6)
		(width 0.2)
		(layer "B.Cu")
		(net 14)
	)
	(segment
		(start 161.275 96.975)
		(end 161.15 97.1)
		(width 0.2)
		(layer "B.Cu")
		(net 14)
	)
	(segment
		(start 153.775 96.975)
		(end 153.65 97.1)
		(width 0.2)
		(layer "B.Cu")
		(net 14)
	)
	(segment
		(start 151.65 97.1)
		(end 151.65 98.625)
		(width 0.2)
		(layer "B.Cu")
		(net 14)
	)
	(segment
		(start 139.891 73.8)
		(end 139.891 73.884)
		(width 0.2)
		(layer "B.Cu")
		(net 14)
	)
	(segment
		(start 157.65 97.1)
		(end 157.65 98.625)
		(width 0.2)
		(layer "B.Cu")
		(net 14)
	)
	(segment
		(start 151.775 96.975)
		(end 151.65 97.1)
		(width 0.2)
		(layer "B.Cu")
		(net 14)
	)
	(segment
		(start 137.791 82.5)
		(end 137.675 82.5)
		(width 0.2)
		(layer "B.Cu")
		(net 14)
	)
	(segment
		(start 150.65 97.1)
		(end 150.65 98.625)
		(width 0.2)
		(layer "B.Cu")
		(net 14)
	)
	(segment
		(start 163.6 94.25)
		(end 161.825 94.25)
		(width 0.2)
		(layer "B.Cu")
		(net 14)
	)
	(segment
		(start 148.15 97.1)
		(end 148.15 98.625)
		(width 0.2)
		(layer "B.Cu")
		(net 14)
	)
	(segment
		(start 116.05 96.975)
		(end 116.175 97.1)
		(width 0.2)
		(layer "B.Cu")
		(net 14)
	)
	(segment
		(start 152.5 89.31)
		(end 151.01 89.31)
		(width 0.15)
		(layer "B.Cu")
		(net 14)
	)
	(segment
		(start 154.65 98.625)
		(end 154.65 97)
		(width 0.2)
		(layer "B.Cu")
		(net 14)
	)
	(segment
		(start 139.115 94.335)
		(end 139.1 94.35)
		(width 0.2)
		(layer "B.Cu")
		(net 14)
	)
	(segment
		(start 147.15 97.1)
		(end 147.15 98.625)
		(width 0.2)
		(layer "B.Cu")
		(net 14)
	)
	(segment
		(start 136.15 91.835)
		(end 135.15 91.835)
		(width 0.2)
		(layer "B.Cu")
		(net 14)
	)
	(segment
		(start 122.55 96.975)
		(end 122.675 97.1)
		(width 0.2)
		(layer "B.Cu")
		(net 14)
	)
	(segment
		(start 121.675 98.625)
		(end 121.675 97)
		(width 0.2)
		(layer "B.Cu")
		(net 14)
	)
	(segment
		(start 148.025 96.975)
		(end 148.15 97.1)
		(width 0.2)
		(layer "B.Cu")
		(net 14)
	)
	(segment
		(start 120.8 96.975)
		(end 120.675 97.1)
		(width 0.2)
		(layer "B.Cu")
		(net 14)
	)
	(segment
		(start 114.548 63.95)
		(end 118.075 63.95)
		(width 0.2)
		(layer "B.Cu")
		(net 15)
	)
	(segment
		(start 114.548 63.95)
		(end 114.498 64)
		(width 0.2)
		(layer "B.Cu")
		(net 15)
	)
	(segment
		(start 118.075 63.95)
		(end 118.475 64.35)
		(width 0.2)
		(layer "B.Cu")
		(net 15)
	)
	(segment
		(start 118.475 65.4)
		(end 118.475 64.35)
		(width 0.2)
		(layer "B.Cu")
		(net 15)
	)
	(segment
		(start 168.275 61.55)
		(end 168.275 61.85)
		(width 0.1524)
		(layer "F.Cu")
		(net 16)
	)
	(segment
		(start 168.275 61.85)
		(end 168.36 61.935)
		(width 0.1524)
		(layer "F.Cu")
		(net 16)
	)
	(segment
		(start 168.224 61.499)
		(end 168.275 61.55)
		(width 0.1524)
		(layer "F.Cu")
		(net 16)
	)
	(segment
		(start 168.36 61.935)
		(end 168.875 61.935)
		(width 0.1524)
		(layer "F.Cu")
		(net 16)
	)
	(segment
		(start 167.676 61.499)
		(end 168.224 61.499)
		(width 0.1524)
		(layer "F.Cu")
		(net 16)
	)
	(segment
		(start 167.823 64.098)
		(end 167.675 63.95)
		(width 0.1524)
		(layer "F.Cu")
		(net 17)
	)
	(segment
		(start 168.175 64.098)
		(end 167.823 64.098)
		(width 0.1524)
		(layer "F.Cu")
		(net 17)
	)
	(segment
		(start 167.675 63.95)
		(end 167.676 63.949)
		(width 0.1524)
		(layer "F.Cu")
		(net 17)
	)
	(segment
		(start 167.676 63.949)
		(end 167.676 62.999)
		(width 0.1524)
		(layer "F.Cu")
		(net 17)
	)
	(segment
		(start 102.15 98.625)
		(end 102.15 97.3)
		(width 0.15)
		(layer "B.Cu")
		(net 18)
	)
	(segment
		(start 106.299 81.549)
		(end 106.299 80.234)
		(width 0.15)
		(layer "B.Cu")
		(net 18)
	)
	(segment
		(start 102.15 97.3)
		(end 102.375 97.075)
		(width 0.15)
		(layer "B.Cu")
		(net 18)
	)
	(segment
		(start 102.375 83.475)
		(end 104.301 81.549)
		(width 0.15)
		(layer "B.Cu")
		(net 18)
	)
	(segment
		(start 104.301 81.549)
		(end 106.299 81.549)
		(width 0.15)
		(layer "B.Cu")
		(net 18)
	)
	(segment
		(start 102.375 97.075)
		(end 102.375 83.475)
		(width 0.15)
		(layer "B.Cu")
		(net 18)
	)
	(segment
		(start 106.299 80.234)
		(end 106.25 80.185)
		(width 0.15)
		(layer "B.Cu")
		(net 18)
	)
	(segment
		(start 108.25 80.185)
		(end 108.25 81.498)
		(width 0.15)
		(layer "B.Cu")
		(net 19)
	)
	(segment
		(start 102.7 97.2)
		(end 102.65 97.25)
		(width 0.15)
		(layer "B.Cu")
		(net 19)
	)
	(segment
		(start 102.65 97.25)
		(end 102.65 98.625)
		(width 0.15)
		(layer "B.Cu")
		(net 19)
	)
	(segment
		(start 108.199 82.201)
		(end 108.05 82.35)
		(width 0.15)
		(layer "B.Cu")
		(net 19)
	)
	(segment
		(start 108.25 81.498)
		(end 108.199 81.549)
		(width 0.15)
		(layer "B.Cu")
		(net 19)
	)
	(segment
		(start 108.05 82.35)
		(end 104.25 82.35)
		(width 0.15)
		(layer "B.Cu")
		(net 19)
	)
	(segment
		(start 102.7 83.9)
		(end 102.7 97.2)
		(width 0.15)
		(layer "B.Cu")
		(net 19)
	)
	(segment
		(start 108.199 81.549)
		(end 108.199 82.201)
		(width 0.15)
		(layer "B.Cu")
		(net 19)
	)
	(segment
		(start 104.25 82.35)
		(end 102.7 83.9)
		(width 0.15)
		(layer "B.Cu")
		(net 19)
	)
	(segment
		(start 103.5 67.525)
		(end 102.5875 67.525)
		(width 0.182)
		(layer "F.Cu")
		(net 20)
	)
	(segment
		(start 161.59 65.35)
		(end 161.2 65.35)
		(width 0.15)
		(layer "F.Cu")
		(net 20)
	)
	(segment
		(start 104.5 82.95)
		(end 104.5 81.1)
		(width 0.15)
		(layer "F.Cu")
		(net 20)
	)
	(via
		(at 104.5 82.95)
		(size 0.4)
		(drill 0.15)
		(layers "F.Cu" "B.Cu")
		(net 20)
	)
	(via
		(at 161.2 65.35)
		(size 0.4)
		(drill 0.15)
		(layers "F.Cu" "B.Cu")
		(net 20)
	)
	(via
		(at 104.5 81.1)
		(size 0.4)
		(drill 0.15)
		(layers "F.Cu" "B.Cu")
		(net 20)
	)
	(via
		(at 102.5875 67.525)
		(size 0.45)
		(drill 0.2)
		(layers "F.Cu" "B.Cu")
		(net 20)
	)
	(segment
		(start 106.5 76.5)
		(end 108.8 76.5)
		(width 0.15)
		(layer "B.Cu")
		(net 20)
	)
	(segment
		(start 104.5 81.1)
		(end 104.5 78.5)
		(width 0.15)
		(layer "B.Cu")
		(net 20)
	)
	(segment
		(start 112.6 68.6)
		(end 131.55 68.6)
		(width 0.15)
		(layer "B.Cu")
		(net 20)
	)
	(segment
		(start 110.1 75.2)
		(end 110.8 75.2)
		(width 0.15)
		(layer "B.Cu")
		(net 20)
	)
	(segment
		(start 111.5 74.5)
		(end 111.5 69.7)
		(width 0.15)
		(layer "B.Cu")
		(net 20)
	)
	(segment
		(start 111.5 69.7)
		(end 112.6 68.6)
		(width 0.15)
		(layer "B.Cu")
		(net 20)
	)
	(segment
		(start 134.8 65.35)
		(end 161.2 65.35)
		(width 0.15)
		(layer "B.Cu")
		(net 20)
	)
	(segment
		(start 104.5 78.5)
		(end 106.5 76.5)
		(width 0.15)
		(layer "B.Cu")
		(net 20)
	)
	(segment
		(start 103.1 84.15)
		(end 103.1 98.575)
		(width 0.15)
		(layer "B.Cu")
		(net 20)
	)
	(segment
		(start 104.5 82.95)
		(end 104.3 82.95)
		(width 0.15)
		(layer "B.Cu")
		(net 20)
	)
	(segment
		(start 108.8 76.5)
		(end 110.1 75.2)
		(width 0.15)
		(layer "B.Cu")
		(net 20)
	)
	(segment
		(start 131.55 68.6)
		(end 134.8 65.35)
		(width 0.15)
		(layer "B.Cu")
		(net 20)
	)
	(segment
		(start 104.3 82.95)
		(end 103.1 84.15)
		(width 0.15)
		(layer "B.Cu")
		(net 20)
	)
	(segment
		(start 110.8 75.2)
		(end 111.5 74.5)
		(width 0.15)
		(layer "B.Cu")
		(net 20)
	)
	(segment
		(start 103.45 72.3)
		(end 103.45 67.7)
		(width 0.15)
		(layer "In2.Cu")
		(net 20)
	)
	(segment
		(start 103.45 67.7)
		(end 103.275 67.525)
		(width 0.15)
		(layer "In2.Cu")
		(net 20)
	)
	(segment
		(start 104.5 81.1)
		(end 105.25 80.35)
		(width 0.15)
		(layer "In2.Cu")
		(net 20)
	)
	(segment
		(start 105.25 74.1)
		(end 103.45 72.3)
		(width 0.15)
		(layer "In2.Cu")
		(net 20)
	)
	(segment
		(start 105.25 80.35)
		(end 105.25 74.1)
		(width 0.15)
		(layer "In2.Cu")
		(net 20)
	)
	(segment
		(start 103.275 67.525)
		(end 102.5875 67.525)
		(width 0.15)
		(layer "In2.Cu")
		(net 20)
	)
	(segment
		(start 135.15 94.5775)
		(end 134.9 94.3275)
		(width 0.15)
		(layer "B.Cu")
		(net 33)
	)
	(segment
		(start 134.9 94.3275)
		(end 133.9 94.3275)
		(width 0.15)
		(layer "B.Cu")
		(net 33)
	)
	(segment
		(start 135.15 98.625)
		(end 135.15 94.5775)
		(width 0.15)
		(layer "B.Cu")
		(net 33)
	)
	(segment
		(start 145.7 95.4)
		(end 146.05 95.05)
		(width 0.15)
		(layer "F.Cu")
		(net 34)
	)
	(segment
		(start 143.4 96.79)
		(end 144.79 95.4)
		(width 0.15)
		(layer "F.Cu")
		(net 34)
	)
	(segment
		(start 146.05 95.05)
		(end 146.05 94.285)
		(width 0.15)
		(layer "F.Cu")
		(net 34)
	)
	(segment
		(start 144.79 95.4)
		(end 145.7 95.4)
		(width 0.15)
		(layer "F.Cu")
		(net 34)
	)
	(segment
		(start 143.4 98.625)
		(end 143.4 96.79)
		(width 0.15)
		(layer "F.Cu")
		(net 34)
	)
	(segment
		(start 102.125 61.1)
		(end 102.15 61.075)
		(width 0.2)
		(layer "F.Cu")
		(net 35)
	)
	(segment
		(start 101.2 61.1)
		(end 102.125 61.1)
		(width 0.2)
		(layer "F.Cu")
		(net 35)
	)
	(via
		(at 129.175 85.6)
		(size 0.4)
		(drill 0.15)
		(layers "F.Cu" "B.Cu")
		(net 35)
	)
	(via
		(at 142.8 85.7)
		(size 0.4)
		(drill 0.15)
		(layers "F.Cu" "B.Cu")
		(net 35)
	)
	(via
		(at 129.175 74.4)
		(size 0.4)
		(drill 0.15)
		(layers "F.Cu" "B.Cu")
		(net 35)
	)
	(via
		(at 106.32 83.32)
		(size 0.4)
		(drill 0.15)
		(layers "F.Cu" "B.Cu")
		(net 35)
	)
	(via
		(at 113.6 69.1)
		(size 0.4)
		(drill 0.15)
		(layers "F.Cu" "B.Cu")
		(net 35)
	)
	(via
		(at 140.375 74.4)
		(size 0.4)
		(drill 0.2)
		(layers "F.Cu" "B.Cu")
		(net 35)
	)
	(via
		(at 140.375 85.6)
		(size 0.4)
		(drill 0.15)
		(layers "F.Cu" "B.Cu")
		(net 35)
	)
	(via
		(at 101.2 61.1)
		(size 0.4)
		(drill 0.15)
		(layers "F.Cu" "B.Cu")
		(net 35)
	)
	(via
		(at 126.5 85.8)
		(size 0.4)
		(drill 0.15)
		(layers "F.Cu" "B.Cu")
		(net 35)
	)
	(segment
		(start 129.175 85.6)
		(end 129.175 85.716)
		(width 0.2)
		(layer "B.Cu")
		(net 35)
	)
	(segment
		(start 140.375 85.716)
		(end 140.859 86.2)
		(width 0.2)
		(layer "B.Cu")
		(net 35)
	)
	(segment
		(start 113.6 69.1)
		(end 121.9 69.1)
		(width 0.4)
		(layer "B.Cu")
		(net 35)
	)
	(segment
		(start 106.92 83.32)
		(end 106.32 83.32)
		(width 0.15)
		(layer "B.Cu")
		(net 35)
	)
	(segment
		(start 108.199 84.25)
		(end 107.85 84.25)
		(width 0.15)
		(layer "B.Cu")
		(net 35)
	)
	(segment
		(start 107.734 84.715)
		(end 108.199 84.25)
		(width 0.15)
		(layer "B.Cu")
		(net 35)
	)
	(segment
		(start 126.85 86.15)
		(end 128.691 86.15)
		(width 0.4)
		(layer "B.Cu")
		(net 35)
	)
	(segment
		(start 140.859 73.75)
		(end 140.859 73.916)
		(width 0.3)
		(layer "B.Cu")
		(net 35)
	)
	(segment
		(start 140.859 86.15)
		(end 142.35 86.15)
		(width 0.4)
		(layer "B.Cu")
		(net 35)
	)
	(segment
		(start 142.35 86.15)
		(end 142.8 85.7)
		(width 0.4)
		(layer "B.Cu")
		(net 35)
	)
	(segment
		(start 129.175 85.716)
		(end 128.691 86.2)
		(width 0.2)
		(layer "B.Cu")
		(net 35)
	)
	(segment
		(start 107.734 85.3)
		(end 107.734 84.715)
		(width 0.15)
		(layer "B.Cu")
		(net 35)
	)
	(segment
		(start 121.9 69.1)
		(end 126.55 73.75)
		(width 0.4)
		(layer "B.Cu")
		(net 35)
	)
	(segment
		(start 140.859 73.916)
		(end 140.375 74.4)
		(width 0.3)
		(layer "B.Cu")
		(net 35)
	)
	(segment
		(start 140.375 85.6)
		(end 140.375 85.716)
		(width 0.2)
		(layer "B.Cu")
		(net 35)
	)
	(segment
		(start 129.175 74.284)
		(end 128.691 73.8)
		(width 0.4)
		(layer "B.Cu")
		(net 35)
	)
	(segment
		(start 126.55 73.75)
		(end 128.691 73.75)
		(width 0.4)
		(layer "B.Cu")
		(net 35)
	)
	(segment
		(start 107.85 84.25)
		(end 106.92 83.32)
		(width 0.15)
		(layer "B.Cu")
		(net 35)
	)
	(segment
		(start 129.175 74.4)
		(end 129.175 74.284)
		(width 0.4)
		(layer "B.Cu")
		(net 35)
	)
	(segment
		(start 126.5 85.8)
		(end 126.85 86.15)
		(width 0.4)
		(layer "B.Cu")
		(net 35)
	)
	(segment
		(start 104.9 64.8)
		(end 107.3 64.8)
		(width 0.4)
		(layer "In2.Cu")
		(net 35)
	)
	(segment
		(start 126 74.4)
		(end 129.175 74.4)
		(width 0.4)
		(layer "In2.Cu")
		(net 35)
	)
	(segment
		(start 144.925 84.075)
		(end 143.3 85.7)
		(width 0.4)
		(layer "In2.Cu")
		(net 35)
	)
	(segment
		(start 109.1 71.2)
		(end 111.2 69.1)
		(width 0.2)
		(layer "In2.Cu")
		(net 35)
	)
	(segment
		(start 108.7 80.94)
		(end 108.7 76.1)
		(width 0.2)
		(layer "In2.Cu")
		(net 35)
	)
	(segment
		(start 101.2 61.1)
		(end 104.9 64.8)
		(width 0.4)
		(layer "In2.Cu")
		(net 35)
	)
	(segment
		(start 109.1 75.7)
		(end 109.1 71.2)
		(width 0.2)
		(layer "In2.Cu")
		(net 35)
	)
	(segment
		(start 111.55 66.15)
		(end 113.6 68.2)
		(width 0.4)
		(layer "In2.Cu")
		(net 35)
	)
	(segment
		(start 143 74.4)
		(end 144.925 76.325)
		(width 0.4)
		(layer "In2.Cu")
		(net 35)
	)
	(segment
		(start 143.3 85.7)
		(end 142.8 85.7)
		(width 0.4)
		(layer "In2.Cu")
		(net 35)
	)
	(segment
		(start 144.925 76.325)
		(end 144.925 84.075)
		(width 0.4)
		(layer "In2.Cu")
		(net 35)
	)
	(segment
		(start 126.2 85.8)
		(end 125 84.6)
		(width 0.4)
		(layer "In2.Cu")
		(net 35)
	)
	(segment
		(start 139.775 73.8)
		(end 140.375 74.4)
		(width 0.4)
		(layer "In2.Cu")
		(net 35)
	)
	(segment
		(start 125 75.4)
		(end 126 74.4)
		(width 0.4)
		(layer "In2.Cu")
		(net 35)
	)
	(segment
		(start 108.7 76.1)
		(end 109.1 75.7)
		(width 0.2)
		(layer "In2.Cu")
		(net 35)
	)
	(segment
		(start 111.2 69.1)
		(end 113.6 69.1)
		(width 0.2)
		(layer "In2.Cu")
		(net 35)
	)
	(segment
		(start 107.3 64.8)
		(end 108.65 66.15)
		(width 0.4)
		(layer "In2.Cu")
		(net 35)
	)
	(segment
		(start 126.5 85.8)
		(end 126.2 85.8)
		(width 0.4)
		(layer "In2.Cu")
		(net 35)
	)
	(segment
		(start 113.6 68.2)
		(end 113.6 69.1)
		(width 0.4)
		(layer "In2.Cu")
		(net 35)
	)
	(segment
		(start 139.775 73.8)
		(end 129.775 73.8)
		(width 0.4)
		(layer "In2.Cu")
		(net 35)
	)
	(segment
		(start 108.65 66.15)
		(end 111.55 66.15)
		(width 0.4)
		(layer "In2.Cu")
		(net 35)
	)
	(segment
		(start 140.375 74.4)
		(end 143 74.4)
		(width 0.4)
		(layer "In2.Cu")
		(net 35)
	)
	(segment
		(start 125 84.6)
		(end 125 75.4)
		(width 0.4)
		(layer "In2.Cu")
		(net 35)
	)
	(segment
		(start 106.32 83.32)
		(end 108.7 80.94)
		(width 0.2)
		(layer "In2.Cu")
		(net 35)
	)
	(segment
		(start 129.775 73.8)
		(end 129.175 74.4)
		(width 0.4)
		(layer "In2.Cu")
		(net 35)
	)
	(segment
		(start 110.672 68.178)
		(end 110.7 68.15)
		(width 0.15)
		(layer "F.Cu")
		(net 38)
	)
	(segment
		(start 109.7755 68.178)
		(end 110.672 68.178)
		(width 0.15)
		(layer "F.Cu")
		(net 38)
	)
	(segment
		(start 119.423 65.45)
		(end 119.473 65.4)
		(width 0.15)
		(layer "F.Cu")
		(net 38)
	)
	(via
		(at 110.7 68.15)
		(size 0.4)
		(drill 0.15)
		(layers "F.Cu" "B.Cu")
		(net 38)
	)
	(via
		(at 119.473 65.4)
		(size 0.4)
		(drill 0.15)
		(layers "F.Cu" "B.Cu")
		(net 38)
	)
	(via
		(at 108.25 78.55)
		(size 0.4)
		(drill 0.15)
		(layers "F.Cu" "B.Cu")
		(net 38)
	)
	(segment
		(start 118.1 67.8)
		(end 119.473 66.427)
		(width 0.15)
		(layer "B.Cu")
		(net 38)
	)
	(segment
		(start 108.25 79.215)
		(end 108.25 78.55)
		(width 0.2)
		(layer "B.Cu")
		(net 38)
	)
	(segment
		(start 111.05 68.15)
		(end 111.4 67.8)
		(width 0.15)
		(layer "B.Cu")
		(net 38)
	)
	(segment
		(start 111.4 67.8)
		(end 118.1 67.8)
		(width 0.15)
		(layer "B.Cu")
		(net 38)
	)
	(segment
		(start 119.473 66.427)
		(end 119.473 65.4)
		(width 0.15)
		(layer "B.Cu")
		(net 38)
	)
	(segment
		(start 110.7 68.15)
		(end 111.05 68.15)
		(width 0.15)
		(layer "B.Cu")
		(net 38)
	)
	(segment
		(start 110.7 68.15)
		(end 110.3 68.15)
		(width 0.15)
		(layer "In2.Cu")
		(net 38)
	)
	(segment
		(start 110 69.15)
		(end 107.8 71.35)
		(width 0.15)
		(layer "In2.Cu")
		(net 38)
	)
	(segment
		(start 107.8 77.65)
		(end 108.25 78.1)
		(width 0.15)
		(layer "In2.Cu")
		(net 38)
	)
	(segment
		(start 110.3 68.15)
		(end 110 68.45)
		(width 0.15)
		(layer "In2.Cu")
		(net 38)
	)
	(segment
		(start 110 68.45)
		(end 110 69.15)
		(width 0.15)
		(layer "In2.Cu")
		(net 38)
	)
	(segment
		(start 108.25 78.1)
		(end 108.25 78.55)
		(width 0.15)
		(layer "In2.Cu")
		(net 38)
	)
	(segment
		(start 107.8 71.35)
		(end 107.8 77.65)
		(width 0.15)
		(layer "In2.Cu")
		(net 38)
	)
	(segment
		(start 109.7755 67.525)
		(end 110.725 67.525)
		(width 0.15)
		(layer "F.Cu")
		(net 39)
	)
	(segment
		(start 120.475 65.401)
		(end 120.474 65.4)
		(width 0.15)
		(layer "F.Cu")
		(net 39)
	)
	(segment
		(start 110.725 67.525)
		(end 110.75 67.5)
		(width 0.15)
		(layer "F.Cu")
		(net 39)
	)
	(via
		(at 106.25 78.55)
		(size 0.4)
		(drill 0.15)
		(layers "F.Cu" "B.Cu")
		(net 39)
	)
	(via
		(at 110.75 67.5)
		(size 0.4)
		(drill 0.15)
		(layers "F.Cu" "B.Cu")
		(net 39)
	)
	(via
		(at 120.474 65.4)
		(size 0.4)
		(drill 0.15)
		(layers "F.Cu" "B.Cu")
		(net 39)
	)
	(segment
		(start 111.2 67.4)
		(end 117.9 67.4)
		(width 0.15)
		(layer "B.Cu")
		(net 39)
	)
	(segment
		(start 106.25 79.215)
		(end 106.25 78.55)
		(width 0.2)
		(layer "B.Cu")
		(net 39)
	)
	(segment
		(start 117.9 67.4)
		(end 118.95 66.35)
		(width 0.15)
		(layer "B.Cu")
		(net 39)
	)
	(segment
		(start 120.474 64.374)
		(end 120.474 65.4)
		(width 0.15)
		(layer "B.Cu")
		(net 39)
	)
	(segment
		(start 118.95 64.4)
		(end 119.1 64.25)
		(width 0.15)
		(layer "B.Cu")
		(net 39)
	)
	(segment
		(start 111.1 67.5)
		(end 111.2 67.4)
		(width 0.15)
		(layer "B.Cu")
		(net 39)
	)
	(segment
		(start 118.95 66.35)
		(end 118.95 64.4)
		(width 0.15)
		(layer "B.Cu")
		(net 39)
	)
	(segment
		(start 120.35 64.25)
		(end 120.474 64.374)
		(width 0.15)
		(layer "B.Cu")
		(net 39)
	)
	(segment
		(start 110.75 67.5)
		(end 111.1 67.5)
		(width 0.15)
		(layer "B.Cu")
		(net 39)
	)
	(segment
		(start 119.1 64.25)
		(end 120.35 64.25)
		(width 0.15)
		(layer "B.Cu")
		(net 39)
	)
	(segment
		(start 106.25 78.55)
		(end 106.25 75)
		(width 0.15)
		(layer "In2.Cu")
		(net 39)
	)
	(segment
		(start 107.45 71.15)
		(end 109.55 69.05)
		(width 0.15)
		(layer "In2.Cu")
		(net 39)
	)
	(segment
		(start 109.85 67.5)
		(end 110.75 67.5)
		(width 0.15)
		(layer "In2.Cu")
		(net 39)
	)
	(segment
		(start 109.55 67.8)
		(end 109.85 67.5)
		(width 0.15)
		(layer "In2.Cu")
		(net 39)
	)
	(segment
		(start 106.25 75)
		(end 107.45 73.8)
		(width 0.15)
		(layer "In2.Cu")
		(net 39)
	)
	(segment
		(start 107.45 73.8)
		(end 107.45 71.15)
		(width 0.15)
		(layer "In2.Cu")
		(net 39)
	)
	(segment
		(start 109.55 69.05)
		(end 109.55 67.8)
		(width 0.15)
		(layer "In2.Cu")
		(net 39)
	)
	(segment
		(start 134.8 89)
		(end 133 89)
		(width 0.15)
		(layer "F.Cu")
		(net 40)
	)
	(segment
		(start 146.05 92.6)
		(end 146.05 93.315)
		(width 0.15)
		(layer "F.Cu")
		(net 40)
	)
	(segment
		(start 133 89)
		(end 132.6 88.6)
		(width 0.15)
		(layer "F.Cu")
		(net 40)
	)
	(segment
		(start 132.675 86.325)
		(end 132.675 85.6)
		(width 0.15)
		(layer "F.Cu")
		(net 40)
	)
	(segment
		(start 132.6 88.6)
		(end 132.6 86.4)
		(width 0.15)
		(layer "F.Cu")
		(net 40)
	)
	(segment
		(start 132.6 86.4)
		(end 132.675 86.325)
		(width 0.15)
		(layer "F.Cu")
		(net 40)
	)
	(via
		(at 134.8 89)
		(size 0.4)
		(drill 0.2)
		(layers "F.Cu" "B.Cu")
		(net 40)
	)
	(via
		(at 146.05 92.6)
		(size 0.4)
		(drill 0.2)
		(layers "F.Cu" "B.Cu")
		(net 40)
	)
	(segment
		(start 146.05 91.85)
		(end 146.05 92.6)
		(width 0.15)
		(layer "B.Cu")
		(net 40)
	)
	(segment
		(start 146.05 93.315)
		(end 146.05 92.6)
		(width 0.15)
		(layer "B.Cu")
		(net 40)
	)
	(segment
		(start 134.8 89)
		(end 143.2 89)
		(width 0.15)
		(layer "B.Cu")
		(net 40)
	)
	(segment
		(start 143.2 89)
		(end 146.05 91.85)
		(width 0.15)
		(layer "B.Cu")
		(net 40)
	)
	(segment
		(start 166.46 65.75)
		(end 166.46 65.35)
		(width 0.1524)
		(layer "F.Cu")
		(net 41)
	)
	(segment
		(start 165.325 66.55)
		(end 165.325 66.1)
		(width 0.1524)
		(layer "F.Cu")
		(net 41)
	)
	(segment
		(start 167.675 65.4)
		(end 167.1 65.4)
		(width 0.1524)
		(layer "F.Cu")
		(net 41)
	)
	(segment
		(start 167.05 65.35)
		(end 166.46 65.35)
		(width 0.1524)
		(layer "F.Cu")
		(net 41)
	)
	(segment
		(start 166.26 65.95)
		(end 166.46 65.75)
		(width 0.1524)
		(layer "F.Cu")
		(net 41)
	)
	(segment
		(start 102.9 93.8995)
		(end 102.9 98.625)
		(width 0.15)
		(layer "F.Cu")
		(net 41)
	)
	(segment
		(start 102.0005 93)
		(end 102.9 93.8995)
		(width 0.15)
		(layer "F.Cu")
		(net 41)
	)
	(segment
		(start 165.325 66.1)
		(end 165.475 65.95)
		(width 0.1524)
		(layer "F.Cu")
		(net 41)
	)
	(segment
		(start 165.475 65.95)
		(end 166.26 65.95)
		(width 0.1524)
		(layer "F.Cu")
		(net 41)
	)
	(segment
		(start 167.1 65.4)
		(end 167.05 65.35)
		(width 0.1524)
		(layer "F.Cu")
		(net 41)
	)
	(via
		(at 102.0005 93)
		(size 0.4)
		(drill 0.2)
		(layers "F.Cu" "B.Cu")
		(net 41)
	)
	(via
		(at 166.46 65.35)
		(size 0.4)
		(drill 0.2)
		(layers "F.Cu" "B.Cu")
		(net 41)
	)
	(segment
		(start 104.1 81.1)
		(end 102.0005 83.1995)
		(width 0.15)
		(layer "B.Cu")
		(net 41)
	)
	(segment
		(start 110.7 74.8)
		(end 110 74.8)
		(width 0.15)
		(layer "B.Cu")
		(net 41)
	)
	(segment
		(start 166.46 65.35)
		(end 166.46 61.8)
		(width 0.15)
		(layer "B.Cu")
		(net 41)
	)
	(segment
		(start 160.3 62)
		(end 125.6 62)
		(width 0.15)
		(layer "B.Cu")
		(net 41)
	)
	(segment
		(start 111.1 74.4)
		(end 110.7 74.8)
		(width 0.15)
		(layer "B.Cu")
		(net 41)
	)
	(segment
		(start 112.4 68.2)
		(end 111.1 69.5)
		(width 0.15)
		(layer "B.Cu")
		(net 41)
	)
	(segment
		(start 106.3 76.1)
		(end 104.1 78.3)
		(width 0.15)
		(layer "B.Cu")
		(net 41)
	)
	(segment
		(start 119.4 68.2)
		(end 112.4 68.2)
		(width 0.15)
		(layer "B.Cu")
		(net 41)
	)
	(segment
		(start 111.1 69.5)
		(end 111.1 74.4)
		(width 0.15)
		(layer "B.Cu")
		(net 41)
	)
	(segment
		(start 161 61.3)
		(end 160.3 62)
		(width 0.15)
		(layer "B.Cu")
		(net 41)
	)
	(segment
		(start 110 74.8)
		(end 108.7 76.1)
		(width 0.15)
		(layer "B.Cu")
		(net 41)
	)
	(segment
		(start 102.0005 83.1995)
		(end 102.0005 93)
		(width 0.15)
		(layer "B.Cu")
		(net 41)
	)
	(segment
		(start 108.7 76.1)
		(end 106.3 76.1)
		(width 0.15)
		(layer "B.Cu")
		(net 41)
	)
	(segment
		(start 104.1 78.3)
		(end 104.1 81.1)
		(width 0.15)
		(layer "B.Cu")
		(net 41)
	)
	(segment
		(start 125.6 62)
		(end 119.4 68.2)
		(width 0.15)
		(layer "B.Cu")
		(net 41)
	)
	(segment
		(start 166.46 61.8)
		(end 165.96 61.3)
		(width 0.15)
		(layer "B.Cu")
		(net 41)
	)
	(segment
		(start 165.96 61.3)
		(end 161 61.3)
		(width 0.15)
		(layer "B.Cu")
		(net 41)
	)
	(segment
		(start 126.878 92.8)
		(end 126.878 93.348)
		(width 0.15)
		(layer "F.Cu")
		(net 43)
	)
	(segment
		(start 126.878 93.348)
		(end 126.876 93.35)
		(width 0.15)
		(layer "F.Cu")
		(net 43)
	)
	(via
		(at 126.878 92.8)
		(size 0.4)
		(drill 0.2)
		(layers "F.Cu" "B.Cu")
		(net 43)
	)
	(via
		(at 132.675 80.8)
		(size 0.4)
		(drill 0.15)
		(layers "F.Cu" "B.Cu")
		(net 43)
	)
	(segment
		(start 126.878 93.35)
		(end 126.878 92.8)
		(width 0.15)
		(layer "B.Cu")
		(net 43)
	)
	(segment
		(start 134.06 91.966312)
		(end 133.92 92.106312)
		(width 0.15)
		(layer "In3.Cu")
		(net 43)
	)
	(segment
		(start 132.848812 87.115)
		(end 133.365 87.115)
		(width 0.15)
		(layer "In3.Cu")
		(net 43)
	)
	(segment
		(start 134.06 91.709669)
		(end 134.06 91.966312)
		(width 0.15)
		(layer "In3.Cu")
		(net 43)
	)
	(segment
		(start 132.62 86.886188)
		(end 132.848812 87.115)
		(width 0.15)
		(layer "In3.Cu")
		(net 43)
	)
	(segment
		(start 134.37 91.399669)
		(end 134.06 91.709669)
		(width 0.15)
		(layer "In3.Cu")
		(net 43)
	)
	(segment
		(start 133.365 87.115)
		(end 134.37 88.12)
		(width 0.15)
		(layer "In3.Cu")
		(net 43)
	)
	(segment
		(start 132.36 83.372904)
		(end 132.36 85.757549)
		(width 0.09)
		(layer "In3.Cu")
		(net 43)
	)
	(segment
		(start 132.295 85.822549)
		(end 132.62 86.147549)
		(width 0.15)
		(layer "In3.Cu")
		(net 43)
	)
	(segment
		(start 134.37 88.12)
		(end 134.37 91.399669)
		(width 0.15)
		(layer "In3.Cu")
		(net 43)
	)
	(segment
		(start 132.62 86.147549)
		(end 132.62 86.886188)
		(width 0.15)
		(layer "In3.Cu")
		(net 43)
	)
	(segment
		(start 132.33 81.145)
		(end 132.33 83.342904)
		(width 0.09)
		(layer "In3.Cu")
		(net 43)
	)
	(segment
		(start 132.36 85.757549)
		(end 132.295 85.822549)
		(width 0.09)
		(layer "In3.Cu")
		(net 43)
	)
	(segment
		(start 132.33 83.342904)
		(end 132.36 83.372904)
		(width 0.09)
		(layer "In3.Cu")
		(net 43)
	)
	(segment
		(start 132.100588 93.97)
		(end 128.02 93.97)
		(width 0.15)
		(layer "In3.Cu")
		(net 43)
	)
	(segment
		(start 133.46 94.11)
		(end 132.240588 94.11)
		(width 0.15)
		(layer "In3.Cu")
		(net 43)
	)
	(segment
		(start 133.92 93.65)
		(end 133.46 94.11)
		(width 0.15)
		(layer "In3.Cu")
		(net 43)
	)
	(segment
		(start 128.02 93.97)
		(end 126.878 92.828)
		(width 0.15)
		(layer "In3.Cu")
		(net 43)
	)
	(segment
		(start 132.675 80.8)
		(end 132.33 81.145)
		(width 0.09)
		(layer "In3.Cu")
		(net 43)
	)
	(segment
		(start 133.92 92.106312)
		(end 133.92 93.65)
		(width 0.15)
		(layer "In3.Cu")
		(net 43)
	)
	(segment
		(start 132.240588 94.11)
		(end 132.100588 93.97)
		(width 0.15)
		(layer "In3.Cu")
		(net 43)
	)
	(segment
		(start 126.878 92.828)
		(end 126.878 92.8)
		(width 0.15)
		(layer "In3.Cu")
		(net 43)
	)
	(segment
		(start 126.64 92.4)
		(end 127.008331 92.4)
		(width 0.15)
		(layer "F.Cu")
		(net 44)
	)
	(segment
		(start 126.77 91.29)
		(end 124.68 91.29)
		(width 0.15)
		(layer "F.Cu")
		(net 44)
	)
	(segment
		(start 125.9 94.12)
		(end 126.18 93.84)
		(width 0.15)
		(layer "F.Cu")
		(net 44)
	)
	(segment
		(start 124.68 91.29)
		(end 123.67 92.3)
		(width 0.15)
		(layer "F.Cu")
		(net 44)
	)
	(segment
		(start 127.408 92.802)
		(end 127.408 93.35)
		(width 0.15)
		(layer "F.Cu")
		(net 44)
	)
	(segment
		(start 127.008331 92.4)
		(end 127.408 92.799669)
		(width 0.15)
		(layer "F.Cu")
		(net 44)
	)
	(segment
		(start 131.115012 82.8)
		(end 130.925 82.990012)
		(width 0.09)
		(layer "F.Cu")
		(net 44)
	)
	(segment
		(start 123.67 93.56)
		(end 124.23 94.12)
		(width 0.15)
		(layer "F.Cu")
		(net 44)
	)
	(segment
		(start 126.18 93.84)
		(end 126.18 92.86)
		(width 0.15)
		(layer "F.Cu")
		(net 44)
	)
	(segment
		(start 131.975 81.6)
		(end 131.625 81.95)
		(width 0.09)
		(layer "F.Cu")
		(net 44)
	)
	(segment
		(start 130.925 82.990012)
		(end 130.925 85.925)
		(width 0.09)
		(layer "F.Cu")
		(net 44)
	)
	(segment
		(start 131.625 82.575)
		(end 131.4 82.8)
		(width 0.09)
		(layer "F.Cu")
		(net 44)
	)
	(segment
		(start 131.4 82.8)
		(end 131.115012 82.8)
		(width 0.09)
		(layer "F.Cu")
		(net 44)
	)
	(segment
		(start 126.18 92.86)
		(end 126.64 92.4)
		(width 0.15)
		(layer "F.Cu")
		(net 44)
	)
	(segment
		(start 124.23 94.12)
		(end 125.9 94.12)
		(width 0.15)
		(layer "F.Cu")
		(net 44)
	)
	(segment
		(start 127.408 92.799669)
		(end 127.408 92.802)
		(width 0.15)
		(layer "F.Cu")
		(net 44)
	)
	(segment
		(start 130.925 87.135)
		(end 126.77 91.29)
		(width 0.15)
		(layer "F.Cu")
		(net 44)
	)
	(segment
		(start 123.67 92.3)
		(end 123.67 93.56)
		(width 0.15)
		(layer "F.Cu")
		(net 44)
	)
	(segment
		(start 130.925 85.925)
		(end 130.925 87.135)
		(width 0.15)
		(layer "F.Cu")
		(net 44)
	)
	(segment
		(start 131.625 81.95)
		(end 131.625 82.575)
		(width 0.09)
		(layer "F.Cu")
		(net 44)
	)
	(via
		(at 127.408 92.802)
		(size 0.4)
		(drill 0.2)
		(layers "F.Cu" "B.Cu")
		(net 44)
	)
	(segment
		(start 127.408 93.352)
		(end 127.408 92.802)
		(width 0.15)
		(layer "B.Cu")
		(net 44)
	)
	(via
		(at 130.575 83.2)
		(size 0.4)
		(drill 0.15)
		(layers "F.Cu" "B.Cu")
		(net 45)
	)
	(segment
		(start 117.731601 89.136601)
		(end 118.095 89.5)
		(width 0.1016)
		(layer "B.Cu")
		(net 45)
	)
	(segment
		(start 117.328399 85.89)
		(end 117.43 85.89)
		(width 0.1016)
		(layer "B.Cu")
		(net 45)
	)
	(segment
		(start 122.8416 82.1216)
		(end 122.07605 82.1216)
		(width 0.1016)
		(layer "B.Cu")
		(net 45)
	)
	(segment
		(start 117.23 85.341601)
		(end 117.23 85.791601)
		(width 0.1016)
		(layer "B.Cu")
		(net 45)
	)
	(segment
		(start 129.525 82.675)
		(end 129.525 82.207554)
		(width 0.1)
		(layer "B.Cu")
		(net 45)
	)
	(segment
		(start 122.07605 82.1216)
		(end 118.760954 82.1216)
		(width 0.1016)
		(layer "B.Cu")
		(net 45)
	)
	(segment
		(start 123.6916 82.6232)
		(end 123.2416 82.6232)
		(width 0.1016)
		(layer "B.Cu")
		(net 45)
	)
	(segment
		(start 118.233202 84.491601)
		(end 118.233202 84.941601)
		(width 0.1016)
		(layer "B.Cu")
		(net 45)
	)
	(segment
		(start 123.9932 81.82)
		(end 123.9932 82.3216)
		(width 0.1016)
		(layer "B.Cu")
		(net 45)
	)
	(segment
		(start 117.731601 86.191601)
		(end 117.731601 87.432361)
		(width 0.1016)
		(layer "B.Cu")
		(net 45)
	)
	(segment
		(start 129.525 82.207554)
		(end 129.384208 82.066762)
		(width 0.1)
		(layer "B.Cu")
		(net 45)
	)
	(segment
		(start 118.13 90.455)
		(end 118.13 89.535)
		(width 0.1)
		(layer "B.Cu")
		(net 45)
	)
	(segment
		(start 124.5416 81.62)
		(end 124.0916 81.62)
		(width 0.1016)
		(layer "B.Cu")
		(net 45)
	)
	(segment
		(start 117.731601 87.432361)
		(end 117.731601 89.136601)
		(width 0.1016)
		(layer "B.Cu")
		(net 45)
	)
	(segment
		(start 126.942086 81.9416)
		(end 126.762086 82.1216)
		(width 0.1016)
		(layer "B.Cu")
		(net 45)
	)
	(segment
		(start 129.65 82.8)
		(end 129.525 82.675)
		(width 0.1)
		(layer "B.Cu")
		(net 45)
	)
	(segment
		(start 117.731601 83.150953)
		(end 117.731601 84.091601)
		(width 0.1016)
		(layer "B.Cu")
		(net 45)
	)
	(segment
		(start 130.575 83.2)
		(end 130.175 82.8)
		(width 0.1)
		(layer "B.Cu")
		(net 45)
	)
	(segment
		(start 117.83 84.19)
		(end 117.931601 84.19)
		(width 0.1016)
		(layer "B.Cu")
		(net 45)
	)
	(segment
		(start 118.760954 82.1216)
		(end 117.731601 83.150953)
		(width 0.1016)
		(layer "B.Cu")
		(net 45)
	)
	(segment
		(start 122.94 82.3216)
		(end 122.94 82.22)
		(width 0.1016)
		(layer "B.Cu")
		(net 45)
	)
	(segment
		(start 128.732086 82.2316)
		(end 128.207914 82.2316)
		(width 0.1016)
		(layer "B.Cu")
		(net 45)
	)
	(segment
		(start 129.384208 82.066762)
		(end 129.349046 82.0316)
		(width 0.1016)
		(layer "B.Cu")
		(net 45)
	)
	(segment
		(start 128.207914 82.2316)
		(end 127.917914 81.9416)
		(width 0.1016)
		(layer "B.Cu")
		(net 45)
	)
	(segment
		(start 117.931601 85.243202)
		(end 117.83 85.243202)
		(width 0.1016)
		(layer "B.Cu")
		(net 45)
	)
	(segment
		(start 126.762086 82.1216)
		(end 124.9416 82.1216)
		(width 0.1016)
		(layer "B.Cu")
		(net 45)
	)
	(segment
		(start 130.175 82.8)
		(end 129.65 82.8)
		(width 0.1)
		(layer "B.Cu")
		(net 45)
	)
	(segment
		(start 123.9932 81.7184)
		(end 123.9932 81.82)
		(width 0.1016)
		(layer "B.Cu")
		(net 45)
	)
	(segment
		(start 127.917914 81.9416)
		(end 126.942086 81.9416)
		(width 0.1016)
		(layer "B.Cu")
		(net 45)
	)
	(segment
		(start 118.13 89.535)
		(end 118.095 89.5)
		(width 0.1)
		(layer "B.Cu")
		(net 45)
	)
	(segment
		(start 129.349046 82.0316)
		(end 128.932086 82.0316)
		(width 0.1016)
		(layer "B.Cu")
		(net 45)
	)
	(segment
		(start 117.83 85.243202)
		(end 117.328399 85.243202)
		(width 0.1016)
		(layer "B.Cu")
		(net 45)
	)
	(segment
		(start 128.932086 82.0316)
		(end 128.732086 82.2316)
		(width 0.1016)
		(layer "B.Cu")
		(net 45)
	)
	(segment
		(start 124.64 81.82)
		(end 124.64 81.7184)
		(width 0.1016)
		(layer "B.Cu")
		(net 45)
	)
	(arc
		(start 123.9932 82.3216)
		(mid 123.904863 82.534863)
		(end 123.6916 82.6232)
		(width 0.1016)
		(layer "B.Cu")
		(net 45)
	)
	(arc
		(start 118.233202 84.941601)
		(mid 118.144865 85.154865)
		(end 117.931601 85.243202)
		(width 0.1016)
		(layer "B.Cu")
		(net 45)
	)
	(arc
		(start 117.931601 84.19)
		(mid 118.144865 84.278337)
		(end 118.233202 84.491601)
		(width 0.1016)
		(layer "B.Cu")
		(net 45)
	)
	(arc
		(start 124.64 81.7184)
		(mid 124.611179 81.648821)
		(end 124.5416 81.62)
		(width 0.1016)
		(layer "B.Cu")
		(net 45)
	)
	(arc
		(start 117.731601 84.091601)
		(mid 117.760421 84.16118)
		(end 117.83 84.19)
		(width 0.1016)
		(layer "B.Cu")
		(net 45)
	)
	(arc
		(start 123.2416 82.6232)
		(mid 123.028337 82.534863)
		(end 122.94 82.3216)
		(width 0.1016)
		(layer "B.Cu")
		(net 45)
	)
	(arc
		(start 117.328399 85.243202)
		(mid 117.25882 85.272022)
		(end 117.23 85.341601)
		(width 0.1016)
		(layer "B.Cu")
		(net 45)
	)
	(arc
		(start 117.43 85.89)
		(mid 117.643264 85.978337)
		(end 117.731601 86.191601)
		(width 0.1016)
		(layer "B.Cu")
		(net 45)
	)
	(arc
		(start 122.94 82.22)
		(mid 122.911179 82.150421)
		(end 122.8416 82.1216)
		(width 0.1016)
		(layer "B.Cu")
		(net 45)
	)
	(arc
		(start 117.23 85.791601)
		(mid 117.25882 85.86118)
		(end 117.328399 85.89)
		(width 0.1016)
		(layer "B.Cu")
		(net 45)
	)
	(arc
		(start 124.9416 82.1216)
		(mid 124.728337 82.033263)
		(end 124.64 81.82)
		(width 0.1016)
		(layer "B.Cu")
		(net 45)
	)
	(arc
		(start 124.0916 81.62)
		(mid 124.022021 81.648821)
		(end 123.9932 81.7184)
		(width 0.1016)
		(layer "B.Cu")
		(net 45)
	)
	(via
		(at 129.875 82.4)
		(size 0.4)
		(drill 0.15)
		(layers "F.Cu" "B.Cu")
		(net 46)
	)
	(segment
		(start 117.528399 89.136601)
		(end 117.165 89.5)
		(width 0.1016)
		(layer "B.Cu")
		(net 46)
	)
	(segment
		(start 124.5416 81.4168)
		(end 124.0916 81.4168)
		(width 0.1016)
		(layer "B.Cu")
		(net 46)
	)
	(segment
		(start 117.528399 87.432361)
		(end 117.528399 89.136601)
		(width 0.1016)
		(layer "B.Cu")
		(net 46)
	)
	(segment
		(start 122.8416 81.9184)
		(end 122.07605 81.9184)
		(width 0.1016)
		(layer "B.Cu")
		(net 46)
	)
	(segment
		(start 123.79 81.82)
		(end 123.79 82.3216)
		(width 0.1016)
		(layer "B.Cu")
		(net 46)
	)
	(segment
		(start 127.2734 81.6134)
		(end 127.2734 81.5634)
		(width 0.1016)
		(layer "B.Cu")
		(net 46)
	)
	(segment
		(start 123.6916 82.42)
		(end 123.2416 82.42)
		(width 0.1016)
		(layer "B.Cu")
		(net 46)
	)
	(segment
		(start 117.83 84.393202)
		(end 117.931601 84.393202)
		(width 0.1016)
		(layer "B.Cu")
		(net 46)
	)
	(segment
		(start 117.83 85.04)
		(end 117.328399 85.04)
		(width 0.1016)
		(layer "B.Cu")
		(net 46)
	)
	(segment
		(start 129.875 82.225)
		(end 129.78 82.13)
		(width 0.1)
		(layer "B.Cu")
		(net 46)
	)
	(segment
		(start 127.0234 81.5634)
		(end 127.0234 81.6134)
		(width 0.1016)
		(layer "B.Cu")
		(net 46)
	)
	(segment
		(start 117.026798 85.341601)
		(end 117.026798 85.791601)
		(width 0.1016)
		(layer "B.Cu")
		(net 46)
	)
	(segment
		(start 129.875 82.4)
		(end 129.875 82.225)
		(width 0.1)
		(layer "B.Cu")
		(net 46)
	)
	(segment
		(start 128.292086 82.0284)
		(end 128.002086 81.7384)
		(width 0.1016)
		(layer "B.Cu")
		(net 46)
	)
	(segment
		(start 129.430954 81.8284)
		(end 128.847914 81.8284)
		(width 0.1016)
		(layer "B.Cu")
		(net 46)
	)
	(segment
		(start 117.328399 86.093202)
		(end 117.43 86.093202)
		(width 0.1016)
		(layer "B.Cu")
		(net 46)
	)
	(segment
		(start 128.847914 81.8284)
		(end 128.647914 82.0284)
		(width 0.1016)
		(layer "B.Cu")
		(net 46)
	)
	(segment
		(start 118.679046 81.9184)
		(end 117.528399 83.069047)
		(width 0.1016)
		(layer "B.Cu")
		(net 46)
	)
	(segment
		(start 129.78 82.13)
		(end 129.732554 82.13)
		(width 0.1)
		(layer "B.Cu")
		(net 46)
	)
	(segment
		(start 118.03 84.491601)
		(end 118.03 84.941601)
		(width 0.1016)
		(layer "B.Cu")
		(net 46)
	)
	(segment
		(start 129.467716 81.865162)
		(end 129.430954 81.8284)
		(width 0.1016)
		(layer "B.Cu")
		(net 46)
	)
	(segment
		(start 127.5234 81.5634)
		(end 127.5234 81.6134)
		(width 0.1016)
		(layer "B.Cu")
		(net 46)
	)
	(segment
		(start 126.8984 81.7384)
		(end 126.857914 81.7384)
		(width 0.1016)
		(layer "B.Cu")
		(net 46)
	)
	(segment
		(start 129.732554 82.13)
		(end 129.467716 81.865162)
		(width 0.1)
		(layer "B.Cu")
		(net 46)
	)
	(segment
		(start 124.8432 81.82)
		(end 124.8432 81.7184)
		(width 0.1016)
		(layer "B.Cu")
		(net 46)
	)
	(segment
		(start 117.528399 83.069047)
		(end 117.528399 84.091601)
		(width 0.1016)
		(layer "B.Cu")
		(net 46)
	)
	(segment
		(start 117.931601 85.04)
		(end 117.83 85.04)
		(width 0.1016)
		(layer "B.Cu")
		(net 46)
	)
	(segment
		(start 126.677914 81.9184)
		(end 124.9416 81.9184)
		(width 0.1016)
		(layer "B.Cu")
		(net 46)
	)
	(segment
		(start 122.07605 81.9184)
		(end 118.679046 81.9184)
		(width 0.1016)
		(layer "B.Cu")
		(net 46)
	)
	(segment
		(start 117.13 90.455)
		(end 117.13 89.535)
		(width 0.1)
		(layer "B.Cu")
		(net 46)
	)
	(segment
		(start 128.647914 82.0284)
		(end 128.292086 82.0284)
		(width 0.1016)
		(layer "B.Cu")
		(net 46)
	)
	(segment
		(start 126.857914 81.7384)
		(end 126.677914 81.9184)
		(width 0.1016)
		(layer "B.Cu")
		(net 46)
	)
	(segment
		(start 123.79 81.7184)
		(end 123.79 81.82)
		(width 0.1016)
		(layer "B.Cu")
		(net 46)
	)
	(segment
		(start 127.7734 81.6134)
		(end 127.7734 81.5634)
		(width 0.1016)
		(layer "B.Cu")
		(net 46)
	)
	(segment
		(start 123.1432 82.3216)
		(end 123.1432 82.22)
		(width 0.1016)
		(layer "B.Cu")
		(net 46)
	)
	(segment
		(start 128.002086 81.7384)
		(end 127.8984 81.7384)
		(width 0.1016)
		(layer "B.Cu")
		(net 46)
	)
	(segment
		(start 117.13 89.535)
		(end 117.165 89.5)
		(width 0.1)
		(layer "B.Cu")
		(net 46)
	)
	(segment
		(start 117.528399 86.191601)
		(end 117.528399 87.432361)
		(width 0.1016)
		(layer "B.Cu")
		(net 46)
	)
	(arc
		(start 127.6484 81.4384)
		(mid 127.560012 81.475012)
		(end 127.5234 81.5634)
		(width 0.1016)
		(layer "B.Cu")
		(net 46)
	)
	(arc
		(start 117.328399 85.04)
		(mid 117.115135 85.128337)
		(end 117.026798 85.341601)
		(width 0.1016)
		(layer "B.Cu")
		(net 46)
	)
	(arc
		(start 127.7734 81.5634)
		(mid 127.736788 81.475012)
		(end 127.6484 81.4384)
		(width 0.1016)
		(layer "B.Cu")
		(net 46)
	)
	(arc
		(start 117.528399 84.091601)
		(mid 117.616736 84.304865)
		(end 117.83 84.393202)
		(width 0.1016)
		(layer "B.Cu")
		(net 46)
	)
	(arc
		(start 124.8432 81.7184)
		(mid 124.754863 81.505137)
		(end 124.5416 81.4168)
		(width 0.1016)
		(layer "B.Cu")
		(net 46)
	)
	(arc
		(start 117.931601 84.393202)
		(mid 118.00118 84.422022)
		(end 118.03 84.491601)
		(width 0.1016)
		(layer "B.Cu")
		(net 46)
	)
	(arc
		(start 117.43 86.093202)
		(mid 117.499579 86.122022)
		(end 117.528399 86.191601)
		(width 0.1016)
		(layer "B.Cu")
		(net 46)
	)
	(arc
		(start 127.8984 81.7384)
		(mid 127.810012 81.701788)
		(end 127.7734 81.6134)
		(width 0.1016)
		(layer "B.Cu")
		(net 46)
	)
	(arc
		(start 127.0234 81.6134)
		(mid 126.986788 81.701788)
		(end 126.8984 81.7384)
		(width 0.1016)
		(layer "B.Cu")
		(net 46)
	)
	(arc
		(start 127.5234 81.6134)
		(mid 127.486788 81.701788)
		(end 127.3984 81.7384)
		(width 0.1016)
		(layer "B.Cu")
		(net 46)
	)
	(arc
		(start 123.1432 82.22)
		(mid 123.054863 82.006737)
		(end 122.8416 81.9184)
		(width 0.1016)
		(layer "B.Cu")
		(net 46)
	)
	(arc
		(start 127.3984 81.7384)
		(mid 127.310012 81.701788)
		(end 127.2734 81.6134)
		(width 0.1016)
		(layer "B.Cu")
		(net 46)
	)
	(arc
		(start 127.2734 81.5634)
		(mid 127.236788 81.475012)
		(end 127.1484 81.4384)
		(width 0.1016)
		(layer "B.Cu")
		(net 46)
	)
	(arc
		(start 123.2416 82.42)
		(mid 123.172021 82.391179)
		(end 123.1432 82.3216)
		(width 0.1016)
		(layer "B.Cu")
		(net 46)
	)
	(arc
		(start 124.9416 81.9184)
		(mid 124.872021 81.889579)
		(end 124.8432 81.82)
		(width 0.1016)
		(layer "B.Cu")
		(net 46)
	)
	(arc
		(start 117.026798 85.791601)
		(mid 117.115135 86.004865)
		(end 117.328399 86.093202)
		(width 0.1016)
		(layer "B.Cu")
		(net 46)
	)
	(arc
		(start 124.0916 81.4168)
		(mid 123.878337 81.505137)
		(end 123.79 81.7184)
		(width 0.1016)
		(layer "B.Cu")
		(net 46)
	)
	(arc
		(start 123.79 82.3216)
		(mid 123.761179 82.391179)
		(end 123.6916 82.42)
		(width 0.1016)
		(layer "B.Cu")
		(net 46)
	)
	(arc
		(start 118.03 84.941601)
		(mid 118.00118 85.01118)
		(end 117.931601 85.04)
		(width 0.1016)
		(layer "B.Cu")
		(net 46)
	)
	(arc
		(start 127.1484 81.4384)
		(mid 127.060012 81.475012)
		(end 127.0234 81.5634)
		(width 0.1016)
		(layer "B.Cu")
		(net 46)
	)
	(via
		(at 129.875 77.6)
		(size 0.4)
		(drill 0.15)
		(layers "F.Cu" "B.Cu")
		(net 47)
	)
	(segment
		(start 129.875 77.6)
		(end 129.775 77.6)
		(width 0.1)
		(layer "B.Cu")
		(net 47)
	)
	(segment
		(start 129.449541 78.0384)
		(end 128.992086 78.0384)
		(width 0.1016)
		(layer "B.Cu")
		(net 47)
	)
	(segment
		(start 123.5908 77.1784)
		(end 123.4908 77.1784)
		(width 0.1016)
		(layer "B.Cu")
		(net 47)
	)
	(segment
		(start 125.408246 78.2292)
		(end 124.5408 78.2292)
		(width 0.1016)
		(layer "B.Cu")
		(net 47)
	)
	(segment
		(start 126.8616 77.5084)
		(end 126.8616 77.3584)
		(width 0.1016)
		(layer "B.Cu")
		(net 47)
	)
	(segment
		(start 120.245262 78.2292)
		(end 115.878246 78.2292)
		(width 0.1016)
		(layer "B.Cu")
		(net 47)
	)
	(segment
		(start 129.782262 77.6)
		(end 129.8 77.6)
		(width 0.1016)
		(layer "B.Cu")
		(net 47)
	)
	(segment
		(start 113.919046 87.5084)
		(end 108.027914 87.5084)
		(width 0.1016)
		(layer "B.Cu")
		(net 47)
	)
	(segment
		(start 126.1116 77.7584)
		(end 126.0616 77.7584)
		(width 0.1016)
		(layer "B.Cu")
		(net 47)
	)
	(segment
		(start 125.879046 77.7584)
		(end 125.408246 78.2292)
		(width 0.1016)
		(layer "B.Cu")
		(net 47)
	)
	(segment
		(start 128.208247 77.7284)
		(end 127.898247 78.0384)
		(width 0.1016)
		(layer "B.Cu")
		(net 47)
	)
	(segment
		(start 106.63 90.485)
		(end 106.63 89.605)
		(width 0.1)
		(layer "B.Cu")
		(net 47)
	)
	(segment
		(start 129.875 77.6)
		(end 129.8 77.6)
		(width 0.09)
		(layer "B.Cu")
		(net 47)
	)
	(segment
		(start 115.0892 79.018246)
		(end 115.0892 86.338246)
		(width 0.1016)
		(layer "B.Cu")
		(net 47)
	)
	(segment
		(start 126.3616 77.3584)
		(end 126.3616 77.5084)
		(width 0.1016)
		(layer "B.Cu")
		(net 47)
	)
	(segment
		(start 115.0892 86.338246)
		(end 113.919046 87.5084)
		(width 0.1016)
		(layer "B.Cu")
		(net 47)
	)
	(segment
		(start 129.670377 77.817564)
		(end 129.449541 78.0384)
		(width 0.1016)
		(layer "B.Cu")
		(net 47)
	)
	(segment
		(start 107.028399 88.507915)
		(end 107.028399 89.206601)
		(width 0.1016)
		(layer "B.Cu")
		(net 47)
	)
	(segment
		(start 122.915 77.7542)
		(end 122.915 77.855)
		(width 0.1016)
		(layer "B.Cu")
		(net 47)
	)
	(segment
		(start 122.0666 78.9058)
		(end 122.0666 78.805)
		(width 0.1016)
		(layer "B.Cu")
		(net 47)
	)
	(segment
		(start 115.878246 78.2292)
		(end 115.0892 79.018246)
		(width 0.1016)
		(layer "B.Cu")
		(net 47)
	)
	(segment
		(start 124.1666 77.855)
		(end 124.1666 77.7542)
		(width 0.1016)
		(layer "B.Cu")
		(net 47)
	)
	(segment
		(start 127.898247 78.0384)
		(end 127.453077 78.0384)
		(width 0.1016)
		(layer "B.Cu")
		(net 47)
	)
	(segment
		(start 127.173077 77.7584)
		(end 127.1116 77.7584)
		(width 0.1016)
		(layer "B.Cu")
		(net 47)
	)
	(segment
		(start 120.565 77.7542)
		(end 120.565 78.055)
		(width 0.1016)
		(layer "B.Cu")
		(net 47)
	)
	(segment
		(start 120.3908 78.2292)
		(end 120.245262 78.2292)
		(width 0.1016)
		(layer "B.Cu")
		(net 47)
	)
	(segment
		(start 106.63 89.605)
		(end 106.665 89.57)
		(width 0.1)
		(layer "B.Cu")
		(net 47)
	)
	(segment
		(start 129.775 77.6)
		(end 129.670377 77.6)
		(width 0.1016)
		(layer "B.Cu")
		(net 47)
	)
	(segment
		(start 121.3166 78.055)
		(end 121.3166 77.7542)
		(width 0.1016)
		(layer "B.Cu")
		(net 47)
	)
	(segment
		(start 129.670377 77.6)
		(end 129.670377 77.817564)
		(width 0.1016)
		(layer "B.Cu")
		(net 47)
	)
	(segment
		(start 122.5408 79.28)
		(end 122.4408 79.28)
		(width 0.1016)
		(layer "B.Cu")
		(net 47)
	)
	(segment
		(start 126.0616 77.7584)
		(end 125.879046 77.7584)
		(width 0.1016)
		(layer "B.Cu")
		(net 47)
	)
	(segment
		(start 107.028399 89.206601)
		(end 106.665 89.57)
		(width 0.1016)
		(layer "B.Cu")
		(net 47)
	)
	(segment
		(start 128.992086 78.0384)
		(end 128.682086 77.7284)
		(width 0.1016)
		(layer "B.Cu")
		(net 47)
	)
	(segment
		(start 122.915 77.855)
		(end 122.915 78.9058)
		(width 0.1016)
		(layer "B.Cu")
		(net 47)
	)
	(segment
		(start 108.027914 87.5084)
		(end 107.028399 88.507915)
		(width 0.1016)
		(layer "B.Cu")
		(net 47)
	)
	(segment
		(start 127.453077 78.0384)
		(end 127.173077 77.7584)
		(width 0.1016)
		(layer "B.Cu")
		(net 47)
	)
	(segment
		(start 128.682086 77.7284)
		(end 128.208247 77.7284)
		(width 0.1016)
		(layer "B.Cu")
		(net 47)
	)
	(arc
		(start 123.4908 77.1784)
		(mid 123.083648 77.347048)
		(end 122.915 77.7542)
		(width 0.1016)
		(layer "B.Cu")
		(net 47)
	)
	(arc
		(start 127.1116 77.7584)
		(mid 126.934823 77.685177)
		(end 126.8616 77.5084)
		(width 0.1016)
		(layer "B.Cu")
		(net 47)
	)
	(arc
		(start 122.0666 78.805)
		(mid 121.897952 78.397848)
		(end 121.4908 78.2292)
		(width 0.1016)
		(layer "B.Cu")
		(net 47)
	)
	(arc
		(start 126.3616 77.5084)
		(mid 126.288377 77.685177)
		(end 126.1116 77.7584)
		(width 0.1016)
		(layer "B.Cu")
		(net 47)
	)
	(arc
		(start 126.8616 77.3584)
		(mid 126.788377 77.181623)
		(end 126.6116 77.1084)
		(width 0.1016)
		(layer "B.Cu")
		(net 47)
	)
	(arc
		(start 120.565 78.055)
		(mid 120.513978 78.178178)
		(end 120.3908 78.2292)
		(width 0.1016)
		(layer "B.Cu")
		(net 47)
	)
	(arc
		(start 122.915 78.9058)
		(mid 122.805399 79.170399)
		(end 122.5408 79.28)
		(width 0.1016)
		(layer "B.Cu")
		(net 47)
	)
	(arc
		(start 121.4908 78.2292)
		(mid 121.367622 78.178178)
		(end 121.3166 78.055)
		(width 0.1016)
		(layer "B.Cu")
		(net 47)
	)
	(arc
		(start 124.5408 78.2292)
		(mid 124.276201 78.119599)
		(end 124.1666 77.855)
		(width 0.1016)
		(layer "B.Cu")
		(net 47)
	)
	(arc
		(start 122.4408 79.28)
		(mid 122.176201 79.170399)
		(end 122.0666 78.9058)
		(width 0.1016)
		(layer "B.Cu")
		(net 47)
	)
	(arc
		(start 124.1666 77.7542)
		(mid 123.997952 77.347048)
		(end 123.5908 77.1784)
		(width 0.1016)
		(layer "B.Cu")
		(net 47)
	)
	(arc
		(start 120.9408 77.3784)
		(mid 120.675069 77.488469)
		(end 120.565 77.7542)
		(width 0.1016)
		(layer "B.Cu")
		(net 47)
	)
	(arc
		(start 126.6116 77.1084)
		(mid 126.434823 77.181623)
		(end 126.3616 77.3584)
		(width 0.1016)
		(layer "B.Cu")
		(net 47)
	)
	(arc
		(start 121.3166 77.7542)
		(mid 121.206531 77.488469)
		(end 120.9408 77.3784)
		(width 0.1016)
		(layer "B.Cu")
		(net 47)
	)
	(via
		(at 130.575 76.8)
		(size 0.4)
		(drill 0.15)
		(layers "F.Cu" "B.Cu")
		(net 48)
	)
	(segment
		(start 107.63 90.485)
		(end 107.63 89.605)
		(width 0.1)
		(layer "B.Cu")
		(net 48)
	)
	(segment
		(start 130.575 76.8)
		(end 130.225 77.15)
		(width 0.1)
		(layer "B.Cu")
		(net 48)
	)
	(segment
		(start 125.491754 78.4308)
		(end 124.5408 78.4308)
		(width 0.1016)
		(layer "B.Cu")
		(net 48)
	)
	(segment
		(start 121.865 78.9058)
		(end 121.865 78.805)
		(width 0.1016)
		(layer "B.Cu")
		(net 48)
	)
	(segment
		(start 120.7666 77.7542)
		(end 120.7666 78.055)
		(width 0.1016)
		(layer "B.Cu")
		(net 48)
	)
	(segment
		(start 125.960954 77.9616)
		(end 125.491754 78.4308)
		(width 0.1016)
		(layer "B.Cu")
		(net 48)
	)
	(segment
		(start 129.795313 77.98)
		(end 129.533713 78.2416)
		(width 0.1016)
		(layer "B.Cu")
		(net 48)
	)
	(segment
		(start 108.112086 87.7116)
		(end 107.231601 88.592085)
		(width 0.1016)
		(layer "B.Cu")
		(net 48)
	)
	(segment
		(start 107.231601 89.206601)
		(end 107.595 89.57)
		(width 0.1016)
		(layer "B.Cu")
		(net 48)
	)
	(segment
		(start 123.1166 77.855)
		(end 123.1166 78.9058)
		(width 0.1016)
		(layer "B.Cu")
		(net 48)
	)
	(segment
		(start 119.926447 78.4308)
		(end 115.961754 78.4308)
		(width 0.1016)
		(layer "B.Cu")
		(net 48)
	)
	(segment
		(start 115.2908 86.421754)
		(end 114.000954 87.7116)
		(width 0.1016)
		(layer "B.Cu")
		(net 48)
	)
	(segment
		(start 127.982419 78.2416)
		(end 127.368905 78.2416)
		(width 0.1016)
		(layer "B.Cu")
		(net 48)
	)
	(segment
		(start 127.368905 78.2416)
		(end 127.088905 77.9616)
		(width 0.1016)
		(layer "B.Cu")
		(net 48)
	)
	(segment
		(start 128.292419 77.9316)
		(end 127.982419 78.2416)
		(width 0.1016)
		(layer "B.Cu")
		(net 48)
	)
	(segment
		(start 122.5408 79.4816)
		(end 122.4408 79.4816)
		(width 0.1016)
		(layer "B.Cu")
		(net 48)
	)
	(segment
		(start 120.3908 78.4308)
		(end 119.926447 78.4308)
		(width 0.1016)
		(layer "B.Cu")
		(net 48)
	)
	(segment
		(start 115.2908 79.101754)
		(end 115.2908 86.421754)
		(width 0.1016)
		(layer "B.Cu")
		(net 48)
	)
	(segment
		(start 123.5908 77.38)
		(end 123.4908 77.38)
		(width 0.1016)
		(layer "B.Cu")
		(net 48)
	)
	(segment
		(start 128.597914 77.9316)
		(end 128.292419 77.9316)
		(width 0.1016)
		(layer "B.Cu")
		(net 48)
	)
	(segment
		(start 130.225 77.79)
		(end 130.035 77.98)
		(width 0.1)
		(layer "B.Cu")
		(net 48)
	)
	(segment
		(start 128.907914 78.2416)
		(end 128.597914 77.9316)
		(width 0.1016)
		(layer "B.Cu")
		(net 48)
	)
	(segment
		(start 127.088905 77.9616)
		(end 125.960954 77.9616)
		(width 0.1016)
		(layer "B.Cu")
		(net 48)
	)
	(segment
		(start 123.1166 77.7542)
		(end 123.1166 77.855)
		(width 0.1016)
		(layer "B.Cu")
		(net 48)
	)
	(segment
		(start 121.115 78.055)
		(end 121.115 77.7542)
		(width 0.1016)
		(layer "B.Cu")
		(net 48)
	)
	(segment
		(start 129.533713 78.2416)
		(end 128.907914 78.2416)
		(width 0.1016)
		(layer "B.Cu")
		(net 48)
	)
	(segment
		(start 115.961754 78.4308)
		(end 115.2908 79.101754)
		(width 0.1016)
		(layer "B.Cu")
		(net 48)
	)
	(segment
		(start 107.231601 88.592085)
		(end 107.231601 89.206601)
		(width 0.1016)
		(layer "B.Cu")
		(net 48)
	)
	(segment
		(start 130.035 77.98)
		(end 129.795313 77.98)
		(width 0.1016)
		(layer "B.Cu")
		(net 48)
	)
	(segment
		(start 107.63 89.605)
		(end 107.595 89.57)
		(width 0.1)
		(layer "B.Cu")
		(net 48)
	)
	(segment
		(start 123.965 77.855)
		(end 123.965 77.7542)
		(width 0.1016)
		(layer "B.Cu")
		(net 48)
	)
	(segment
		(start 114.000954 87.7116)
		(end 108.112086 87.7116)
		(width 0.1016)
		(layer "B.Cu")
		(net 48)
	)
	(segment
		(start 130.225 77.15)
		(end 130.225 77.79)
		(width 0.1)
		(layer "B.Cu")
		(net 48)
	)
	(arc
		(start 123.1166 78.9058)
		(mid 122.947952 79.312952)
		(end 122.5408 79.4816)
		(width 0.1016)
		(layer "B.Cu")
		(net 48)
	)
	(arc
		(start 124.5408 78.4308)
		(mid 124.133648 78.262152)
		(end 123.965 77.855)
		(width 0.1016)
		(layer "B.Cu")
		(net 48)
	)
	(arc
		(start 123.965 77.7542)
		(mid 123.855399 77.489601)
		(end 123.5908 77.38)
		(width 0.1016)
		(layer "B.Cu")
		(net 48)
	)
	(arc
		(start 121.115 77.7542)
		(mid 121.063978 77.631022)
		(end 120.9408 77.58)
		(width 0.1016)
		(layer "B.Cu")
		(net 48)
	)
	(arc
		(start 123.4908 77.38)
		(mid 123.226201 77.489601)
		(end 123.1166 77.7542)
		(width 0.1016)
		(layer "B.Cu")
		(net 48)
	)
	(arc
		(start 120.7666 78.055)
		(mid 120.656531 78.320731)
		(end 120.3908 78.4308)
		(width 0.1016)
		(layer "B.Cu")
		(net 48)
	)
	(arc
		(start 121.4908 78.4308)
		(mid 121.225069 78.320731)
		(end 121.115 78.055)
		(width 0.1016)
		(layer "B.Cu")
		(net 48)
	)
	(arc
		(start 120.9408 77.58)
		(mid 120.817622 77.631022)
		(end 120.7666 77.7542)
		(width 0.1016)
		(layer "B.Cu")
		(net 48)
	)
	(arc
		(start 122.4408 79.4816)
		(mid 122.033648 79.312952)
		(end 121.865 78.9058)
		(width 0.1016)
		(layer "B.Cu")
		(net 48)
	)
	(arc
		(start 121.865 78.805)
		(mid 121.755399 78.540401)
		(end 121.4908 78.4308)
		(width 0.1016)
		(layer "B.Cu")
		(net 48)
	)
	(segment
		(start 135.4 90.141349)
		(end 135.55 90.291349)
		(width 0.1)
		(layer "F.Cu")
		(net 49)
	)
	(segment
		(start 135.55 90.291349)
		(end 135.55 90.465)
		(width 0.1)
		(layer "F.Cu")
		(net 49)
	)
	(segment
		(start 135.55 90.465)
		(end 135.15 90.865)
		(width 0.1)
		(layer "F.Cu")
		(net 49)
	)
	(via
		(at 132.675 79.2)
		(size 0.4)
		(drill 0.15)
		(layers "F.Cu" "B.Cu")
		(net 49)
	)
	(via
		(at 135.4 90.141349)
		(size 0.4)
		(drill 0.15)
		(layers "F.Cu" "B.Cu")
		(net 49)
	)
	(segment
		(start 135.55 90.291349)
		(end 135.55 90.465)
		(width 0.1)
		(layer "B.Cu")
		(net 49)
	)
	(segment
		(start 135.4 90.141349)
		(end 135.55 90.291349)
		(width 0.1)
		(layer "B.Cu")
		(net 49)
	)
	(segment
		(start 135.55 90.465)
		(end 135.15 90.865)
		(width 0.1)
		(layer "B.Cu")
		(net 49)
	)
	(segment
		(start 132.75 85.791422)
		(end 135.55 88.591422)
		(width 0.1)
		(layer "In3.Cu")
		(net 49)
	)
	(segment
		(start 132.925 79.766422)
		(end 133.15 79.991422)
		(width 0.1)
		(layer "In3.Cu")
		(net 49)
	)
	(segment
		(start 133.15 79.991422)
		(end 133.15 83.358578)
		(width 0.1)
		(layer "In3.Cu")
		(net 49)
	)
	(segment
		(start 135.55 88.591422)
		(end 135.55 89.991349)
		(width 0.1)
		(layer "In3.Cu")
		(net 49)
	)
	(segment
		(start 132.925 79.45)
		(end 132.925 79.766422)
		(width 0.1)
		(layer "In3.Cu")
		(net 49)
	)
	(segment
		(start 132.675 79.2)
		(end 132.925 79.45)
		(width 0.1)
		(layer "In3.Cu")
		(net 49)
	)
	(segment
		(start 132.75 83.758578)
		(end 132.75 85.791422)
		(width 0.1)
		(layer "In3.Cu")
		(net 49)
	)
	(segment
		(start 135.55 89.991349)
		(end 135.4 90.141349)
		(width 0.1)
		(layer "In3.Cu")
		(net 49)
	)
	(segment
		(start 133.15 83.358578)
		(end 132.75 83.758578)
		(width 0.1)
		(layer "In3.Cu")
		(net 49)
	)
	(segment
		(start 135.75 90.291349)
		(end 135.75 90.465)
		(width 0.1)
		(layer "F.Cu")
		(net 50)
	)
	(segment
		(start 135.75 90.465)
		(end 136.15 90.865)
		(width 0.1)
		(layer "F.Cu")
		(net 50)
	)
	(segment
		(start 135.9 90.141349)
		(end 135.75 90.291349)
		(width 0.1)
		(layer "F.Cu")
		(net 50)
	)
	(via
		(at 135.9 90.141349)
		(size 0.4)
		(drill 0.15)
		(layers "F.Cu" "B.Cu")
		(net 50)
	)
	(via
		(at 133.375 79.2)
		(size 0.4)
		(drill 0.15)
		(layers "F.Cu" "B.Cu")
		(net 50)
	)
	(segment
		(start 135.75 90.291349)
		(end 135.75 90.465)
		(width 0.1)
		(layer "B.Cu")
		(net 50)
	)
	(segment
		(start 135.9 90.141349)
		(end 135.75 90.291349)
		(width 0.1)
		(layer "B.Cu")
		(net 50)
	)
	(segment
		(start 135.75 90.465)
		(end 136.15 90.865)
		(width 0.1)
		(layer "B.Cu")
		(net 50)
	)
	(segment
		(start 135.75 89.991349)
		(end 135.9 90.141349)
		(width 0.1)
		(layer "In3.Cu")
		(net 50)
	)
	(segment
		(start 133.35 79.908578)
		(end 133.35 83.441422)
		(width 0.1)
		(layer "In3.Cu")
		(net 50)
	)
	(segment
		(start 133.125 79.683578)
		(end 133.35 79.908578)
		(width 0.1)
		(layer "In3.Cu")
		(net 50)
	)
	(segment
		(start 133.125 79.45)
		(end 133.125 79.683578)
		(width 0.1)
		(layer "In3.Cu")
		(net 50)
	)
	(segment
		(start 132.95 85.708578)
		(end 135.75 88.508578)
		(width 0.1)
		(layer "In3.Cu")
		(net 50)
	)
	(segment
		(start 132.95 83.841422)
		(end 132.95 85.708578)
		(width 0.1)
		(layer "In3.Cu")
		(net 50)
	)
	(segment
		(start 133.375 79.2)
		(end 133.125 79.45)
		(width 0.1)
		(layer "In3.Cu")
		(net 50)
	)
	(segment
		(start 135.75 88.508578)
		(end 135.75 89.991349)
		(width 0.1)
		(layer "In3.Cu")
		(net 50)
	)
	(segment
		(start 133.35 83.441422)
		(end 132.95 83.841422)
		(width 0.1)
		(layer "In3.Cu")
		(net 50)
	)
	(segment
		(start 167.115 66.45)
		(end 166.175 66.45)
		(width 0.2)
		(layer "F.Cu")
		(net 52)
	)
	(segment
		(start 167.775 65.95)
		(end 167.87 65.855)
		(width 0.2)
		(layer "F.Cu")
		(net 52)
	)
	(segment
		(start 165.16 64.15)
		(end 165.16 63.716)
		(width 0.2)
		(layer "F.Cu")
		(net 52)
	)
	(segment
		(start 165.975 66.65)
		(end 165.975 67.2)
		(width 0.2)
		(layer "F.Cu")
		(net 52)
	)
	(segment
		(start 166.775 64.65)
		(end 166.226 64.101)
		(width 0.2)
		(layer "F.Cu")
		(net 52)
	)
	(segment
		(start 167.775 64.65)
		(end 166.775 64.65)
		(width 0.2)
		(layer "F.Cu")
		(net 52)
	)
	(segment
		(start 166.226 64.101)
		(end 166.226 62.65)
		(width 0.2)
		(layer "F.Cu")
		(net 52)
	)
	(segment
		(start 167.115 66.45)
		(end 167.115 66.21)
		(width 0.2)
		(layer "F.Cu")
		(net 52)
	)
	(segment
		(start 167.375 65.95)
		(end 167.775 65.95)
		(width 0.2)
		(layer "F.Cu")
		(net 52)
	)
	(segment
		(start 168.175 65.05)
		(end 167.775 64.65)
		(width 0.2)
		(layer "F.Cu")
		(net 52)
	)
	(segment
		(start 165.16 63.716)
		(end 166.226 62.65)
		(width 0.2)
		(layer "F.Cu")
		(net 52)
	)
	(segment
		(start 166.175 66.45)
		(end 165.975 66.65)
		(width 0.2)
		(layer "F.Cu")
		(net 52)
	)
	(segment
		(start 168.175 65.65)
		(end 168.175 65.05)
		(width 0.2)
		(layer "F.Cu")
		(net 52)
	)
	(segment
		(start 167.87 65.855)
		(end 167.97 65.855)
		(width 0.2)
		(layer "F.Cu")
		(net 52)
	)
	(segment
		(start 167.97 65.855)
		(end 168.175 65.65)
		(width 0.2)
		(layer "F.Cu")
		(net 52)
	)
	(segment
		(start 167.115 66.21)
		(end 167.375 65.95)
		(width 0.2)
		(layer "F.Cu")
		(net 52)
	)
	(segment
		(start 163.573 63.648)
		(end 162.875 63.648)
		(width 0.2)
		(layer "F.Cu")
		(net 53)
	)
	(segment
		(start 161.575 63.35)
		(end 162.692 63.35)
		(width 0.2)
		(layer "F.Cu")
		(net 53)
	)
	(segment
		(start 162.692 63.35)
		(end 162.975 63.633)
		(width 0.2)
		(layer "F.Cu")
		(net 53)
	)
	(segment
		(start 164.175 64.25)
		(end 163.573 63.648)
		(width 0.2)
		(layer "F.Cu")
		(net 53)
	)
	(segment
		(start 164.19 64.25)
		(end 164.175 64.25)
		(width 0.2)
		(layer "F.Cu")
		(net 53)
	)
	(segment
		(start 130.025 92.797)
		(end 130.03 92.802)
		(width 0.15)
		(layer "F.Cu")
		(net 54)
	)
	(segment
		(start 130.03 92.802)
		(end 130.03 93.35)
		(width 0.15)
		(layer "F.Cu")
		(net 54)
	)
	(segment
		(start 130.025 91.825)
		(end 130.025 92.797)
		(width 0.15)
		(layer "F.Cu")
		(net 54)
	)
	(via
		(at 130.025 91.825)
		(size 0.4)
		(drill 0.2)
		(layers "F.Cu" "B.Cu")
		(net 54)
	)
	(via
		(at 132.675 77.6)
		(size 0.4)
		(drill 0.15)
		(layers "F.Cu" "B.Cu")
		(net 54)
	)
	(via
		(at 130.03 92.802)
		(size 0.4)
		(drill 0.2)
		(layers "F.Cu" "B.Cu")
		(net 54)
	)
	(segment
		(start 130.03 93.352)
		(end 130.03 92.802)
		(width 0.15)
		(layer "B.Cu")
		(net 54)
	)
	(segment
		(start 130.197 91.213)
		(end 130.197 91.558331)
		(width 0.15)
		(layer "In3.Cu")
		(net 54)
	)
	(segment
		(start 131.41 87.964623)
		(end 131.184623 88.19)
		(width 0.15)
		(layer "In3.Cu")
		(net 54)
	)
	(segment
		(start 132.325 77.95)
		(end 131.05 77.95)
		(width 0.09)
		(layer "In3.Cu")
		(net 54)
	)
	(segment
		(start 130.244335 91.605665)
		(end 130.025 91.825)
		(width 0.15)
		(layer "In3.Cu")
		(net 54)
	)
	(segment
		(start 131.05 89.69)
		(end 131.2 89.69)
		(width 0.15)
		(layer "In3.Cu")
		(net 54)
	)
	(segment
		(start 130.23 85.805)
		(end 130.23 85.97)
		(width 0.15)
		(layer "In3.Cu")
		(net 54)
	)
	(segment
		(start 131.22 89.71)
		(end 131.22 90.19)
		(width 0.15)
		(layer "In3.Cu")
		(net 54)
	)
	(segment
		(start 132.25 89.19)
		(end 131.05 89.19)
		(width 0.15)
		(layer "In3.Cu")
		(net 54)
	)
	(segment
		(start 130.23 78.77)
		(end 130.23 85.805)
		(width 0.09)
		(layer "In3.Cu")
		(net 54)
	)
	(segment
		(start 131.41 87.15)
		(end 131.41 87.964623)
		(width 0.15)
		(layer "In3.Cu")
		(net 54)
	)
	(segment
		(start 130.23 85.97)
		(end 131.41 87.15)
		(width 0.15)
		(layer "In3.Cu")
		(net 54)
	)
	(segment
		(start 131.05 88.69)
		(end 132.25 88.69)
		(width 0.15)
		(layer "In3.Cu")
		(net 54)
	)
	(segment
		(start 131.184623 88.19)
		(end 131.05 88.19)
		(width 0.15)
		(layer "In3.Cu")
		(net 54)
	)
	(segment
		(start 131.22 90.19)
		(end 130.197 91.213)
		(width 0.15)
		(layer "In3.Cu")
		(net 54)
	)
	(segment
		(start 131.05 77.95)
		(end 130.23 78.77)
		(width 0.09)
		(layer "In3.Cu")
		(net 54)
	)
	(segment
		(start 132.675 77.6)
		(end 132.325 77.95)
		(width 0.09)
		(layer "In3.Cu")
		(net 54)
	)
	(segment
		(start 131.2 89.69)
		(end 131.22 89.71)
		(width 0.15)
		(layer "In3.Cu")
		(net 54)
	)
	(segment
		(start 130.197 91.558331)
		(end 130.244335 91.605665)
		(width 0.15)
		(layer "In3.Cu")
		(net 54)
	)
	(arc
		(start 130.8 89.44)
		(mid 130.873223 89.616777)
		(end 131.05 89.69)
		(width 0.15)
		(layer "In3.Cu")
		(net 54)
	)
	(arc
		(start 132.25 88.69)
		(mid 132.426777 88.763223)
		(end 132.5 88.94)
		(width 0.15)
		(layer "In3.Cu")
		(net 54)
	)
	(arc
		(start 130.8 88.44)
		(mid 130.873223 88.616777)
		(end 131.05 88.69)
		(width 0.15)
		(layer "In3.Cu")
		(net 54)
	)
	(arc
		(start 131.05 88.19)
		(mid 130.873223 88.263223)
		(end 130.8 88.44)
		(width 0.15)
		(layer "In3.Cu")
		(net 54)
	)
	(arc
		(start 132.5 88.94)
		(mid 132.426777 89.116777)
		(end 132.25 89.19)
		(width 0.15)
		(layer "In3.Cu")
		(net 54)
	)
	(arc
		(start 131.05 89.19)
		(mid 130.873223 89.263223)
		(end 130.8 89.44)
		(width 0.15)
		(layer "In3.Cu")
		(net 54)
	)
	(segment
		(start 132 92.767)
		(end 132 93.315)
		(width 0.15)
		(layer "F.Cu")
		(net 55)
	)
	(via
		(at 132 92.767)
		(size 0.4)
		(drill 0.2)
		(layers "F.Cu" "B.Cu")
		(net 55)
	)
	(via
		(at 131.975 76.8)
		(size 0.4)
		(drill 0.15)
		(layers "F.Cu" "B.Cu")
		(net 55)
	)
	(segment
		(start 132 93.317)
		(end 132 92.767)
		(width 0.15)
		(layer "B.Cu")
		(net 55)
	)
	(segment
		(start 128.925 85.915)
		(end 128.83 85.82)
		(width 0.15)
		(layer "In3.Cu")
		(net 55)
	)
	(segment
		(start 129.027096 76.455)
		(end 128.83 76.652096)
		(width 0.09)
		(layer "In3.Cu")
		(net 55)
	)
	(segment
		(start 128.925 85.915)
		(end 128.925 93.05)
		(width 0.15)
		(layer "In3.Cu")
		(net 55)
	)
	(segment
		(start 131.725 93.525)
		(end 132 93.25)
		(width 0.15)
		(layer "In3.Cu")
		(net 55)
	)
	(segment
		(start 131.63 76.455)
		(end 129.027096 76.455)
		(width 0.09)
		(layer "In3.Cu")
		(net 55)
	)
	(segment
		(start 131.975 76.8)
		(end 131.63 76.455)
		(width 0.09)
		(layer "In3.Cu")
		(net 55)
	)
	(segment
		(start 132 93.25)
		(end 132 92.767)
		(width 0.15)
		(layer "In3.Cu")
		(net 55)
	)
	(segment
		(start 129.4 93.525)
		(end 131.725 93.525)
		(width 0.15)
		(layer "In3.Cu")
		(net 55)
	)
	(segment
		(start 128.83 76.652096)
		(end 128.83 85.82)
		(width 0.09)
		(layer "In3.Cu")
		(net 55)
	)
	(segment
		(start 128.925 93.05)
		(end 129.4 93.525)
		(width 0.15)
		(layer "In3.Cu")
		(net 55)
	)
	(segment
		(start 131.102 92.8)
		(end 131.102 93.348)
		(width 0.15)
		(layer "F.Cu")
		(net 56)
	)
	(via
		(at 132.675 76)
		(size 0.4)
		(drill 0.15)
		(layers "F.Cu" "B.Cu")
		(net 56)
	)
	(via
		(at 131.102 92.8)
		(size 0.4)
		(drill 0.2)
		(layers "F.Cu" "B.Cu")
		(net 56)
	)
	(segment
		(start 131.102 93.35)
		(end 131.102 92.8)
		(width 0.15)
		(layer "B.Cu")
		(net 56)
	)
	(segment
		(start 129.695 87.925)
		(end 130.045 87.925)
		(width 0.15)
		(layer "In3.Cu")
		(net 56)
	)
	(segment
		(start 132.675 76)
		(end 132.33 76.345)
		(width 0.09)
		(layer "In3.Cu")
		(net 56)
	)
	(segment
		(start 129.65 92.15)
		(end 129.85 92.35)
		(width 0.15)
		(layer "In3.Cu")
		(net 56)
	)
	(segment
		(start 130.045 87.325)
		(end 129.695 87.325)
		(width 0.15)
		(layer "In3.Cu")
		(net 56)
	)
	(segment
		(start 129.85 92.35)
		(end 130.652 92.35)
		(width 0.15)
		(layer "In3.Cu")
		(net 56)
	)
	(segment
		(start 129.87 86.12)
		(end 129.87 86.55)
		(width 0.15)
		(layer "In3.Cu")
		(net 56)
	)
	(segment
		(start 129.65 91.17)
		(end 129.65 92.15)
		(width 0.15)
		(layer "In3.Cu")
		(net 56)
	)
	(segment
		(start 130.22 86.9)
		(end 130.22 87.15)
		(width 0.15)
		(layer "In3.Cu")
		(net 56)
	)
	(segment
		(start 129.52 77.467096)
		(end 129.53 77.477096)
		(width 0.09)
		(layer "In3.Cu")
		(net 56)
	)
	(segment
		(start 129.87 88.7)
		(end 129.87 90.95)
		(width 0.15)
		(layer "In3.Cu")
		(net 56)
	)
	(segment
		(start 129.55 85.8)
		(end 129.87 86.12)
		(width 0.15)
		(layer "In3.Cu")
		(net 56)
	)
	(segment
		(start 130.045 88.525)
		(end 129.87 88.7)
		(width 0.15)
		(layer "In3.Cu")
		(net 56)
	)
	(segment
		(start 130.652 92.35)
		(end 131.102 92.8)
		(width 0.15)
		(layer "In3.Cu")
		(net 56)
	)
	(segment
		(start 129.87 90.95)
		(end 129.65 91.17)
		(width 0.15)
		(layer "In3.Cu")
		(net 56)
	)
	(segment
		(start 132.33 76.345)
		(end 132.33 76.97)
		(width 0.09)
		(layer "In3.Cu")
		(net 56)
	)
	(segment
		(start 132.33 76.97)
		(end 132.1 77.2)
		(width 0.09)
		(layer "In3.Cu")
		(net 56)
	)
	(segment
		(start 129.52 87.5)
		(end 129.52 87.75)
		(width 0.15)
		(layer "In3.Cu")
		(net 56)
	)
	(segment
		(start 130.22 88.1)
		(end 130.22 88.35)
		(width 0.15)
		(layer "In3.Cu")
		(net 56)
	)
	(segment
		(start 129.53 77.477096)
		(end 129.53 85.78)
		(width 0.09)
		(layer "In3.Cu")
		(net 56)
	)
	(segment
		(start 132.1 77.2)
		(end 129.787096 77.2)
		(width 0.09)
		(layer "In3.Cu")
		(net 56)
	)
	(segment
		(start 129.787096 77.2)
		(end 129.52 77.467096)
		(width 0.09)
		(layer "In3.Cu")
		(net 56)
	)
	(segment
		(start 129.53 85.78)
		(end 129.55 85.8)
		(width 0.09)
		(layer "In3.Cu")
		(net 56)
	)
	(arc
		(start 129.52 87.75)
		(mid 129.571256 87.873744)
		(end 129.695 87.925)
		(width 0.15)
		(layer "In3.Cu")
		(net 56)
	)
	(arc
		(start 130.22 87.15)
		(mid 130.168744 87.273744)
		(end 130.045 87.325)
		(width 0.15)
		(layer "In3.Cu")
		(net 56)
	)
	(arc
		(start 130.22 88.35)
		(mid 130.168744 88.473744)
		(end 130.045 88.525)
		(width 0.15)
		(layer "In3.Cu")
		(net 56)
	)
	(arc
		(start 130.045 87.925)
		(mid 130.168744 87.976256)
		(end 130.22 88.1)
		(width 0.15)
		(layer "In3.Cu")
		(net 56)
	)
	(arc
		(start 129.695 87.325)
		(mid 129.571256 87.376256)
		(end 129.52 87.5)
		(width 0.15)
		(layer "In3.Cu")
		(net 56)
	)
	(arc
		(start 130.045 86.725)
		(mid 130.168744 86.776256)
		(end 130.22 86.9)
		(width 0.15)
		(layer "In3.Cu")
		(net 56)
	)
	(arc
		(start 129.87 86.55)
		(mid 129.921256 86.673744)
		(end 130.045 86.725)
		(width 0.15)
		(layer "In3.Cu")
		(net 56)
	)
	(segment
		(start 130.875 89.25)
		(end 130.875 90)
		(width 0.15)
		(layer "F.Cu")
		(net 57)
	)
	(segment
		(start 127.95 92.802)
		(end 127.95 91.25)
		(width 0.15)
		(layer "F.Cu")
		(net 57)
	)
	(segment
		(start 131.825 87.275)
		(end 131.325 87.275)
		(width 0.15)
		(layer "F.Cu")
		(net 57)
	)
	(segment
		(start 127.95 91.25)
		(end 129 90.2)
		(width 0.15)
		(layer "F.Cu")
		(net 57)
	)
	(segment
		(start 130.675 88.175)
		(end 131.825 88.175)
		(width 0.15)
		(layer "F.Cu")
		(net 57)
	)
	(segment
		(start 132 90.4)
		(end 132 90)
		(width 0.15)
		(layer "F.Cu")
		(net 57)
	)
	(segment
		(start 129.675 90.275)
		(end 129.675 89.25)
		(width 0.15)
		(layer "F.Cu")
		(net 57)
	)
	(segment
		(start 130.15 90.35)
		(end 130.4 90.35)
		(width 0.15)
		(layer "F.Cu")
		(net 57)
	)
	(segment
		(start 131.075 87.575)
		(end 131.825 87.575)
		(width 0.15)
		(layer "F.Cu")
		(net 57)
	)
	(segment
		(start 131.6 90.4)
		(end 132 90.4)
		(width 0.15)
		(layer "F.Cu")
		(net 57)
	)
	(segment
		(start 131.4 90.2)
		(end 131.6 90.4)
		(width 0.15)
		(layer "F.Cu")
		(net 57)
	)
	(segment
		(start 129.35 90.35)
		(end 129.6 90.35)
		(width 0.15)
		(layer "F.Cu")
		(net 57)
	)
	(segment
		(start 131.8 89.1)
		(end 131.625 88.925)
		(width 0.15)
		(layer "F.Cu")
		(net 57)
	)
	(segment
		(start 131.075 90.2)
		(end 131.4 90.2)
		(width 0.15)
		(layer "F.Cu")
		(net 57)
	)
	(segment
		(start 131.8 89.8)
		(end 131.8 89.1)
		(width 0.15)
		(layer "F.Cu")
		(net 57)
	)
	(segment
		(start 130.075 89.25)
		(end 130.075 90.275)
		(width 0.15)
		(layer "F.Cu")
		(net 57)
	)
	(segment
		(start 131.825 88.475)
		(end 130.675 88.475)
		(width 0.15)
		(layer "F.Cu")
		(net 57)
	)
	(segment
		(start 127.95 92.802)
		(end 127.95 93.35)
		(width 0.15)
		(layer "F.Cu")
		(net 57)
	)
	(segment
		(start 132 90)
		(end 131.8 89.8)
		(width 0.15)
		(layer "F.Cu")
		(net 57)
	)
	(segment
		(start 131.625 83.55)
		(end 131.975 83.2)
		(width 0.09)
		(layer "F.Cu")
		(net 57)
	)
	(segment
		(start 131.325 86.975)
		(end 131.475 86.975)
		(width 0.15)
		(layer "F.Cu")
		(net 57)
	)
	(segment
		(start 131.775 88.775)
		(end 131.825 88.775)
		(width 0.15)
		(layer "F.Cu")
		(net 57)
	)
	(segment
		(start 131.625 86.825)
		(end 131.625 85.875)
		(width 0.15)
		(layer "F.Cu")
		(net 57)
	)
	(segment
		(start 131.825 87.875)
		(end 131.075 87.875)
		(width 0.15)
		(layer "F.Cu")
		(net 57)
	)
	(segment
		(start 129 90.2)
		(end 129.2 90.2)
		(width 0.15)
		(layer "F.Cu")
		(net 57)
	)
	(segment
		(start 131.625 85.875)
		(end 131.625 83.55)
		(width 0.09)
		(layer "F.Cu")
		(net 57)
	)
	(segment
		(start 130.475 90.275)
		(end 130.475 89.25)
		(width 0.15)
		(layer "F.Cu")
		(net 57)
	)
	(via
		(at 127.95 92.802)
		(size 0.4)
		(drill 0.2)
		(layers "F.Cu" "B.Cu")
		(net 57)
	)
	(arc
		(start 131.325 87.275)
		(mid 131.218934 87.231066)
		(end 131.175 87.125)
		(width 0.15)
		(layer "F.Cu")
		(net 57)
	)
	(arc
		(start 129.6 90.35)
		(mid 129.653033 90.328033)
		(end 129.675 90.275)
		(width 0.15)
		(layer "F.Cu")
		(net 57)
	)
	(arc
		(start 131.625 88.925)
		(mid 131.668934 88.818934)
		(end 131.775 88.775)
		(width 0.15)
		(layer "F.Cu")
		(net 57)
	)
	(arc
		(start 130.675 88.475)
		(mid 130.568934 88.431066)
		(end 130.525 88.325)
		(width 0.15)
		(layer "F.Cu")
		(net 57)
	)
	(arc
		(start 130.875 90)
		(mid 130.933579 90.141421)
		(end 131.075 90.2)
		(width 0.15)
		(layer "F.Cu")
		(net 57)
	)
	(arc
		(start 131.825 88.775)
		(mid 131.931066 88.731066)
		(end 131.975 88.625)
		(width 0.15)
		(layer "F.Cu")
		(net 57)
	)
	(arc
		(start 131.075 87.875)
		(mid 130.968934 87.831066)
		(end 130.925 87.725)
		(width 0.15)
		(layer "F.Cu")
		(net 57)
	)
	(arc
		(start 130.475 89.25)
		(mid 130.533579 89.108579)
		(end 130.675 89.05)
		(width 0.15)
		(layer "F.Cu")
		(net 57)
	)
	(arc
		(start 131.975 88.625)
		(mid 131.931066 88.518934)
		(end 131.825 88.475)
		(width 0.15)
		(layer "F.Cu")
		(net 57)
	)
	(arc
		(start 129.875 89.05)
		(mid 130.016421 89.108579)
		(end 130.075 89.25)
		(width 0.15)
		(layer "F.Cu")
		(net 57)
	)
	(arc
		(start 130.925 87.725)
		(mid 130.968934 87.618934)
		(end 131.075 87.575)
		(width 0.15)
		(layer "F.Cu")
		(net 57)
	)
	(arc
		(start 131.975 88.025)
		(mid 131.931066 87.918934)
		(end 131.825 87.875)
		(width 0.15)
		(layer "F.Cu")
		(net 57)
	)
	(arc
		(start 129.675 89.25)
		(mid 129.733579 89.108579)
		(end 129.875 89.05)
		(width 0.15)
		(layer "F.Cu")
		(net 57)
	)
	(arc
		(start 130.525 88.325)
		(mid 130.568934 88.218934)
		(end 130.675 88.175)
		(width 0.15)
		(layer "F.Cu")
		(net 57)
	)
	(arc
		(start 129.275 90.275)
		(mid 129.296967 90.328033)
		(end 129.35 90.35)
		(width 0.15)
		(layer "F.Cu")
		(net 57)
	)
	(arc
		(start 130.675 89.05)
		(mid 130.816421 89.108579)
		(end 130.875 89.25)
		(width 0.15)
		(layer "F.Cu")
		(net 57)
	)
	(arc
		(start 130.075 90.275)
		(mid 130.096967 90.328033)
		(end 130.15 90.35)
		(width 0.15)
		(layer "F.Cu")
		(net 57)
	)
	(arc
		(start 131.975 87.425)
		(mid 131.931066 87.318934)
		(end 131.825 87.275)
		(width 0.15)
		(layer "F.Cu")
		(net 57)
	)
	(arc
		(start 131.175 87.125)
		(mid 131.218934 87.018934)
		(end 131.325 86.975)
		(width 0.15)
		(layer "F.Cu")
		(net 57)
	)
	(arc
		(start 130.4 90.35)
		(mid 130.453033 90.328033)
		(end 130.475 90.275)
		(width 0.15)
		(layer "F.Cu")
		(net 57)
	)
	(arc
		(start 131.475 86.975)
		(mid 131.581066 86.931066)
		(end 131.625 86.825)
		(width 0.15)
		(layer "F.Cu")
		(net 57)
	)
	(arc
		(start 129.2 90.2)
		(mid 129.253033 90.221967)
		(end 129.275 90.275)
		(width 0.15)
		(layer "F.Cu")
		(net 57)
	)
	(arc
		(start 131.825 88.175)
		(mid 131.931066 88.131066)
		(end 131.975 88.025)
		(width 0.15)
		(layer "F.Cu")
		(net 57)
	)
	(arc
		(start 131.825 87.575)
		(mid 131.931066 87.531066)
		(end 131.975 87.425)
		(width 0.15)
		(layer "F.Cu")
		(net 57)
	)
	(segment
		(start 127.95 93.352)
		(end 127.95 92.802)
		(width 0.15)
		(layer "B.Cu")
		(net 57)
	)
	(segment
		(start 132.8 91)
		(end 134.4 91)
		(width 0.15)
		(layer "F.Cu")
		(net 58)
	)
	(segment
		(start 128.48 91.72)
		(end 129.6 90.6)
		(width 0.15)
		(layer "F.Cu")
		(net 58)
	)
	(segment
		(start 133.6 90)
		(end 133.6 89.609553)
		(width 0.15)
		(layer "F.Cu")
		(net 58)
	)
	(segment
		(start 132.325 82.75)
		(end 132.325 85.875)
		(width 0.09)
		(layer "F.Cu")
		(net 58)
	)
	(segment
		(start 132.325 85.875)
		(end 132.3 85.9)
		(width 0.09)
		(layer "F.Cu")
		(net 58)
	)
	(segment
		(start 132.8 90.6)
		(end 134.4 90.6)
		(width 0.15)
		(layer "F.Cu")
		(net 58)
	)
	(segment
		(start 133.6 89.6)
		(end 133.4 89.4)
		(width 0.15)
		(layer "F.Cu")
		(net 58)
	)
	(segment
		(start 132.675 82.4)
		(end 132.325 82.75)
		(width 0.09)
		(layer "F.Cu")
		(net 58)
	)
	(segment
		(start 132.25 85.95)
		(end 132.325 85.875)
		(width 0.15)
		(layer "F.Cu")
		(net 58)
	)
	(segment
		(start 133.4 92.2)
		(end 133.6 92)
		(width 0.15)
		(layer "F.Cu")
		(net 58)
	)
	(segment
		(start 129.6 90.6)
		(end 131.076041 90.6)
		(width 0.15)
		(layer "F.Cu")
		(net 58)
	)
	(segment
		(start 132.676041 92.2)
		(end 133.4 92.2)
		(width 0.15)
		(layer "F.Cu")
		(net 58)
	)
	(segment
		(start 131.076041 90.6)
		(end 132.676041 92.2)
		(width 0.15)
		(layer "F.Cu")
		(net 58)
	)
	(segment
		(start 128.48 92.8)
		(end 128.48 91.72)
		(width 0.15)
		(layer "F.Cu")
		(net 58)
	)
	(segment
		(start 133.8 91.8)
		(end 133.85 91.8)
		(width 0.15)
		(layer "F.Cu")
		(net 58)
	)
	(segment
		(start 133.8 91.4)
		(end 132.8 91.4)
		(width 0.15)
		(layer "F.Cu")
		(net 58)
	)
	(segment
		(start 133.6 89.609553)
		(end 133.6 89.6)
		(width 0.15)
		(layer "F.Cu")
		(net 58)
	)
	(segment
		(start 133.4 89.4)
		(end 132.8 89.4)
		(width 0.15)
		(layer "F.Cu")
		(net 58)
	)
	(segment
		(start 132.8 90.2)
		(end 133.4 90.2)
		(width 0.15)
		(layer "F.Cu")
		(net 58)
	)
	(segment
		(start 132.8 89.4)
		(end 132.25 88.85)
		(width 0.15)
		(layer "F.Cu")
		(net 58)
	)
	(segment
		(start 133.85 91.4)
		(end 133.8 91.4)
		(width 0.15)
		(layer "F.Cu")
		(net 58)
	)
	(segment
		(start 132.25 88.85)
		(end 132.25 85.95)
		(width 0.15)
		(layer "F.Cu")
		(net 58)
	)
	(segment
		(start 128.48 92.8)
		(end 128.48 93.348)
		(width 0.15)
		(layer "F.Cu")
		(net 58)
	)
	(via
		(at 128.48 92.8)
		(size 0.4)
		(drill 0.2)
		(layers "F.Cu" "B.Cu")
		(net 58)
	)
	(arc
		(start 132.8 91.4)
		(mid 132.658579 91.341421)
		(end 132.6 91.2)
		(width 0.15)
		(layer "F.Cu")
		(net 58)
	)
	(arc
		(start 133.6 92)
		(mid 133.658579 91.858579)
		(end 133.8 91.8)
		(width 0.15)
		(layer "F.Cu")
		(net 58)
	)
	(arc
		(start 134.4 91)
		(mid 134.541421 90.941421)
		(end 134.6 90.8)
		(width 0.15)
		(layer "F.Cu")
		(net 58)
	)
	(arc
		(start 133.4 90.2)
		(mid 133.541421 90.141421)
		(end 133.6 90)
		(width 0.15)
		(layer "F.Cu")
		(net 58)
	)
	(arc
		(start 134.05 91.6)
		(mid 133.991421 91.458579)
		(end 133.85 91.4)
		(width 0.15)
		(layer "F.Cu")
		(net 58)
	)
	(arc
		(start 132.8 90.6)
		(mid 132.658579 90.541421)
		(end 132.6 90.4)
		(width 0.15)
		(layer "F.Cu")
		(net 58)
	)
	(arc
		(start 132.6 91.2)
		(mid 132.658579 91.058579)
		(end 132.8 91)
		(width 0.15)
		(layer "F.Cu")
		(net 58)
	)
	(arc
		(start 132.6 90.4)
		(mid 132.658579 90.258579)
		(end 132.8 90.2)
		(width 0.15)
		(layer "F.Cu")
		(net 58)
	)
	(arc
		(start 134.6 90.8)
		(mid 134.541421 90.658579)
		(end 134.4 90.6)
		(width 0.15)
		(layer "F.Cu")
		(net 58)
	)
	(arc
		(start 133.85 91.8)
		(mid 133.991421 91.741421)
		(end 134.05 91.6)
		(width 0.15)
		(layer "F.Cu")
		(net 58)
	)
	(segment
		(start 128.48 93.35)
		(end 128.48 92.8)
		(width 0.15)
		(layer "B.Cu")
		(net 58)
	)
	(segment
		(start 129.5 92.8)
		(end 129.5 93.348)
		(width 0.15)
		(layer "F.Cu")
		(net 59)
	)
	(segment
		(start 130.853 90.978)
		(end 129.832 90.978)
		(width 0.15)
		(layer "F.Cu")
		(net 59)
	)
	(segment
		(start 129.5 91.31)
		(end 129.5 92.8)
		(width 0.15)
		(layer "F.Cu")
		(net 59)
	)
	(segment
		(start 129.832 90.978)
		(end 129.5 91.31)
		(width 0.15)
		(layer "F.Cu")
		(net 59)
	)
	(segment
		(start 129.5 93.348)
		(end 129.498 93.35)
		(width 0.15)
		(layer "F.Cu")
		(net 59)
	)
	(segment
		(start 131.275 91.4)
		(end 130.853 90.978)
		(width 0.15)
		(layer "F.Cu")
		(net 59)
	)
	(via
		(at 131.275 91.4)
		(size 0.4)
		(drill 0.2)
		(layers "F.Cu" "B.Cu")
		(net 59)
	)
	(via
		(at 129.5 92.8)
		(size 0.4)
		(drill 0.2)
		(layers "F.Cu" "B.Cu")
		(net 59)
	)
	(via
		(at 131.975 80)
		(size 0.4)
		(drill 0.15)
		(layers "F.Cu" "B.Cu")
		(net 59)
	)
	(segment
		(start 129.5 93.35)
		(end 129.5 92.8)
		(width 0.15)
		(layer "B.Cu")
		(net 59)
	)
	(segment
		(start 132.375 92.5)
		(end 132.375 93.485)
		(width 0.15)
		(layer "In3.Cu")
		(net 59)
	)
	(segment
		(start 133.82 88.37)
		(end 133.09 87.64)
		(width 0.15)
		(layer "In3.Cu")
		(net 59)
	)
	(segment
		(start 131.275 91.4)
		(end 132.375 92.5)
		(width 0.15)
		(layer "In3.Cu")
		(net 59)
	)
	(segment
		(start 131.65 85.96)
		(end 131.65 85.825)
		(width 0.15)
		(layer "In3.Cu")
		(net 59)
	)
	(segment
		(start 132.76 87.64)
		(end 132.15 87.03)
		(width 0.15)
		(layer "In3.Cu")
		(net 59)
	)
	(segment
		(start 133.09 87.64)
		(end 132.76 87.64)
		(width 0.15)
		(layer "In3.Cu")
		(net 59)
	)
	(segment
		(start 131.975 80)
		(end 131.63 80.345)
		(width 0.09)
		(layer "In3.Cu")
		(net 59)
	)
	(segment
		(start 132.15 87.03)
		(end 132.15 86.46)
		(width 0.15)
		(layer "In3.Cu")
		(net 59)
	)
	(segment
		(start 132.375 93.485)
		(end 132.69 93.8)
		(width 0.15)
		(layer "In3.Cu")
		(net 59)
	)
	(segment
		(start 132.15 86.46)
		(end 131.65 85.96)
		(width 0.15)
		(layer "In3.Cu")
		(net 59)
	)
	(segment
		(start 133.82 91.26)
		(end 133.82 88.37)
		(width 0.15)
		(layer "In3.Cu")
		(net 59)
	)
	(segment
		(start 133.57 91.51)
		(end 133.82 91.26)
		(width 0.15)
		(layer "In3.Cu")
		(net 59)
	)
	(segment
		(start 132.69 93.8)
		(end 133.31 93.8)
		(width 0.15)
		(layer "In3.Cu")
		(net 59)
	)
	(segment
		(start 131.63 80.345)
		(end 131.63 85.805)
		(width 0.09)
		(layer "In3.Cu")
		(net 59)
	)
	(segment
		(start 133.31 93.8)
		(end 133.57 93.54)
		(width 0.15)
		(layer "In3.Cu")
		(net 59)
	)
	(segment
		(start 131.63 85.805)
		(end 131.65 85.825)
		(width 0.09)
		(layer "In3.Cu")
		(net 59)
	)
	(segment
		(start 133.57 93.54)
		(end 133.57 91.51)
		(width 0.15)
		(layer "In3.Cu")
		(net 59)
	)
	(segment
		(start 130.572 92.50324)
		(end 130.572 92.802)
		(width 0.15)
		(layer "F.Cu")
		(net 60)
	)
	(segment
		(start 130.70024 92.375)
		(end 130.572 92.50324)
		(width 0.15)
		(layer "F.Cu")
		(net 60)
	)
	(segment
		(start 131.825001 92.375)
		(end 130.70024 92.375)
		(width 0.15)
		(layer "F.Cu")
		(net 60)
	)
	(segment
		(start 131.825001 91.825)
		(end 132.100001 92.1)
		(width 0.15)
		(layer "F.Cu")
		(net 60)
	)
	(segment
		(start 130.572 91.403)
		(end 130.676959 91.403)
		(width 0.15)
		(layer "F.Cu")
		(net 60)
	)
	(segment
		(start 132.100001 92.1)
		(end 131.825001 92.375)
		(width 0.15)
		(layer "F.Cu")
		(net 60)
	)
	(segment
		(start 130.572 92.802)
		(end 130.572 93.35)
		(width 0.15)
		(layer "F.Cu")
		(net 60)
	)
	(segment
		(start 131.098959 91.825)
		(end 131.825001 91.825)
		(width 0.15)
		(layer "F.Cu")
		(net 60)
	)
	(segment
		(start 130.676959 91.403)
		(end 131.098959 91.825)
		(width 0.15)
		(layer "F.Cu")
		(net 60)
	)
	(via
		(at 130.572 91.403)
		(size 0.4)
		(drill 0.2)
		(layers "F.Cu" "B.Cu")
		(net 60)
	)
	(via
		(at 130.572 92.802)
		(size 0.4)
		(drill 0.2)
		(layers "F.Cu" "B.Cu")
		(net 60)
	)
	(via
		(at 131.975 78.4)
		(size 0.4)
		(drill 0.15)
		(layers "F.Cu" "B.Cu")
		(net 60)
	)
	(segment
		(start 130.572 93.352)
		(end 130.572 92.802)
		(width 0.15)
		(layer "B.Cu")
		(net 60)
	)
	(segment
		(start 133.44 88.56)
		(end 132.86 87.98)
		(width 0.15)
		(layer "In3.Cu")
		(net 60)
	)
	(segment
		(start 131.79 87.27)
		(end 131.79 86.75)
		(width 0.15)
		(layer "In3.Cu")
		(net 60)
	)
	(segment
		(start 132.86 87.98)
		(end 132.5 87.98)
		(width 0.15)
		(layer "In3.Cu")
		(net 60)
	)
	(segment
		(start 130.92 79.455)
		(end 130.92 85.77)
		(width 0.09)
		(layer "In3.Cu")
		(net 60)
	)
	(segment
		(start 133.25 92.2)
		(end 133.25 91.21)
		(width 0.15)
		(layer "In3.Cu")
		(net 60)
	)
	(segment
		(start 132.745331 92.34)
		(end 133.11 92.34)
		(width 0.15)
		(layer "In3.Cu")
		(net 60)
	)
	(segment
		(start 130.955 91.02)
		(end 131.425331 91.02)
		(width 0.15)
		(layer "In3.Cu")
		(net 60)
	)
	(segment
		(start 133.25 91.21)
		(end 133.44 91.02)
		(width 0.15)
		(layer "In3.Cu")
		(net 60)
	)
	(segment
		(start 131.975 78.4)
		(end 130.92 79.455)
		(width 0.09)
		(layer "In3.Cu")
		(net 60)
	)
	(segment
		(start 130.572 91.403)
		(end 130.955 91.02)
		(width 0.15)
		(layer "In3.Cu")
		(net 60)
	)
	(segment
		(start 130.92 85.77)
		(end 130.955 85.805)
		(width 0.09)
		(layer "In3.Cu")
		(net 60)
	)
	(segment
		(start 130.955 85.915)
		(end 130.955 85.805)
		(width 0.15)
		(layer "In3.Cu")
		(net 60)
	)
	(segment
		(start 131.425331 91.02)
		(end 132.745331 92.34)
		(width 0.15)
		(layer "In3.Cu")
		(net 60)
	)
	(segment
		(start 133.44 91.02)
		(end 133.44 88.56)
		(width 0.15)
		(layer "In3.Cu")
		(net 60)
	)
	(segment
		(start 132.5 87.98)
		(end 131.79 87.27)
		(width 0.15)
		(layer "In3.Cu")
		(net 60)
	)
	(segment
		(start 131.79 86.75)
		(end 130.955 85.915)
		(width 0.15)
		(layer "In3.Cu")
		(net 60)
	)
	(segment
		(start 133.11 92.34)
		(end 133.25 92.2)
		(width 0.15)
		(layer "In3.Cu")
		(net 60)
	)
	(segment
		(start 161 62.65)
		(end 161.265 62.385)
		(width 0.15)
		(layer "F.Cu")
		(net 61)
	)
	(segment
		(start 162.56 65.35)
		(end 163.06 64.85)
		(width 0.09)
		(layer "F.Cu")
		(net 61)
	)
	(segment
		(start 163.06 64.85)
		(end 164.06 64.85)
		(width 0.09)
		(layer "F.Cu")
		(net 61)
	)
	(segment
		(start 164.06 64.85)
		(end 164.56 65.35)
		(width 0.09)
		(layer "F.Cu")
		(net 61)
	)
	(segment
		(start 161 63.591084)
		(end 161 62.65)
		(width 0.15)
		(layer "F.Cu")
		(net 61)
	)
	(segment
		(start 162.56 65.35)
		(end 162.1 64.89)
		(width 0.15)
		(layer "F.Cu")
		(net 61)
	)
	(segment
		(start 164.825 65.615)
		(end 164.56 65.35)
		(width 0.1)
		(layer "F.Cu")
		(net 61)
	)
	(segment
		(start 161.915 63.865)
		(end 161.273916 63.865)
		(width 0.15)
		(layer "F.Cu")
		(net 61)
	)
	(segment
		(start 162.1 64.89)
		(end 162.1 64.05)
		(width 0.15)
		(layer "F.Cu")
		(net 61)
	)
	(segment
		(start 162.1 64.05)
		(end 161.915 63.865)
		(width 0.15)
		(layer "F.Cu")
		(net 61)
	)
	(segment
		(start 164.825 66.55)
		(end 164.825 65.615)
		(width 0.1)
		(layer "F.Cu")
		(net 61)
	)
	(segment
		(start 161.273916 63.865)
		(end 161 63.591084)
		(width 0.15)
		(layer "F.Cu")
		(net 61)
	)
	(segment
		(start 161.265 62.385)
		(end 161.55 62.385)
		(width 0.15)
		(layer "F.Cu")
		(net 61)
	)
	(segment
		(start 166.287 68.2)
		(end 166.552 68.465)
		(width 0.1524)
		(layer "F.Cu")
		(net 69)
	)
	(segment
		(start 166.552 68.465)
		(end 167.075 68.465)
		(width 0.1524)
		(layer "F.Cu")
		(net 69)
	)
	(segment
		(start 168.06 68.465)
		(end 168.068 68.457)
		(width 0.1524)
		(layer "F.Cu")
		(net 69)
	)
	(segment
		(start 167.075 68.465)
		(end 168.06 68.465)
		(width 0.1524)
		(layer "F.Cu")
		(net 69)
	)
	(segment
		(start 165.975 68.2)
		(end 166.287 68.2)
		(width 0.1524)
		(layer "F.Cu")
		(net 69)
	)
	(segment
		(start 101.9525 66.875)
		(end 101.7875 66.71)
		(width 0.182)
		(layer "F.Cu")
		(net 70)
	)
	(segment
		(start 101.9525 66.875)
		(end 103.5 66.875)
		(width 0.182)
		(layer "F.Cu")
		(net 70)
	)
	(segment
		(start 100.6875 66.71)
		(end 101.7875 66.71)
		(width 0.1)
		(layer "F.Cu")
		(net 70)
	)
	(segment
		(start 109.775 66.225)
		(end 111.4225 66.225)
		(width 0.182)
		(layer "F.Cu")
		(net 71)
	)
	(segment
		(start 112.525 66.11)
		(end 111.5375 66.11)
		(width 0.1)
		(layer "F.Cu")
		(net 71)
	)
	(segment
		(start 111.5375 66.11)
		(end 111.4225 66.225)
		(width 0.182)
		(layer "F.Cu")
		(net 71)
	)
	(segment
		(start 109.5175 72.755)
		(end 109.5175 73.75)
		(width 0.182)
		(layer "F.Cu")
		(net 72)
	)
	(segment
		(start 109.5175 72.755)
		(end 108.9125 72.15)
		(width 0.182)
		(layer "F.Cu")
		(net 72)
	)
	(segment
		(start 108.9125 72.15)
		(end 108.9125 70.9875)
		(width 0.182)
		(layer "F.Cu")
		(net 72)
	)
	(segment
		(start 104.3625 72.135)
		(end 103.7725 72.725)
		(width 0.182)
		(layer "F.Cu")
		(net 73)
	)
	(segment
		(start 103.7725 72.725)
		(end 103.7725 73.725)
		(width 0.182)
		(layer "F.Cu")
		(net 73)
	)
	(segment
		(start 104.3625 70.9875)
		(end 104.3625 72.135)
		(width 0.182)
		(layer "F.Cu")
		(net 73)
	)
	(segment
		(start 131.41 73.41)
		(end 131.99 73.41)
		(width 0.2)
		(layer "F.Cu")
		(net 92)
	)
	(segment
		(start 131.99 73.41)
		(end 132.675 74.095)
		(width 0.2)
		(layer "F.Cu")
		(net 92)
	)
	(segment
		(start 132.675 74.095)
		(end 132.675 74.4)
		(width 0.2)
		(layer "F.Cu")
		(net 92)
	)
	(segment
		(start 131.19 73.19)
		(end 131.41 73.41)
		(width 0.2)
		(layer "F.Cu")
		(net 92)
	)
	(segment
		(start 131.19 72.275)
		(end 131.19 73.19)
		(width 0.2)
		(layer "F.Cu")
		(net 92)
	)
	(segment
		(start 140.194713 89.9604)
		(end 140.194714 89.960399)
		(width 0.15)
		(layer "F.Cu")
		(net 99)
	)
	(segment
		(start 136.875 82.4)
		(end 137.225 82.75)
		(width 0.09)
		(layer "F.Cu")
		(net 99)
	)
	(segment
		(start 137.925 87.125)
		(end 137.925 85.875)
		(width 0.15)
		(layer "F.Cu")
		(net 99)
	)
	(segment
		(start 137.925 82.975)
		(end 137.925 85.875)
		(width 0.09)
		(layer "F.Cu")
		(net 99)
	)
	(segment
		(start 137.225 82.75)
		(end 137.7 82.75)
		(width 0.09)
		(layer "F.Cu")
		(net 99)
	)
	(segment
		(start 139.558315 89.182581)
		(end 139.558316 89.18258)
		(width 0.15)
		(layer "F.Cu")
		(net 99)
	)
	(segment
		(start 139.275468 88.758311)
		(end 139.575991 88.457792)
		(width 0.15)
		(layer "F.Cu")
		(net 99)
	)
	(segment
		(start 141.343766 89.907369)
		(end 141.30841 89.872013)
		(width 0.15)
		(layer "F.Cu")
		(net 99)
	)
	(segment
		(start 138.992626 88.758312)
		(end 138.921915 88.687601)
		(width 0.15)
		(layer "F.Cu")
		(net 99)
	)
	(segment
		(start 139.346179 87.62694)
		(end 139.346178 87.626939)
		(width 0.15)
		(layer "F.Cu")
		(net 99)
	)
	(segment
		(start 138.073383 87.839068)
		(end 138.17945 87.733002)
		(width 0.15)
		(layer "F.Cu")
		(net 99)
	)
	(segment
		(start 138.179449 87.379449)
		(end 138.179449 87.379448)
		(width 0.15)
		(layer "F.Cu")
		(net 99)
	)
	(segment
		(start 141.85 92.6)
		(end 141.85 91.05)
		(width 0.15)
		(layer "F.Cu")
		(net 99)
	)
	(segment
		(start 137.7 82.75)
		(end 137.925 82.975)
		(width 0.09)
		(layer "F.Cu")
		(net 99)
	)
	(segment
		(start 139.911868 89.536133)
		(end 140.283102 89.164903)
		(width 0.15)
		(layer "F.Cu")
		(net 99)
	)
	(segment
		(start 141.85 93.35)
		(end 141.85 92.6)
		(width 0.15)
		(layer "F.Cu")
		(net 99)
	)
	(segment
		(start 140.548268 90.313953)
		(end 140.990212 89.872013)
		(width 0.15)
		(layer "F.Cu")
		(net 99)
	)
	(segment
		(start 139.929545 88.493148)
		(end 139.894189 88.457792)
		(width 0.15)
		(layer "F.Cu")
		(net 99)
	)
	(segment
		(start 138.921914 88.404757)
		(end 139.346178 87.980493)
		(width 0.15)
		(layer "F.Cu")
		(net 99)
	)
	(segment
		(start 139.558315 89.536132)
		(end 139.558316 89.536134)
		(width 0.15)
		(layer "F.Cu")
		(net 99)
	)
	(segment
		(start 138.179449 87.379448)
		(end 137.925 87.125)
		(width 0.15)
		(layer "F.Cu")
		(net 99)
	)
	(segment
		(start 141.85 91.05)
		(end 141.715 90.915)
		(width 0.15)
		(layer "F.Cu")
		(net 99)
	)
	(segment
		(start 141.361446 90.915)
		(end 141.255378 91.021065)
		(width 0.15)
		(layer "F.Cu")
		(net 99)
	)
	(segment
		(start 140.636656 89.200259)
		(end 140.6013 89.164903)
		(width 0.15)
		(layer "F.Cu")
		(net 99)
	)
	(segment
		(start 141.361447 90.914999)
		(end 141.361446 90.915)
		(width 0.15)
		(layer "F.Cu")
		(net 99)
	)
	(segment
		(start 138.921914 88.404758)
		(end 138.921914 88.404757)
		(width 0.15)
		(layer "F.Cu")
		(net 99)
	)
	(segment
		(start 138.992624 87.626939)
		(end 138.426937 88.192622)
		(width 0.15)
		(layer "F.Cu")
		(net 99)
	)
	(segment
		(start 138.073382 87.839069)
		(end 138.073383 87.839068)
		(width 0.15)
		(layer "F.Cu")
		(net 99)
	)
	(segment
		(start 140.901825 91.021064)
		(end 140.901826 91.021066)
		(width 0.15)
		(layer "F.Cu")
		(net 99)
	)
	(segment
		(start 140.194714 89.960399)
		(end 140.636656 89.518457)
		(width 0.15)
		(layer "F.Cu")
		(net 99)
	)
	(segment
		(start 140.901826 90.667512)
		(end 141.343766 90.225567)
		(width 0.15)
		(layer "F.Cu")
		(net 99)
	)
	(segment
		(start 138.073384 88.192623)
		(end 138.073383 88.192622)
		(width 0.15)
		(layer "F.Cu")
		(net 99)
	)
	(segment
		(start 138.992625 87.626938)
		(end 138.992624 87.626939)
		(width 0.15)
		(layer "F.Cu")
		(net 99)
	)
	(segment
		(start 138.992626 88.758311)
		(end 138.992626 88.758312)
		(width 0.15)
		(layer "F.Cu")
		(net 99)
	)
	(segment
		(start 139.558316 89.18258)
		(end 139.929545 88.811346)
		(width 0.15)
		(layer "F.Cu")
		(net 99)
	)
	(segment
		(start 140.901825 90.667513)
		(end 140.901826 90.667512)
		(width 0.15)
		(layer "F.Cu")
		(net 99)
	)
	(segment
		(start 140.194715 90.313954)
		(end 140.194714 90.313953)
		(width 0.15)
		(layer "F.Cu")
		(net 99)
	)
	(via
		(at 141.85 92.6)
		(size 0.4)
		(drill 0.2)
		(layers "F.Cu" "B.Cu")
		(net 99)
	)
	(arc
		(start 140.194714 90.313953)
		(mid 140.12149 90.137177)
		(end 140.194713 89.9604)
		(width 0.15)
		(layer "F.Cu")
		(net 99)
	)
	(arc
		(start 139.275468 88.758311)
		(mid 139.134048 88.81689)
		(end 138.992626 88.758311)
		(width 0.15)
		(layer "F.Cu")
		(net 99)
	)
	(arc
		(start 139.346178 87.626939)
		(mid 139.169402 87.553715)
		(end 138.992625 87.626938)
		(width 0.15)
		(layer "F.Cu")
		(net 99)
	)
	(arc
		(start 138.073383 88.192622)
		(mid 138.000159 88.015846)
		(end 138.073382 87.839069)
		(width 0.15)
		(layer "F.Cu")
		(net 99)
	)
	(arc
		(start 138.426937 88.192622)
		(mid 138.250161 88.265846)
		(end 138.073384 88.192623)
		(width 0.15)
		(layer "F.Cu")
		(net 99)
	)
	(arc
		(start 141.343766 90.225567)
		(mid 141.409667 90.066468)
		(end 141.343766 89.907369)
		(width 0.15)
		(layer "F.Cu")
		(net 99)
	)
	(arc
		(start 138.921915 88.687601)
		(mid 138.863336 88.54618)
		(end 138.921914 88.404758)
		(width 0.15)
		(layer "F.Cu")
		(net 99)
	)
	(arc
		(start 141.30841 89.872013)
		(mid 141.149311 89.806112)
		(end 140.990212 89.872013)
		(width 0.15)
		(layer "F.Cu")
		(net 99)
	)
	(arc
		(start 141.715 90.915)
		(mid 141.538224 90.841776)
		(end 141.361447 90.914999)
		(width 0.15)
		(layer "F.Cu")
		(net 99)
	)
	(arc
		(start 139.558316 89.536134)
		(mid 139.485092 89.359358)
		(end 139.558315 89.182581)
		(width 0.15)
		(layer "F.Cu")
		(net 99)
	)
	(arc
		(start 141.255378 91.021065)
		(mid 141.078601 91.094288)
		(end 140.901825 91.021064)
		(width 0.15)
		(layer "F.Cu")
		(net 99)
	)
	(arc
		(start 139.894189 88.457792)
		(mid 139.73509 88.391891)
		(end 139.575991 88.457792)
		(width 0.15)
		(layer "F.Cu")
		(net 99)
	)
	(arc
		(start 139.929545 88.811346)
		(mid 139.995446 88.652247)
		(end 139.929545 88.493148)
		(width 0.15)
		(layer "F.Cu")
		(net 99)
	)
	(arc
		(start 139.911868 89.536133)
		(mid 139.735091 89.609356)
		(end 139.558315 89.536132)
		(width 0.15)
		(layer "F.Cu")
		(net 99)
	)
	(arc
		(start 139.346178 87.980493)
		(mid 139.419402 87.803717)
		(end 139.346179 87.62694)
		(width 0.15)
		(layer "F.Cu")
		(net 99)
	)
	(arc
		(start 140.636656 89.518457)
		(mid 140.702557 89.359358)
		(end 140.636656 89.200259)
		(width 0.15)
		(layer "F.Cu")
		(net 99)
	)
	(arc
		(start 140.6013 89.164903)
		(mid 140.442201 89.099002)
		(end 140.283102 89.164903)
		(width 0.15)
		(layer "F.Cu")
		(net 99)
	)
	(arc
		(start 138.17945 87.733002)
		(mid 138.252673 87.556225)
		(end 138.179449 87.379449)
		(width 0.15)
		(layer "F.Cu")
		(net 99)
	)
	(arc
		(start 140.548268 90.313953)
		(mid 140.371492 90.387177)
		(end 140.194715 90.313954)
		(width 0.15)
		(layer "F.Cu")
		(net 99)
	)
	(arc
		(start 140.901826 91.021066)
		(mid 140.828602 90.84429)
		(end 140.901825 90.667513)
		(width 0.15)
		(layer "F.Cu")
		(net 99)
	)
	(segment
		(start 141.85 93.35)
		(end 141.85 92.6)
		(width 0.15)
		(layer "B.Cu")
		(net 99)
	)
	(segment
		(start 135.825 86.055)
		(end 135.825 85.825)
		(width 0.15)
		(layer "F.Cu")
		(net 100)
	)
	(segment
		(start 139.39 92.4)
		(end 139.19 92.6)
		(width 0.15)
		(layer "F.Cu")
		(net 100)
	)
	(segment
		(start 138.84 92.77)
		(end 138.84 93.28)
		(width 0.15)
		(layer "F.Cu")
		(net 100)
	)
	(segment
		(start 136.68 89.205)
		(end 136.86 89.025)
		(width 0.15)
		(layer "F.Cu")
		(net 100)
	)
	(segment
		(start 137.99 92.6)
		(end 137.930331 92.6)
		(width 0.15)
		(layer "F.Cu")
		(net 100)
	)
	(segment
		(start 139.75 92.6)
		(end 139.75 93.365)
		(width 0.15)
		(layer "F.Cu")
		(net 100)
	)
	(segment
		(start 139.75 92.6)
		(end 139.75 91.13)
		(width 0.15)
		(layer "F.Cu")
		(net 100)
	)
	(segment
		(start 136.07 89.74)
		(end 136.07 89.425)
		(width 0.15)
		(layer "F.Cu")
		(net 100)
	)
	(segment
		(start 137.555331 92.225)
		(end 137.135 92.225)
		(width 0.15)
		(layer "F.Cu")
		(net 100)
	)
	(segment
		(start 139.67 91.05)
		(end 139.51 91.05)
		(width 0.15)
		(layer "F.Cu")
		(net 100)
	)
	(segment
		(start 137.135 92.225)
		(end 136.77 91.86)
		(width 0.15)
		(layer "F.Cu")
		(net 100)
	)
	(segment
		(start 139.51 91.05)
		(end 139.39 91.17)
		(width 0.15)
		(layer "F.Cu")
		(net 100)
	)
	(segment
		(start 138.16 91.92)
		(end 138.16 92.43)
		(width 0.15)
		(layer "F.Cu")
		(net 100)
	)
	(segment
		(start 136.05 83.6)
		(end 135.825 83.825)
		(width 0.09)
		(layer "F.Cu")
		(net 100)
	)
	(segment
		(start 138.5 93.28)
		(end 138.5 91.92)
		(width 0.15)
		(layer "F.Cu")
		(net 100)
	)
	(segment
		(start 136.86 86.51)
		(end 136.55 86.2)
		(width 0.15)
		(layer "F.Cu")
		(net 100)
	)
	(segment
		(start 137.930331 92.6)
		(end 137.555331 92.225)
		(width 0.15)
		(layer "F.Cu")
		(net 100)
	)
	(segment
		(start 136.86 89.025)
		(end 136.86 86.51)
		(width 0.15)
		(layer "F.Cu")
		(net 100)
	)
	(segment
		(start 136.77 91.86)
		(end 136.77 90.44)
		(width 0.15)
		(layer "F.Cu")
		(net 100)
	)
	(segment
		(start 136.55 86.2)
		(end 135.97 86.2)
		(width 0.15)
		(layer "F.Cu")
		(net 100)
	)
	(segment
		(start 136.07 89.425)
		(end 136.29 89.205)
		(width 0.15)
		(layer "F.Cu")
		(net 100)
	)
	(segment
		(start 137.575 83.2)
		(end 137.175 83.6)
		(width 0.09)
		(layer "F.Cu")
		(net 100)
	)
	(segment
		(start 136.77 90.44)
		(end 136.07 89.74)
		(width 0.15)
		(layer "F.Cu")
		(net 100)
	)
	(segment
		(start 139.75 91.13)
		(end 139.67 91.05)
		(width 0.15)
		(layer "F.Cu")
		(net 100)
	)
	(segment
		(start 136.29 89.205)
		(end 136.68 89.205)
		(width 0.15)
		(layer "F.Cu")
		(net 100)
	)
	(segment
		(start 135.825 83.825)
		(end 135.825 85.825)
		(width 0.09)
		(layer "F.Cu")
		(net 100)
	)
	(segment
		(start 135.97 86.2)
		(end 135.825 86.055)
		(width 0.15)
		(layer "F.Cu")
		(net 100)
	)
	(segment
		(start 139.39 91.17)
		(end 139.39 92.4)
		(width 0.15)
		(layer "F.Cu")
		(net 100)
	)
	(segment
		(start 139.19 92.6)
		(end 139.01 92.6)
		(width 0.15)
		(layer "F.Cu")
		(net 100)
	)
	(segment
		(start 137.175 83.6)
		(end 136.05 83.6)
		(width 0.09)
		(layer "F.Cu")
		(net 100)
	)
	(via
		(at 139.75 92.6)
		(size 0.4)
		(drill 0.2)
		(layers "F.Cu" "B.Cu")
		(net 100)
	)
	(arc
		(start 138.84 93.28)
		(mid 138.790208 93.400208)
		(end 138.67 93.45)
		(width 0.15)
		(layer "F.Cu")
		(net 100)
	)
	(arc
		(start 138.67 93.45)
		(mid 138.549792 93.400208)
		(end 138.5 93.28)
		(width 0.15)
		(layer "F.Cu")
		(net 100)
	)
	(arc
		(start 138.5 91.92)
		(mid 138.450208 91.799792)
		(end 138.33 91.75)
		(width 0.15)
		(layer "F.Cu")
		(net 100)
	)
	(arc
		(start 139.01 92.6)
		(mid 138.889792 92.649792)
		(end 138.84 92.77)
		(width 0.15)
		(layer "F.Cu")
		(net 100)
	)
	(arc
		(start 138.33 91.75)
		(mid 138.209792 91.799792)
		(end 138.16 91.92)
		(width 0.15)
		(layer "F.Cu")
		(net 100)
	)
	(arc
		(start 138.16 92.43)
		(mid 138.110208 92.550208)
		(end 137.99 92.6)
		(width 0.15)
		(layer "F.Cu")
		(net 100)
	)
	(segment
		(start 139.75 93.365)
		(end 139.75 92.6)
		(width 0.15)
		(layer "B.Cu")
		(net 100)
	)
	(segment
		(start 138.441795 88.810803)
		(end 138.441794 88.810804)
		(width 0.15)
		(layer "F.Cu")
		(net 101)
	)
	(segment
		(start 138.689281 88.810804)
		(end 138.689282 88.810804)
		(width 0.15)
		(layer "F.Cu")
		(net 101)
	)
	(segment
		(start 140.5755 91.616089)
		(end 139.769411 90.81)
		(width 0.15)
		(layer "F.Cu")
		(net 101)
	)
	(segment
		(start 137.225 84.35)
		(end 137.225 85.875)
		(width 0.09)
		(layer "F.Cu")
		(net 101)
	)
	(segment
		(start 138.512513 90.719999)
		(end 138.512512 90.72)
		(width 0.15)
		(layer "F.Cu")
		(net 101)
	)
	(segment
		(start 138.936774 89.305782)
		(end 138.936773 89.305783)
		(width 0.15)
		(layer "F.Cu")
		(net 101)
	)
	(segment
		(start 137.522554 89.482555)
		(end 137.522555 89.482555)
		(width 0.15)
		(layer "F.Cu")
		(net 101)
	)
	(segment
		(start 137.225 89.185)
		(end 137.225 85.875)
		(width 0.15)
		(layer "F.Cu")
		(net 101)
	)
	(segment
		(start 137.593271 91.39175)
		(end 137.593273 91.391751)
		(width 0.15)
		(layer "F.Cu")
		(net 101)
	)
	(segment
		(start 138.85 90.81)
		(end 138.76 90.72)
		(width 0.15)
		(layer "F.Cu")
		(net 101)
	)
	(segment
		(start 137.098293 90.649285)
		(end 137.098294 90.649284)
		(width 0.15)
		(layer "F.Cu")
		(net 101)
	)
	(segment
		(start 137.593273 91.144263)
		(end 139.184261 89.55327)
		(width 0.15)
		(layer "F.Cu")
		(net 101)
	)
	(segment
		(start 137.098293 90.89677)
		(end 137.098294 90.896772)
		(width 0.15)
		(layer "F.Cu")
		(net 101)
	)
	(segment
		(start 140.5755 92.6)
		(end 140.5755 91.616089)
		(width 0.15)
		(layer "F.Cu")
		(net 101)
	)
	(segment
		(start 138.512512 90.72)
		(end 137.840759 91.39175)
		(width 0.15)
		(layer "F.Cu")
		(net 101)
	)
	(segment
		(start 139.769411 90.81)
		(end 138.85 90.81)
		(width 0.15)
		(layer "F.Cu")
		(net 101)
	)
	(segment
		(start 137.098294 90.649284)
		(end 138.689282 89.058291)
		(width 0.15)
		(layer "F.Cu")
		(net 101)
	)
	(segment
		(start 137.593272 91.144264)
		(end 137.593273 91.144263)
		(width 0.15)
		(layer "F.Cu")
		(net 101)
	)
	(segment
		(start 140.7125 92.737)
		(end 140.5755 92.6)
		(width 0.15)
		(layer "F.Cu")
		(net 101)
	)
	(segment
		(start 138.441794 88.810804)
		(end 137.770042 89.482555)
		(width 0.15)
		(layer "F.Cu")
		(net 101)
	)
	(segment
		(start 136.875 84)
		(end 137.225 84.35)
		(width 0.09)
		(layer "F.Cu")
		(net 101)
	)
	(segment
		(start 138.936773 89.305783)
		(end 137.34578 90.896771)
		(width 0.15)
		(layer "F.Cu")
		(net 101)
	)
	(segment
		(start 139.18426 89.305783)
		(end 139.184261 89.305783)
		(width 0.15)
		(layer "F.Cu")
		(net 101)
	)
	(segment
		(start 140.7125 93.35)
		(end 140.7125 92.737)
		(width 0.15)
		(layer "F.Cu")
		(net 101)
	)
	(segment
		(start 137.522555 89.482555)
		(end 137.225 89.185)
		(width 0.15)
		(layer "F.Cu")
		(net 101)
	)
	(via
		(at 140.5755 92.6)
		(size 0.4)
		(drill 0.2)
		(layers "F.Cu" "B.Cu")
		(net 101)
	)
	(arc
		(start 138.689282 88.810804)
		(mid 138.565539 88.759547)
		(end 138.441795 88.810803)
		(width 0.15)
		(layer "F.Cu")
		(net 101)
	)
	(arc
		(start 137.840759 91.39175)
		(mid 137.717015 91.443006)
		(end 137.593271 91.39175)
		(width 0.15)
		(layer "F.Cu")
		(net 101)
	)
	(arc
		(start 137.098294 90.896772)
		(mid 137.047037 90.773029)
		(end 137.098293 90.649285)
		(width 0.15)
		(layer "F.Cu")
		(net 101)
	)
	(arc
		(start 139.184261 89.305783)
		(mid 139.060518 89.254526)
		(end 138.936774 89.305782)
		(width 0.15)
		(layer "F.Cu")
		(net 101)
	)
	(arc
		(start 139.184261 89.55327)
		(mid 139.235517 89.429526)
		(end 139.18426 89.305783)
		(width 0.15)
		(layer "F.Cu")
		(net 101)
	)
	(arc
		(start 138.689282 89.058291)
		(mid 138.740538 88.934547)
		(end 138.689281 88.810804)
		(width 0.15)
		(layer "F.Cu")
		(net 101)
	)
	(arc
		(start 137.34578 90.896771)
		(mid 137.222036 90.948027)
		(end 137.098293 90.89677)
		(width 0.15)
		(layer "F.Cu")
		(net 101)
	)
	(arc
		(start 137.770042 89.482555)
		(mid 137.646298 89.533811)
		(end 137.522554 89.482555)
		(width 0.15)
		(layer "F.Cu")
		(net 101)
	)
	(arc
		(start 138.76 90.72)
		(mid 138.636257 90.668743)
		(end 138.512513 90.719999)
		(width 0.15)
		(layer "F.Cu")
		(net 101)
	)
	(arc
		(start 137.593273 91.391751)
		(mid 137.542016 91.268008)
		(end 137.593272 91.144264)
		(width 0.15)
		(layer "F.Cu")
		(net 101)
	)
	(segment
		(start 140.7125 93.35)
		(end 140.7125 92.737)
		(width 0.15)
		(layer "B.Cu")
		(net 101)
	)
	(segment
		(start 140.7125 92.737)
		(end 140.5755 92.6)
		(width 0.15)
		(layer "B.Cu")
		(net 101)
	)
	(segment
		(start 143.95 93.35)
		(end 143.95 92.4)
		(width 0.15)
		(layer "F.Cu")
		(net 102)
	)
	(via
		(at 143.95 92.4)
		(size 0.4)
		(drill 0.2)
		(layers "F.Cu" "B.Cu")
		(net 102)
	)
	(via
		(at 137.575 76.8)
		(size 0.4)
		(drill 0.15)
		(layers "F.Cu" "B.Cu")
		(net 102)
	)
	(segment
		(start 143.95 93.35)
		(end 143.95 92.4)
		(width 0.15)
		(layer "B.Cu")
		(net 102)
	)
	(segment
		(start 141.07 79.892904)
		(end 140.725 80.237904)
		(width 0.09)
		(layer "In3.Cu")
		(net 102)
	)
	(segment
		(start 143.95 89.9)
		(end 140.7 86.65)
		(width 0.15)
		(layer "In3.Cu")
		(net 102)
	)
	(segment
		(start 140.725 86.375)
		(end 140.7 86.4)
		(width 0.09)
		(layer "In3.Cu")
		(net 102)
	)
	(segment
		(start 143.95 92.4)
		(end 143.95 89.9)
		(width 0.15)
		(layer "In3.Cu")
		(net 102)
	)
	(segment
		(start 141.07 79.27)
		(end 141.07 79.892904)
		(width 0.09)
		(layer "In3.Cu")
		(net 102)
	)
	(segment
		(start 140.73 77.467096)
		(end 140.73 78.93)
		(width 0.09)
		(layer "In3.Cu")
		(net 102)
	)
	(segment
		(start 140.73 78.93)
		(end 141.07 79.27)
		(width 0.09)
		(layer "In3.Cu")
		(net 102)
	)
	(segment
		(start 140.725 80.237904)
		(end 140.725 86.375)
		(width 0.09)
		(layer "In3.Cu")
		(net 102)
	)
	(segment
		(start 140.7 86.65)
		(end 140.7 86.4)
		(width 0.15)
		(layer "In3.Cu")
		(net 102)
	)
	(segment
		(start 137.575 76.8)
		(end 137.975 77.2)
		(width 0.09)
		(layer "In3.Cu")
		(net 102)
	)
	(segment
		(start 140.462904 77.2)
		(end 140.73 77.467096)
		(width 0.09)
		(layer "In3.Cu")
		(net 102)
	)
	(segment
		(start 137.975 77.2)
		(end 140.462904 77.2)
		(width 0.09)
		(layer "In3.Cu")
		(net 102)
	)
	(segment
		(start 143.3125 92.4025)
		(end 143.3125 93.35)
		(width 0.15)
		(layer "F.Cu")
		(net 103)
	)
	(segment
		(start 143.3 92.39)
		(end 143.3125 92.4025)
		(width 0.15)
		(layer "F.Cu")
		(net 103)
	)
	(via
		(at 136.875 77.6)
		(size 0.4)
		(drill 0.15)
		(layers "F.Cu" "B.Cu")
		(net 103)
	)
	(via
		(at 143.3 92.39)
		(size 0.4)
		(drill 0.2)
		(layers "F.Cu" "B.Cu")
		(net 103)
	)
	(segment
		(start 143.3125 92.4025)
		(end 143.3125 93.35)
		(width 0.15)
		(layer "B.Cu")
		(net 103)
	)
	(segment
		(start 143.3 92.39)
		(end 143.3125 92.4025)
		(width 0.15)
		(layer "B.Cu")
		(net 103)
	)
	(segment
		(start 143.3 90.51)
		(end 143.3 90.2)
		(width 0.15)
		(layer "In3.Cu")
		(net 103)
	)
	(segment
		(start 143.7 91.11)
		(end 143.7 90.91)
		(width 0.15)
		(layer "In3.Cu")
		(net 103)
	)
	(segment
		(start 142.097922 88.997922)
		(end 140 86.9)
		(width 0.15)
		(layer "In3.Cu")
		(net 103)
	)
	(segment
		(start 143.301201 92.388799)
		(end 143.301201 91.470456)
		(width 0.15)
		(layer "In3.Cu")
		(net 103)
	)
	(segment
		(start 142.80503 89.139343)
		(end 142.80503 89.139344)
		(width 0.15)
		(layer "In3.Cu")
		(net 103)
	)
	(segment
		(start 137.275 78)
		(end 139.8 78)
		(width 0.09)
		(layer "In3.Cu")
		(net 103)
	)
	(segment
		(start 143.3 92.39)
		(end 143.301201 92.388799)
		(width 0.15)
		(layer "In3.Cu")
		(net 103)
	)
	(segment
		(start 142.805029 89.422187)
		(end 142.80503 89.422187)
		(width 0.15)
		(layer "In3.Cu")
		(net 103)
	)
	(segment
		(start 143.3 90.2)
		(end 142.80503 89.70503)
		(width 0.15)
		(layer "In3.Cu")
		(net 103)
	)
	(segment
		(start 140.025 86.375)
		(end 140 86.4)
		(width 0.09)
		(layer "In3.Cu")
		(net 103)
	)
	(segment
		(start 140 86.9)
		(end 140 86.4)
		(width 0.15)
		(layer "In3.Cu")
		(net 103)
	)
	(segment
		(start 142.380765 88.997923)
		(end 142.380765 88.997922)
		(width 0.15)
		(layer "In3.Cu")
		(net 103)
	)
	(segment
		(start 139.8 78)
		(end 140.025 78.225)
		(width 0.09)
		(layer "In3.Cu")
		(net 103)
	)
	(segment
		(start 136.875 77.6)
		(end 137.275 78)
		(width 0.09)
		(layer "In3.Cu")
		(net 103)
	)
	(segment
		(start 140.025 78.225)
		(end 140.025 86.375)
		(width 0.09)
		(layer "In3.Cu")
		(net 103)
	)
	(segment
		(start 142.80503 89.139344)
		(end 142.663608 88.997922)
		(width 0.15)
		(layer "In3.Cu")
		(net 103)
	)
	(segment
		(start 142.097921 88.997922)
		(end 142.097922 88.997922)
		(width 0.15)
		(layer "In3.Cu")
		(net 103)
	)
	(arc
		(start 142.663608 88.997922)
		(mid 142.522186 88.939344)
		(end 142.380765 88.997923)
		(width 0.15)
		(layer "In3.Cu")
		(net 103)
	)
	(arc
		(start 143.5 91.31)
		(mid 143.641421 91.251421)
		(end 143.7 91.11)
		(width 0.15)
		(layer "In3.Cu")
		(net 103)
	)
	(arc
		(start 142.80503 89.422187)
		(mid 142.863609 89.280765)
		(end 142.80503 89.139343)
		(width 0.15)
		(layer "In3.Cu")
		(net 103)
	)
	(arc
		(start 143.7 90.91)
		(mid 143.641421 90.768579)
		(end 143.5 90.71)
		(width 0.15)
		(layer "In3.Cu")
		(net 103)
	)
	(arc
		(start 143.5 90.71)
		(mid 143.358579 90.651421)
		(end 143.3 90.51)
		(width 0.15)
		(layer "In3.Cu")
		(net 103)
	)
	(arc
		(start 142.80503 89.70503)
		(mid 142.746451 89.563609)
		(end 142.805029 89.422187)
		(width 0.15)
		(layer "In3.Cu")
		(net 103)
	)
	(arc
		(start 142.380765 88.997922)
		(mid 142.239343 89.056501)
		(end 142.097921 88.997922)
		(width 0.15)
		(layer "In3.Cu")
		(net 103)
	)
	(arc
		(start 143.301201 91.470456)
		(mid 143.373122 91.355398)
		(end 143.5 91.31)
		(width 0.15)
		(layer "In3.Cu")
		(net 103)
	)
	(segment
		(start 142.4875 93.35)
		(end 142.4875 92.6125)
		(width 0.15)
		(layer "F.Cu")
		(net 104)
	)
	(segment
		(start 142.4875 92.6125)
		(end 142.5 92.6)
		(width 0.15)
		(layer "F.Cu")
		(net 104)
	)
	(via
		(at 137.575 80)
		(size 0.4)
		(drill 0.15)
		(layers "F.Cu" "B.Cu")
		(net 104)
	)
	(via
		(at 142.5 92.6)
		(size 0.4)
		(drill 0.2)
		(layers "F.Cu" "B.Cu")
		(net 104)
	)
	(segment
		(start 142.4875 92.6125)
		(end 142.5 92.6)
		(width 0.15)
		(layer "B.Cu")
		(net 104)
	)
	(segment
		(start 142.4875 93.35)
		(end 142.4875 92.6125)
		(width 0.15)
		(layer "B.Cu")
		(net 104)
	)
	(segment
		(start 141.050422 89.417579)
		(end 141.015066 89.452934)
		(width 0.15)
		(layer "In3.Cu")
		(net 104)
	)
	(segment
		(start 140.802934 89.452934)
		(end 140.802935 89.452935)
		(width 0.15)
		(layer "In3.Cu")
		(net 104)
	)
	(segment
		(start 138.345 80.345)
		(end 137.92 80.345)
		(width 0.09)
		(layer "In3.Cu")
		(net 104)
	)
	(segment
		(start 139.777627 88.144784)
		(end 139.742271 88.180139)
		(width 0.15)
		(layer "In3.Cu")
		(net 104)
	)
	(segment
		(start 141.474687 89.841843)
		(end 141.474687 89.841844)
		(width 0.15)
		(layer "In3.Cu")
		(net 104)
	)
	(segment
		(start 141.898953 90.26611)
		(end 141.898953 90.266111)
		(width 0.15)
		(layer "In3.Cu")
		(net 104)
	)
	(segment
		(start 140.802934 89.240802)
		(end 140.802935 89.240802)
		(width 0.15)
		(layer "In3.Cu")
		(net 104)
	)
	(segment
		(start 141.227199 89.877199)
		(end 141.2272 89.8772)
		(width 0.15)
		(layer "In3.Cu")
		(net 104)
	)
	(segment
		(start 138.681609 87.331609)
		(end 138.68161 87.33161)
		(width 0.15)
		(layer "In3.Cu")
		(net 104)
	)
	(segment
		(start 142.65 92.11)
		(end 142.65 91.96)
		(width 0.15)
		(layer "In3.Cu")
		(net 104)
	)
	(segment
		(start 138.625 86.575)
		(end 138.625 80.625)
		(width 0.09)
		(layer "In3.Cu")
		(net 104)
	)
	(segment
		(start 139.954404 88.604404)
		(end 139.954405 88.604405)
		(width 0.15)
		(layer "In3.Cu")
		(net 104)
	)
	(segment
		(start 139.530139 87.968007)
		(end 139.53014 87.968007)
		(width 0.15)
		(layer "In3.Cu")
		(net 104)
	)
	(segment
		(start 139.954404 88.392272)
		(end 139.954405 88.392272)
		(width 0.15)
		(layer "In3.Cu")
		(net 104)
	)
	(segment
		(start 141.227199 89.665067)
		(end 141.2272 89.665067)
		(width 0.15)
		(layer "In3.Cu")
		(net 104)
	)
	(segment
		(start 138.625 80.625)
		(end 138.345 80.345)
		(width 0.09)
		(layer "In3.Cu")
		(net 104)
	)
	(segment
		(start 140.201892 88.569048)
		(end 140.201892 88.569049)
		(width 0.15)
		(layer "In3.Cu")
		(net 104)
	)
	(segment
		(start 140.378669 88.816537)
		(end 140.37867 88.816537)
		(width 0.15)
		(layer "In3.Cu")
		(net 104)
	)
	(segment
		(start 142.323222 90.690378)
		(end 142.323222 90.690379)
		(width 0.15)
		(layer "In3.Cu")
		(net 104)
	)
	(segment
		(start 142.323222 90.690379)
		(end 141.8636 91.149997)
		(width 0.15)
		(layer "In3.Cu")
		(net 104)
	)
	(segment
		(start 138.6 87.25)
		(end 138.6 86.6)
		(width 0.15)
		(layer "In3.Cu")
		(net 104)
	)
	(segment
		(start 140.626157 88.993313)
		(end 140.626157 88.993314)
		(width 0.15)
		(layer "In3.Cu")
		(net 104)
	)
	(segment
		(start 140.802935 89.240802)
		(end 140.83829 89.205446)
		(width 0.15)
		(layer "In3.Cu")
		(net 104)
	)
	(segment
		(start 139.105875 87.543742)
		(end 139.14123 87.508386)
		(width 0.15)
		(layer "In3.Cu")
		(net 104)
	)
	(segment
		(start 142.499999 90.937867)
		(end 142.5 90.937867)
		(width 0.15)
		(layer "In3.Cu")
		(net 104)
	)
	(segment
		(start 140.378669 89.028669)
		(end 140.37867 89.02867)
		(width 0.15)
		(layer "In3.Cu")
		(net 104)
	)
	(segment
		(start 138.929097 87.296254)
		(end 138.893741 87.331609)
		(width 0.15)
		(layer "In3.Cu")
		(net 104)
	)
	(segment
		(start 140.37867 88.816537)
		(end 140.414025 88.781181)
		(width 0.15)
		(layer "In3.Cu")
		(net 104)
	)
	(segment
		(start 142.5 92.6)
		(end 142.5 92.26)
		(width 0.15)
		(layer "In3.Cu")
		(net 104)
	)
	(segment
		(start 141.050422 89.417578)
		(end 141.050422 89.417579)
		(width 0.15)
		(layer "In3.Cu")
		(net 104)
	)
	(segment
		(start 139.353362 87.720519)
		(end 139.318006 87.755874)
		(width 0.15)
		(layer "In3.Cu")
		(net 104)
	)
	(segment
		(start 141.651469 90.937865)
		(end 142.111086 90.478243)
		(width 0.15)
		(layer "In3.Cu")
		(net 104)
	)
	(segment
		(start 139.954405 88.392272)
		(end 139.98976 88.356916)
		(width 0.15)
		(layer "In3.Cu")
		(net 104)
	)
	(segment
		(start 142.5 91.66)
		(end 142.5 91.15)
		(width 0.15)
		(layer "In3.Cu")
		(net 104)
	)
	(segment
		(start 138.6 86.6)
		(end 138.625 86.575)
		(width 0.09)
		(layer "In3.Cu")
		(net 104)
	)
	(segment
		(start 141.2272 89.665067)
		(end 141.262555 89.629711)
		(width 0.15)
		(layer "In3.Cu")
		(net 104)
	)
	(segment
		(start 141.898953 90.266111)
		(end 141.863597 90.301466)
		(width 0.15)
		(layer "In3.Cu")
		(net 104)
	)
	(segment
		(start 139.53014 87.968007)
		(end 139.565495 87.932651)
		(width 0.15)
		(layer "In3.Cu")
		(net 104)
	)
	(segment
		(start 141.651465 90.089332)
		(end 141.68682 90.053976)
		(width 0.15)
		(layer "In3.Cu")
		(net 104)
	)
	(segment
		(start 139.530139 88.180139)
		(end 139.53014 88.18014)
		(width 0.15)
		(layer "In3.Cu")
		(net 104)
	)
	(segment
		(start 140.626157 88.993314)
		(end 140.590801 89.028669)
		(width 0.15)
		(layer "In3.Cu")
		(net 104)
	)
	(segment
		(start 138.929097 87.296253)
		(end 138.929097 87.296254)
		(width 0.15)
		(layer "In3.Cu")
		(net 104)
	)
	(segment
		(start 141.651465 90.301466)
		(end 141.651465 90.301465)
		(width 0.15)
		(layer "In3.Cu")
		(net 104)
	)
	(segment
		(start 137.92 80.345)
		(end 137.575 80)
		(width 0.09)
		(layer "In3.Cu")
		(net 104)
	)
	(segment
		(start 139.105874 87.543742)
		(end 139.105875 87.543742)
		(width 0.15)
		(layer "In3.Cu")
		(net 104)
	)
	(segment
		(start 142.5 91.81)
		(end 142.5 91.66)
		(width 0.15)
		(layer "In3.Cu")
		(net 104)
	)
	(segment
		(start 139.777627 88.144783)
		(end 139.777627 88.144784)
		(width 0.15)
		(layer "In3.Cu")
		(net 104)
	)
	(segment
		(start 142.5 90.937867)
		(end 142.535355 90.902511)
		(width 0.15)
		(layer "In3.Cu")
		(net 104)
	)
	(segment
		(start 141.651464 90.089332)
		(end 141.651465 90.089332)
		(width 0.15)
		(layer "In3.Cu")
		(net 104)
	)
	(segment
		(start 139.105874 87.755874)
		(end 139.105875 87.755875)
		(width 0.15)
		(layer "In3.Cu")
		(net 104)
	)
	(segment
		(start 141.474687 89.841844)
		(end 141.439331 89.877199)
		(width 0.15)
		(layer "In3.Cu")
		(net 104)
	)
	(segment
		(start 139.353362 87.720518)
		(end 139.353362 87.720519)
		(width 0.15)
		(layer "In3.Cu")
		(net 104)
	)
	(segment
		(start 138.68161 87.33161)
		(end 138.6 87.25)
		(width 0.15)
		(layer "In3.Cu")
		(net 104)
	)
	(segment
		(start 141.651467 90.937864)
		(end 141.651469 90.937865)
		(width 0.15)
		(layer "In3.Cu")
		(net 104)
	)
	(segment
		(start 140.201892 88.569049)
		(end 140.166536 88.604404)
		(width 0.15)
		(layer "In3.Cu")
		(net 104)
	)
	(arc
		(start 139.565495 87.932651)
		(mid 139.609429 87.826585)
		(end 139.565495 87.720519)
		(width 0.15)
		(layer "In3.Cu")
		(net 104)
	)
	(arc
		(start 142.111086 90.266111)
		(mid 142.00502 90.222176)
		(end 141.898953 90.26611)
		(width 0.15)
		(layer "In3.Cu")
		(net 104)
	)
	(arc
		(start 139.98976 88.356916)
		(mid 140.033694 88.25085)
		(end 139.98976 88.144784)
		(width 0.15)
		(layer "In3.Cu")
		(net 104)
	)
	(arc
		(start 139.954405 88.604405)
		(mid 139.91047 88.498339)
		(end 139.954404 88.392272)
		(width 0.15)
		(layer "In3.Cu")
		(net 104)
	)
	(arc
		(start 139.565495 87.720519)
		(mid 139.459429 87.676584)
		(end 139.353362 87.720518)
		(width 0.15)
		(layer "In3.Cu")
		(net 104)
	)
	(arc
		(start 139.105875 87.755875)
		(mid 139.06194 87.649809)
		(end 139.105874 87.543742)
		(width 0.15)
		(layer "In3.Cu")
		(net 104)
	)
	(arc
		(start 138.893741 87.331609)
		(mid 138.787675 87.375543)
		(end 138.681609 87.331609)
		(width 0.15)
		(layer "In3.Cu")
		(net 104)
	)
	(arc
		(start 141.015066 89.452934)
		(mid 140.909 89.496868)
		(end 140.802934 89.452934)
		(width 0.15)
		(layer "In3.Cu")
		(net 104)
	)
	(arc
		(start 141.2272 89.8772)
		(mid 141.183265 89.771134)
		(end 141.227199 89.665067)
		(width 0.15)
		(layer "In3.Cu")
		(net 104)
	)
	(arc
		(start 141.68682 90.053976)
		(mid 141.730754 89.94791)
		(end 141.68682 89.841844)
		(width 0.15)
		(layer "In3.Cu")
		(net 104)
	)
	(arc
		(start 142.575 91.885)
		(mid 142.521967 91.863033)
		(end 142.5 91.81)
		(width 0.15)
		(layer "In3.Cu")
		(net 104)
	)
	(arc
		(start 139.53014 88.18014)
		(mid 139.486205 88.074074)
		(end 139.530139 87.968007)
		(width 0.15)
		(layer "In3.Cu")
		(net 104)
	)
	(arc
		(start 140.802935 89.452935)
		(mid 140.759 89.346869)
		(end 140.802934 89.240802)
		(width 0.15)
		(layer "In3.Cu")
		(net 104)
	)
	(arc
		(start 139.14123 87.508386)
		(mid 139.185164 87.40232)
		(end 139.14123 87.296254)
		(width 0.15)
		(layer "In3.Cu")
		(net 104)
	)
	(arc
		(start 141.651465 90.301465)
		(mid 141.60753 90.195399)
		(end 141.651464 90.089332)
		(width 0.15)
		(layer "In3.Cu")
		(net 104)
	)
	(arc
		(start 141.262555 89.417579)
		(mid 141.156489 89.373644)
		(end 141.050422 89.417578)
		(width 0.15)
		(layer "In3.Cu")
		(net 104)
	)
	(arc
		(start 140.37867 89.02867)
		(mid 140.334735 88.922604)
		(end 140.378669 88.816537)
		(width 0.15)
		(layer "In3.Cu")
		(net 104)
	)
	(arc
		(start 140.414025 88.569049)
		(mid 140.307959 88.525114)
		(end 140.201892 88.569048)
		(width 0.15)
		(layer "In3.Cu")
		(net 104)
	)
	(arc
		(start 140.83829 89.205446)
		(mid 140.882224 89.09938)
		(end 140.83829 88.993314)
		(width 0.15)
		(layer "In3.Cu")
		(net 104)
	)
	(arc
		(start 141.8636 91.149997)
		(mid 141.757534 91.193931)
		(end 141.651468 91.149997)
		(width 0.15)
		(layer "In3.Cu")
		(net 104)
	)
	(arc
		(start 141.651468 91.149997)
		(mid 141.607534 91.043932)
		(end 141.651467 90.937864)
		(width 0.15)
		(layer "In3.Cu")
		(net 104)
	)
	(arc
		(start 139.98976 88.144784)
		(mid 139.883694 88.100849)
		(end 139.777627 88.144783)
		(width 0.15)
		(layer "In3.Cu")
		(net 104)
	)
	(arc
		(start 141.439331 89.877199)
		(mid 141.333265 89.921133)
		(end 141.227199 89.877199)
		(width 0.15)
		(layer "In3.Cu")
		(net 104)
	)
	(arc
		(start 142.5 92.26)
		(mid 142.521967 92.206967)
		(end 142.575 92.185)
		(width 0.15)
		(layer "In3.Cu")
		(net 104)
	)
	(arc
		(start 142.535355 90.690379)
		(mid 142.429289 90.646444)
		(end 142.323222 90.690378)
		(width 0.15)
		(layer "In3.Cu")
		(net 104)
	)
	(arc
		(start 142.65 91.96)
		(mid 142.628033 91.906967)
		(end 142.575 91.885)
		(width 0.15)
		(layer "In3.Cu")
		(net 104)
	)
	(arc
		(start 139.742271 88.180139)
		(mid 139.636205 88.224073)
		(end 139.530139 88.180139)
		(width 0.15)
		(layer "In3.Cu")
		(net 104)
	)
	(arc
		(start 142.575 92.185)
		(mid 142.628033 92.163033)
		(end 142.65 92.11)
		(width 0.15)
		(layer "In3.Cu")
		(net 104)
	)
	(arc
		(start 141.262555 89.629711)
		(mid 141.306489 89.523645)
		(end 141.262555 89.417579)
		(width 0.15)
		(layer "In3.Cu")
		(net 104)
	)
	(arc
		(start 141.68682 89.841844)
		(mid 141.580754 89.797909)
		(end 141.474687 89.841843)
		(width 0.15)
		(layer "In3.Cu")
		(net 104)
	)
	(arc
		(start 142.5 91.15)
		(mid 142.456065 91.043934)
		(end 142.499999 90.937867)
		(width 0.15)
		(layer "In3.Cu")
		(net 104)
	)
	(arc
		(start 140.83829 88.993314)
		(mid 140.732224 88.949379)
		(end 140.626157 88.993313)
		(width 0.15)
		(layer "In3.Cu")
		(net 104)
	)
	(arc
		(start 139.318006 87.755874)
		(mid 139.21194 87.799808)
		(end 139.105874 87.755874)
		(width 0.15)
		(layer "In3.Cu")
		(net 104)
	)
	(arc
		(start 140.414025 88.781181)
		(mid 140.457959 88.675115)
		(end 140.414025 88.569049)
		(width 0.15)
		(layer "In3.Cu")
		(net 104)
	)
	(arc
		(start 142.535355 90.902511)
		(mid 142.579289 90.796445)
		(end 142.535355 90.690379)
		(width 0.15)
		(layer "In3.Cu")
		(net 104)
	)
	(arc
		(start 141.863597 90.301466)
		(mid 141.757531 90.3454)
		(end 141.651465 90.301466)
		(width 0.15)
		(layer "In3.Cu")
		(net 104)
	)
	(arc
		(start 139.14123 87.296254)
		(mid 139.035164 87.252319)
		(end 138.929097 87.296253)
		(width 0.15)
		(layer "In3.Cu")
		(net 104)
	)
	(arc
		(start 140.590801 89.028669)
		(mid 140.484735 89.072603)
		(end 140.378669 89.028669)
		(width 0.15)
		(layer "In3.Cu")
		(net 104)
	)
	(arc
		(start 140.166536 88.604404)
		(mid 140.06047 88.648338)
		(end 139.954404 88.604404)
		(width 0.15)
		(layer "In3.Cu")
		(net 104)
	)
	(arc
		(start 142.111086 90.478243)
		(mid 142.15502 90.372177)
		(end 142.111086 90.266111)
		(width 0.15)
		(layer "In3.Cu")
		(net 104)
	)
	(segment
		(start 141.35 93.35)
		(end 141.35 92.6)
		(width 0.15)
		(layer "F.Cu")
		(net 105)
	)
	(via
		(at 141.35 92.6)
		(size 0.4)
		(drill 0.2)
		(layers "F.Cu" "B.Cu")
		(net 105)
	)
	(via
		(at 137.575 81.6)
		(size 0.4)
		(drill 0.15)
		(layers "F.Cu" "B.Cu")
		(net 105)
	)
	(segment
		(start 141.35 93.35)
		(end 141.35 92.6)
		(width 0.15)
		(layer "B.Cu")
		(net 105)
	)
	(segment
		(start 138.521557 87.74478)
		(end 138.309423 87.95691)
		(width 0.15)
		(layer "In3.Cu")
		(net 105)
	)
	(segment
		(start 140.041846 89.689335)
		(end 140.041847 89.689334)
		(width 0.15)
		(layer "In3.Cu")
		(net 105)
	)
	(segment
		(start 138.769045 87.815492)
		(end 138.769045 87.815491)
		(width 0.15)
		(layer "In3.Cu")
		(net 105)
	)
	(segment
		(start 138.769045 87.815491)
		(end 138.698334 87.74478)
		(width 0.15)
		(layer "In3.Cu")
		(net 105)
	)
	(segment
		(start 139.54687 89.441845)
		(end 139.546869 89.441844)
		(width 0.15)
		(layer "In3.Cu")
		(net 105)
	)
	(segment
		(start 140.536825 90.184312)
		(end 140.748957 89.97218)
		(width 0.15)
		(layer "In3.Cu")
		(net 105)
	)
	(segment
		(start 138.556914 88.451889)
		(end 138.556913 88.451888)
		(width 0.15)
		(layer "In3.Cu")
		(net 105)
	)
	(segment
		(start 140.536826 90.431801)
		(end 140.536825 90.4318)
		(width 0.15)
		(layer "In3.Cu")
		(net 105)
	)
	(segment
		(start 137.92 82.257096)
		(end 137.92 86.38)
		(width 0.09)
		(layer "In3.Cu")
		(net 105)
	)
	(segment
		(start 140.536824 90.184313)
		(end 140.536825 90.184312)
		(width 0.15)
		(layer "In3.Cu")
		(net 105)
	)
	(segment
		(start 140.748957 89.795403)
		(end 140.678246 89.724692)
		(width 0.15)
		(layer "In3.Cu")
		(net 105)
	)
	(segment
		(start 139.759001 88.805448)
		(end 139.759001 88.805447)
		(width 0.15)
		(layer "In3.Cu")
		(net 105)
	)
	(segment
		(start 139.05189 88.699379)
		(end 139.051891 88.699378)
		(width 0.15)
		(layer "In3.Cu")
		(net 105)
	)
	(segment
		(start 139.759001 88.805447)
		(end 139.68829 88.734736)
		(width 0.15)
		(layer "In3.Cu")
		(net 105)
	)
	(segment
		(start 139.016535 88.239758)
		(end 138.804401 88.451888)
		(width 0.15)
		(layer "In3.Cu")
		(net 105)
	)
	(segment
		(start 140.253979 89.300426)
		(end 140.253979 89.300425)
		(width 0.15)
		(layer "In3.Cu")
		(net 105)
	)
	(segment
		(start 139.546869 89.194356)
		(end 139.759001 88.982224)
		(width 0.15)
		(layer "In3.Cu")
		(net 105)
	)
	(segment
		(start 139.016535 88.239757)
		(end 139.016535 88.239758)
		(width 0.15)
		(layer "In3.Cu")
		(net 105)
	)
	(segment
		(start 142.075 91.565)
		(end 141.35 91.565)
		(width 0.15)
		(layer "In3.Cu")
		(net 105)
	)
	(segment
		(start 139.546868 89.194357)
		(end 139.546869 89.194356)
		(width 0.15)
		(layer "In3.Cu")
		(net 105)
	)
	(segment
		(start 139.051892 88.946867)
		(end 139.051891 88.946866)
		(width 0.15)
		(layer "In3.Cu")
		(net 105)
	)
	(segment
		(start 139.051891 88.699378)
		(end 139.264023 88.487246)
		(width 0.15)
		(layer "In3.Cu")
		(net 105)
	)
	(segment
		(start 139.264023 88.31047)
		(end 139.264023 88.310469)
		(width 0.15)
		(layer "In3.Cu")
		(net 105)
	)
	(segment
		(start 138.061935 87.461934)
		(end 137.9 87.3)
		(width 0.15)
		(layer "In3.Cu")
		(net 105)
	)
	(segment
		(start 141.243935 90.29038)
		(end 141.243935 90.290381)
		(width 0.15)
		(layer "In3.Cu")
		(net 105)
	)
	(segment
		(start 141.35 91.915)
		(end 142.075 91.915)
		(width 0.15)
		(layer "In3.Cu")
		(net 105)
	)
	(segment
		(start 140.006491 89.229713)
		(end 140.006491 89.229714)
		(width 0.15)
		(layer "In3.Cu")
		(net 105)
	)
	(segment
		(start 141.35 92.6)
		(end 141.35 92.34)
		(width 0.15)
		(layer "In3.Cu")
		(net 105)
	)
	(segment
		(start 138.061936 87.956911)
		(end 138.061935 87.95691)
		(width 0.15)
		(layer "In3.Cu")
		(net 105)
	)
	(segment
		(start 137.9 87.3)
		(end 137.9 86.4)
		(width 0.15)
		(layer "In3.Cu")
		(net 105)
	)
	(segment
		(start 140.501469 89.724691)
		(end 140.501469 89.724692)
		(width 0.15)
		(layer "In3.Cu")
		(net 105)
	)
	(segment
		(start 137.655 82.055)
		(end 137.717904 82.055)
		(width 0.09)
		(layer "In3.Cu")
		(net 105)
	)
	(segment
		(start 138.556912 88.204401)
		(end 138.556913 88.2044)
		(width 0.15)
		(layer "In3.Cu")
		(net 105)
	)
	(segment
		(start 137.92 86.38)
		(end 137.9 86.4)
		(width 0.09)
		(layer "In3.Cu")
		(net 105)
	)
	(segment
		(start 139.511513 88.734735)
		(end 139.511513 88.734736)
		(width 0.15)
		(layer "In3.Cu")
		(net 105)
	)
	(segment
		(start 140.501469 89.724692)
		(end 140.289335 89.936822)
		(width 0.15)
		(layer "In3.Cu")
		(net 105)
	)
	(segment
		(start 140.006491 89.229714)
		(end 139.794357 89.441844)
		(width 0.15)
		(layer "In3.Cu")
		(net 105)
	)
	(segment
		(start 139.511513 88.734736)
		(end 139.299379 88.946866)
		(width 0.15)
		(layer "In3.Cu")
		(net 105)
	)
	(segment
		(start 137.717904 82.055)
		(end 137.92 82.257096)
		(width 0.09)
		(layer "In3.Cu")
		(net 105)
	)
	(segment
		(start 141.2 91.49)
		(end 141.2 91.29)
		(width 0.15)
		(layer "In3.Cu")
		(net 105)
	)
	(segment
		(start 138.556913 88.2044)
		(end 138.769045 87.992268)
		(width 0.15)
		(layer "In3.Cu")
		(net 105)
	)
	(segment
		(start 140.253979 89.300425)
		(end 140.183268 89.229714)
		(width 0.15)
		(layer "In3.Cu")
		(net 105)
	)
	(segment
		(start 138.061934 87.709423)
		(end 138.061935 87.709422)
		(width 0.15)
		(layer "In3.Cu")
		(net 105)
	)
	(segment
		(start 140.041847 89.689334)
		(end 140.253979 89.477202)
		(width 0.15)
		(layer "In3.Cu")
		(net 105)
	)
	(segment
		(start 138.521557 87.744779)
		(end 138.521557 87.74478)
		(width 0.15)
		(layer "In3.Cu")
		(net 105)
	)
	(segment
		(start 137.575 81.6)
		(end 137.575 81.975)
		(width 0.09)
		(layer "In3.Cu")
		(net 105)
	)
	(segment
		(start 137.575 81.975)
		(end 137.655 82.055)
		(width 0.09)
		(layer "In3.Cu")
		(net 105)
	)
	(segment
		(start 141.275 91.915)
		(end 141.35 91.915)
		(width 0.15)
		(layer "In3.Cu")
		(net 105)
	)
	(segment
		(start 141.35 90.75)
		(end 141.243935 90.643935)
		(width 0.15)
		(layer "In3.Cu")
		(net 105)
	)
	(segment
		(start 141.35 91.565)
		(end 141.275 91.565)
		(width 0.15)
		(layer "In3.Cu")
		(net 105)
	)
	(segment
		(start 141.2 92.19)
		(end 141.2 91.99)
		(width 0.15)
		(layer "In3.Cu")
		(net 105)
	)
	(segment
		(start 140.041848 89.936823)
		(end 140.041847 89.936822)
		(width 0.15)
		(layer "In3.Cu")
		(net 105)
	)
	(segment
		(start 140.996447 90.21967)
		(end 140.784313 90.4318)
		(width 0.15)
		(layer "In3.Cu")
		(net 105)
	)
	(segment
		(start 140.748957 89.795404)
		(end 140.748957 89.795403)
		(width 0.15)
		(layer "In3.Cu")
		(net 105)
	)
	(segment
		(start 141.243935 90.290381)
		(end 141.173224 90.21967)
		(width 0.15)
		(layer "In3.Cu")
		(net 105)
	)
	(segment
		(start 141.35 91.14)
		(end 141.35 90.75)
		(width 0.15)
		(layer "In3.Cu")
		(net 105)
	)
	(segment
		(start 140.996447 90.219669)
		(end 140.996447 90.21967)
		(width 0.15)
		(layer "In3.Cu")
		(net 105)
	)
	(segment
		(start 141.243934 90.467158)
		(end 141.243935 90.467158)
		(width 0.15)
		(layer "In3.Cu")
		(net 105)
	)
	(segment
		(start 139.264023 88.310469)
		(end 139.193312 88.239758)
		(width 0.15)
		(layer "In3.Cu")
		(net 105)
	)
	(arc
		(start 141.2 91.99)
		(mid 141.221967 91.936967)
		(end 141.275 91.915)
		(width 0.15)
		(layer "In3.Cu")
		(net 105)
	)
	(arc
		(start 140.784313 90.4318)
		(mid 140.66057 90.483057)
		(end 140.536826 90.431801)
		(width 0.15)
		(layer "In3.Cu")
		(net 105)
	)
	(arc
		(start 139.759001 88.982224)
		(mid 139.795613 88.893836)
		(end 139.759001 88.805448)
		(width 0.15)
		(layer "In3.Cu")
		(net 105)
	)
	(arc
		(start 141.275 91.215)
		(mid 141.328033 91.193033)
		(end 141.35 91.14)
		(width 0.15)
		(layer "In3.Cu")
		(net 105)
	)
	(arc
		(start 140.748957 89.97218)
		(mid 140.785569 89.883792)
		(end 140.748957 89.795404)
		(width 0.15)
		(layer "In3.Cu")
		(net 105)
	)
	(arc
		(start 141.275 91.565)
		(mid 141.221967 91.543033)
		(end 141.2 91.49)
		(width 0.15)
		(layer "In3.Cu")
		(net 105)
	)
	(arc
		(start 138.698334 87.74478)
		(mid 138.609946 87.708168)
		(end 138.521557 87.744779)
		(width 0.15)
		(layer "In3.Cu")
		(net 105)
	)
	(arc
		(start 139.68829 88.734736)
		(mid 139.599902 88.698124)
		(end 139.511513 88.734735)
		(width 0.15)
		(layer "In3.Cu")
		(net 105)
	)
	(arc
		(start 141.35 92.34)
		(mid 141.328033 92.286967)
		(end 141.275 92.265)
		(width 0.15)
		(layer "In3.Cu")
		(net 105)
	)
	(arc
		(start 138.769045 87.992268)
		(mid 138.805657 87.90388)
		(end 138.769045 87.815492)
		(width 0.15)
		(layer "In3.Cu")
		(net 105)
	)
	(arc
		(start 142.25 91.74)
		(mid 142.198744 91.616256)
		(end 142.075 91.565)
		(width 0.15)
		(layer "In3.Cu")
		(net 105)
	)
	(arc
		(start 138.309423 87.95691)
		(mid 138.18568 88.008167)
		(end 138.061936 87.956911)
		(width 0.15)
		(layer "In3.Cu")
		(net 105)
	)
	(arc
		(start 138.061935 87.709422)
		(mid 138.113191 87.585678)
		(end 138.061935 87.461934)
		(width 0.15)
		(layer "In3.Cu")
		(net 105)
	)
	(arc
		(start 140.536825 90.4318)
		(mid 140.485568 90.308057)
		(end 140.536824 90.184313)
		(width 0.15)
		(layer "In3.Cu")
		(net 105)
	)
	(arc
		(start 139.193312 88.239758)
		(mid 139.104924 88.203146)
		(end 139.016535 88.239757)
		(width 0.15)
		(layer "In3.Cu")
		(net 105)
	)
	(arc
		(start 139.299379 88.946866)
		(mid 139.175636 88.998123)
		(end 139.051892 88.946867)
		(width 0.15)
		(layer "In3.Cu")
		(net 105)
	)
	(arc
		(start 142.075 91.915)
		(mid 142.198744 91.863744)
		(end 142.25 91.74)
		(width 0.15)
		(layer "In3.Cu")
		(net 105)
	)
	(arc
		(start 140.289335 89.936822)
		(mid 140.165592 89.988079)
		(end 140.041848 89.936823)
		(width 0.15)
		(layer "In3.Cu")
		(net 105)
	)
	(arc
		(start 139.264023 88.487246)
		(mid 139.300635 88.398858)
		(end 139.264023 88.31047)
		(width 0.15)
		(layer "In3.Cu")
		(net 105)
	)
	(arc
		(start 140.183268 89.229714)
		(mid 140.09488 89.193102)
		(end 140.006491 89.229713)
		(width 0.15)
		(layer "In3.Cu")
		(net 105)
	)
	(arc
		(start 139.794357 89.441844)
		(mid 139.670614 89.493101)
		(end 139.54687 89.441845)
		(width 0.15)
		(layer "In3.Cu")
		(net 105)
	)
	(arc
		(start 141.173224 90.21967)
		(mid 141.084836 90.183058)
		(end 140.996447 90.219669)
		(width 0.15)
		(layer "In3.Cu")
		(net 105)
	)
	(arc
		(start 141.2 91.29)
		(mid 141.221967 91.236967)
		(end 141.275 91.215)
		(width 0.15)
		(layer "In3.Cu")
		(net 105)
	)
	(arc
		(start 138.061935 87.95691)
		(mid 138.010678 87.833167)
		(end 138.061934 87.709423)
		(width 0.15)
		(layer "In3.Cu")
		(net 105)
	)
	(arc
		(start 138.556913 88.451888)
		(mid 138.505656 88.328145)
		(end 138.556912 88.204401)
		(width 0.15)
		(layer "In3.Cu")
		(net 105)
	)
	(arc
		(start 139.051891 88.946866)
		(mid 139.000634 88.823123)
		(end 139.05189 88.699379)
		(width 0.15)
		(layer "In3.Cu")
		(net 105)
	)
	(arc
		(start 141.275 92.265)
		(mid 141.221967 92.243033)
		(end 141.2 92.19)
		(width 0.15)
		(layer "In3.Cu")
		(net 105)
	)
	(arc
		(start 140.253979 89.477202)
		(mid 140.290591 89.388814)
		(end 140.253979 89.300426)
		(width 0.15)
		(layer "In3.Cu")
		(net 105)
	)
	(arc
		(start 138.804401 88.451888)
		(mid 138.680658 88.503145)
		(end 138.556914 88.451889)
		(width 0.15)
		(layer "In3.Cu")
		(net 105)
	)
	(arc
		(start 140.041847 89.936822)
		(mid 139.99059 89.813079)
		(end 140.041846 89.689335)
		(width 0.15)
		(layer "In3.Cu")
		(net 105)
	)
	(arc
		(start 141.243935 90.467158)
		(mid 141.280547 90.378769)
		(end 141.243935 90.29038)
		(width 0.15)
		(layer "In3.Cu")
		(net 105)
	)
	(arc
		(start 139.546869 89.441844)
		(mid 139.495612 89.318101)
		(end 139.546868 89.194357)
		(width 0.15)
		(layer "In3.Cu")
		(net 105)
	)
	(arc
		(start 141.243935 90.643935)
		(mid 141.207323 90.555547)
		(end 141.243934 90.467158)
		(width 0.15)
		(layer "In3.Cu")
		(net 105)
	)
	(arc
		(start 140.678246 89.724692)
		(mid 140.589858 89.68808)
		(end 140.501469 89.724691)
		(width 0.15)
		(layer "In3.Cu")
		(net 105)
	)
	(segment
		(start 145.0875 93.35)
		(end 145.0875 92.6125)
		(width 0.15)
		(layer "F.Cu")
		(net 106)
	)
	(segment
		(start 145.0875 92.6125)
		(end 145.1 92.6)
		(width 0.15)
		(layer "F.Cu")
		(net 106)
	)
	(via
		(at 145.1 92.6)
		(size 0.4)
		(drill 0.2)
		(layers "F.Cu" "B.Cu")
		(net 106)
	)
	(via
		(at 136.875 79.2)
		(size 0.4)
		(drill 0.15)
		(layers "F.Cu" "B.Cu")
		(net 106)
	)
	(segment
		(start 145.0875 92.6125)
		(end 145.1 92.6)
		(width 0.15)
		(layer "B.Cu")
		(net 106)
	)
	(segment
		(start 145.0875 93.35)
		(end 145.0875 92.6125)
		(width 0.15)
		(layer "B.Cu")
		(net 106)
	)
	(segment
		(start 142.785588 92.975)
		(end 142.830589 93.02)
		(width 0.15)
		(layer "In3.Cu")
		(net 106)
	)
	(segment
		(start 144.68 93.02)
		(end 145.1 92.6)
		(width 0.15)
		(layer "In3.Cu")
		(net 106)
	)
	(segment
		(start 137.44 87.69)
		(end 140.95 91.2)
		(width 0.15)
		(layer "In3.Cu")
		(net 106)
	)
	(segment
		(start 141.194669 92.975)
		(end 142.785588 92.975)
		(width 0.15)
		(layer "In3.Cu")
		(net 106)
	)
	(segment
		(start 137.225 86.295)
		(end 137.225 79.55)
		(width 0.09)
		(layer "In3.Cu")
		(net 106)
	)
	(segment
		(start 140.95 92.730331)
		(end 141.194669 92.975)
		(width 0.15)
		(layer "In3.Cu")
		(net 106)
	)
	(segment
		(start 137.38 86.45)
		(end 137.44 86.51)
		(width 0.15)
		(layer "In3.Cu")
		(net 106)
	)
	(segment
		(start 137.225 79.55)
		(end 136.875 79.2)
		(width 0.09)
		(layer "In3.Cu")
		(net 106)
	)
	(segment
		(start 140.95 91.2)
		(end 140.95 92.730331)
		(width 0.15)
		(layer "In3.Cu")
		(net 106)
	)
	(segment
		(start 137.38 86.45)
		(end 137.225 86.295)
		(width 0.09)
		(layer "In3.Cu")
		(net 106)
	)
	(segment
		(start 137.44 86.51)
		(end 137.44 87.69)
		(width 0.15)
		(layer "In3.Cu")
		(net 106)
	)
	(segment
		(start 142.830589 93.02)
		(end 144.68 93.02)
		(width 0.15)
		(layer "In3.Cu")
		(net 106)
	)
	(segment
		(start 144.45 93.35)
		(end 144.45 92.45)
		(width 0.15)
		(layer "F.Cu")
		(net 107)
	)
	(segment
		(start 144.45 92.45)
		(end 144.47 92.43)
		(width 0.15)
		(layer "F.Cu")
		(net 107)
	)
	(via
		(at 144.47 92.43)
		(size 0.4)
		(drill 0.2)
		(layers "F.Cu" "B.Cu")
		(net 107)
	)
	(via
		(at 137.575 78.4)
		(size 0.4)
		(drill 0.2)
		(layers "F.Cu" "B.Cu")
		(net 107)
	)
	(segment
		(start 144.45 93.35)
		(end 144.45 92.45)
		(width 0.15)
		(layer "B.Cu")
		(net 107)
	)
	(segment
		(start 144.45 92.45)
		(end 144.47 92.43)
		(width 0.15)
		(layer "B.Cu")
		(net 107)
	)
	(segment
		(start 138.376452 78.745)
		(end 139.32 79.688548)
		(width 0.09)
		(layer "In3.Cu")
		(net 107)
	)
	(segment
		(start 140.389773 87.942283)
		(end 140.389772 87.942284)
		(width 0.15)
		(layer "In3.Cu")
		(net 107)
	)
	(segment
		(start 142.086831 89.639341)
		(end 142.08683 89.639342)
		(width 0.15)
		(layer "In3.Cu")
		(net 107)
	)
	(segment
		(start 142.93 92.78)
		(end 142.9 92.75)
		(width 0.15)
		(layer "In3.Cu")
		(net 107)
	)
	(segment
		(start 142.511094 90.063608)
		(end 142.511095 90.063607)
		(width 0.15)
		(layer "In3.Cu")
		(net 107)
	)
	(segment
		(start 142.9 91.42)
		(end 142.9 90.7)
		(width 0.15)
		(layer "In3.Cu")
		(net 107)
	)
	(segment
		(start 141.839342 89.639342)
		(end 141.662566 89.462566)
		(width 0.15)
		(layer "In3.Cu")
		(net 107)
	)
	(segment
		(start 137.92 78.745)
		(end 138.376452 78.745)
		(width 0.09)
		(layer "In3.Cu")
		(net 107)
	)
	(segment
		(start 144.47 92.43)
		(end 144.47 92.78)
		(width 0.15)
		(layer "In3.Cu")
		(net 107)
	)
	(segment
		(start 139.32 79.688548)
		(end 139.32 86.38)
		(width 0.09)
		(layer "In3.Cu")
		(net 107)
	)
	(segment
		(start 137.575 78.4)
		(end 137.92 78.745)
		(width 0.09)
		(layer "In3.Cu")
		(net 107)
	)
	(segment
		(start 144.47 92.78)
		(end 142.93 92.78)
		(width 0.15)
		(layer "In3.Cu")
		(net 107)
	)
	(segment
		(start 140.814037 88.119061)
		(end 140.63726 87.942284)
		(width 0.15)
		(layer "In3.Cu")
		(net 107)
	)
	(segment
		(start 143.05 92.02)
		(end 143.05 91.57)
		(width 0.15)
		(layer "In3.Cu")
		(net 107)
	)
	(segment
		(start 139.32 86.38)
		(end 139.3 86.4)
		(width 0.09)
		(layer "In3.Cu")
		(net 107)
	)
	(segment
		(start 140.990813 88.790813)
		(end 140.814037 88.614037)
		(width 0.15)
		(layer "In3.Cu")
		(net 107)
	)
	(segment
		(start 140.142284 87.942284)
		(end 139.3 87.1)
		(width 0.15)
		(layer "In3.Cu")
		(net 107)
	)
	(segment
		(start 140.814036 88.36655)
		(end 140.814037 88.366549)
		(width 0.15)
		(layer "In3.Cu")
		(net 107)
	)
	(segment
		(start 139.3 87.1)
		(end 139.3 86.4)
		(width 0.15)
		(layer "In3.Cu")
		(net 107)
	)
	(segment
		(start 142.9 90.7)
		(end 142.511095 90.311095)
		(width 0.15)
		(layer "In3.Cu")
		(net 107)
	)
	(segment
		(start 141.238302 88.790812)
		(end 141.238301 88.790813)
		(width 0.15)
		(layer "In3.Cu")
		(net 107)
	)
	(segment
		(start 142.9 92.75)
		(end 142.9 92.17)
		(width 0.15)
		(layer "In3.Cu")
		(net 107)
	)
	(segment
		(start 141.662565 89.215079)
		(end 141.662566 89.215078)
		(width 0.15)
		(layer "In3.Cu")
		(net 107)
	)
	(segment
		(start 142.511095 89.816119)
		(end 142.334318 89.639342)
		(width 0.15)
		(layer "In3.Cu")
		(net 107)
	)
	(segment
		(start 141.662566 88.96759)
		(end 141.485789 88.790813)
		(width 0.15)
		(layer "In3.Cu")
		(net 107)
	)
	(arc
		(start 142.334318 89.639342)
		(mid 142.210575 89.588085)
		(end 142.086831 89.639341)
		(width 0.15)
		(layer "In3.Cu")
		(net 107)
	)
	(arc
		(start 140.63726 87.942284)
		(mid 140.513517 87.891027)
		(end 140.389773 87.942283)
		(width 0.15)
		(layer "In3.Cu")
		(net 107)
	)
	(arc
		(start 143.05 91.57)
		(mid 143.028033 91.516967)
		(end 142.975 91.495)
		(width 0.15)
		(layer "In3.Cu")
		(net 107)
	)
	(arc
		(start 142.511095 90.063607)
		(mid 142.562351 89.939863)
		(end 142.511095 89.816119)
		(width 0.15)
		(layer "In3.Cu")
		(net 107)
	)
	(arc
		(start 140.814037 88.366549)
		(mid 140.865293 88.242805)
		(end 140.814037 88.119061)
		(width 0.15)
		(layer "In3.Cu")
		(net 107)
	)
	(arc
		(start 142.511095 90.311095)
		(mid 142.459838 90.187352)
		(end 142.511094 90.063608)
		(width 0.15)
		(layer "In3.Cu")
		(net 107)
	)
	(arc
		(start 141.662566 89.215078)
		(mid 141.713822 89.091334)
		(end 141.662566 88.96759)
		(width 0.15)
		(layer "In3.Cu")
		(net 107)
	)
	(arc
		(start 141.238301 88.790813)
		(mid 141.114557 88.842069)
		(end 140.990813 88.790813)
		(width 0.15)
		(layer "In3.Cu")
		(net 107)
	)
	(arc
		(start 142.9 92.17)
		(mid 142.921967 92.116967)
		(end 142.975 92.095)
		(width 0.15)
		(layer "In3.Cu")
		(net 107)
	)
	(arc
		(start 142.975 92.095)
		(mid 143.028033 92.073033)
		(end 143.05 92.02)
		(width 0.15)
		(layer "In3.Cu")
		(net 107)
	)
	(arc
		(start 141.485789 88.790813)
		(mid 141.362046 88.739556)
		(end 141.238302 88.790812)
		(width 0.15)
		(layer "In3.Cu")
		(net 107)
	)
	(arc
		(start 140.814037 88.614037)
		(mid 140.76278 88.490294)
		(end 140.814036 88.36655)
		(width 0.15)
		(layer "In3.Cu")
		(net 107)
	)
	(arc
		(start 141.662566 89.462566)
		(mid 141.611309 89.338823)
		(end 141.662565 89.215079)
		(width 0.15)
		(layer "In3.Cu")
		(net 107)
	)
	(arc
		(start 140.389772 87.942284)
		(mid 140.266028 87.99354)
		(end 140.142284 87.942284)
		(width 0.15)
		(layer "In3.Cu")
		(net 107)
	)
	(arc
		(start 142.975 91.495)
		(mid 142.921967 91.473033)
		(end 142.9 91.42)
		(width 0.15)
		(layer "In3.Cu")
		(net 107)
	)
	(arc
		(start 142.08683 89.639342)
		(mid 141.963086 89.690598)
		(end 141.839342 89.639342)
		(width 0.15)
		(layer "In3.Cu")
		(net 107)
	)
	(via
		(at 138.975 76.8)
		(size 0.4)
		(drill 0.15)
		(layers "F.Cu" "B.Cu")
		(net 108)
	)
	(segment
		(start 148.795 78.3266)
		(end 148.795 78.225)
		(width 0.1016)
		(layer "B.Cu")
		(net 108)
	)
	(segment
		(start 164.551601 88.617915)
		(end 164.551601 89.101601)
		(width 0.1016)
		(layer "B.Cu")
		(net 108)
	)
	(segment
		(start 152.830954 77.7484)
		(end 155.2908 80.208246)
		(width 0.1016)
		(layer "B.Cu")
		(net 108)
	)
	(segment
		(start 155.2908 80.208246)
		(end 155.2908 85.618246)
		(width 0.1016)
		(layer "B.Cu")
		(net 108)
	)
	(segment
		(start 155.2908 85.618246)
		(end 157.570954 87.8984)
		(width 0.1016)
		(layer "B.Cu")
		(net 108)
	)
	(segment
		(start 164.551601 89.101601)
		(end 164.915 89.465)
		(width 0.1016)
		(layer "B.Cu")
		(net 108)
	)
	(segment
		(start 145.0716 76.8968)
		(end 145.3716 76.8968)
		(width 0.1016)
		(layer "B.Cu")
		(net 108)
	)
	(segment
		(start 139.9 77.2)
		(end 140.471107 77.2)
		(width 0.1016)
		(layer "B.Cu")
		(net 108)
	)
	(segment
		(start 146.1216 78.6)
		(end 146.4216 78.6)
		(width 0.1016)
		(layer "B.Cu")
		(net 108)
	)
	(segment
		(start 144.595 77.475)
		(end 144.595 77.3734)
		(width 0.1016)
		(layer "B.Cu")
		(net 108)
	)
	(segment
		(start 164.95 89.5)
		(end 164.915 89.465)
		(width 0.1)
		(layer "B.Cu")
		(net 108)
	)
	(segment
		(start 163.832086 87.8984)
		(end 164.551601 88.617915)
		(width 0.1016)
		(layer "B.Cu")
		(net 108)
	)
	(segment
		(start 142.567914 77.7484)
		(end 144.3216 77.7484)
		(width 0.1016)
		(layer "B.Cu")
		(net 108)
	)
	(segment
		(start 148.2216 78.6)
		(end 148.5216 78.6)
		(width 0.1016)
		(layer "B.Cu")
		(net 108)
	)
	(segment
		(start 145.8482 77.475)
		(end 145.8482 78.3266)
		(width 0.1016)
		(layer "B.Cu")
		(net 108)
	)
	(segment
		(start 146.695 78.3266)
		(end 146.695 77.9516)
		(width 0.1016)
		(layer "B.Cu")
		(net 108)
	)
	(segment
		(start 157.570954 87.8984)
		(end 163.832086 87.8984)
		(width 0.1016)
		(layer "B.Cu")
		(net 108)
	)
	(segment
		(start 139.9 77.2)
		(end 139.375 77.2)
		(width 0.1)
		(layer "B.Cu")
		(net 108)
	)
	(segment
		(start 146.695 77.9516)
		(end 146.695 77.3734)
		(width 0.1016)
		(layer "B.Cu")
		(net 108)
	)
	(segment
		(start 141.642086 78.0184)
		(end 142.297914 78.0184)
		(width 0.1016)
		(layer "B.Cu")
		(net 108)
	)
	(segment
		(start 141.202086 77.5784)
		(end 141.642086 78.0184)
		(width 0.1016)
		(layer "B.Cu")
		(net 108)
	)
	(segment
		(start 164.95 90.415)
		(end 164.95 89.5)
		(width 0.1)
		(layer "B.Cu")
		(net 108)
	)
	(segment
		(start 139.375 77.2)
		(end 138.975 76.8)
		(width 0.1)
		(layer "B.Cu")
		(net 108)
	)
	(segment
		(start 149.2716 77.7484)
		(end 150.5 77.7484)
		(width 0.1016)
		(layer "B.Cu")
		(net 108)
	)
	(segment
		(start 140.471107 77.2)
		(end 140.849507 77.5784)
		(width 0.1016)
		(layer "B.Cu")
		(net 108)
	)
	(segment
		(start 145.8482 77.3734)
		(end 145.8482 77.475)
		(width 0.1016)
		(layer "B.Cu")
		(net 108)
	)
	(segment
		(start 147.9482 77.3734)
		(end 147.9482 77.7484)
		(width 0.1016)
		(layer "B.Cu")
		(net 108)
	)
	(segment
		(start 140.849507 77.5784)
		(end 141.202086 77.5784)
		(width 0.1016)
		(layer "B.Cu")
		(net 108)
	)
	(segment
		(start 142.297914 78.0184)
		(end 142.567914 77.7484)
		(width 0.1016)
		(layer "B.Cu")
		(net 108)
	)
	(segment
		(start 150.5 77.7484)
		(end 152.830954 77.7484)
		(width 0.1016)
		(layer "B.Cu")
		(net 108)
	)
	(segment
		(start 147.1716 76.8968)
		(end 147.4716 76.8968)
		(width 0.1016)
		(layer "B.Cu")
		(net 108)
	)
	(segment
		(start 147.9482 77.7484)
		(end 147.9482 78.3266)
		(width 0.1016)
		(layer "B.Cu")
		(net 108)
	)
	(arc
		(start 147.9482 78.3266)
		(mid 148.028277 78.519923)
		(end 148.2216 78.6)
		(width 0.1016)
		(layer "B.Cu")
		(net 108)
	)
	(arc
		(start 146.695 77.3734)
		(mid 146.834593 77.036393)
		(end 147.1716 76.8968)
		(width 0.1016)
		(layer "B.Cu")
		(net 108)
	)
	(arc
		(start 144.3216 77.7484)
		(mid 144.514923 77.668323)
		(end 144.595 77.475)
		(width 0.1016)
		(layer "B.Cu")
		(net 108)
	)
	(arc
		(start 145.8482 78.3266)
		(mid 145.928277 78.519923)
		(end 146.1216 78.6)
		(width 0.1016)
		(layer "B.Cu")
		(net 108)
	)
	(arc
		(start 146.4216 78.6)
		(mid 146.614923 78.519923)
		(end 146.695 78.3266)
		(width 0.1016)
		(layer "B.Cu")
		(net 108)
	)
	(arc
		(start 148.795 78.225)
		(mid 148.934593 77.887993)
		(end 149.2716 77.7484)
		(width 0.1016)
		(layer "B.Cu")
		(net 108)
	)
	(arc
		(start 144.595 77.3734)
		(mid 144.734593 77.036393)
		(end 145.0716 76.8968)
		(width 0.1016)
		(layer "B.Cu")
		(net 108)
	)
	(arc
		(start 145.3716 76.8968)
		(mid 145.708607 77.036393)
		(end 145.8482 77.3734)
		(width 0.1016)
		(layer "B.Cu")
		(net 108)
	)
	(arc
		(start 148.5216 78.6)
		(mid 148.714923 78.519923)
		(end 148.795 78.3266)
		(width 0.1016)
		(layer "B.Cu")
		(net 108)
	)
	(arc
		(start 147.4716 76.8968)
		(mid 147.808607 77.036393)
		(end 147.9482 77.3734)
		(width 0.1016)
		(layer "B.Cu")
		(net 108)
	)
	(via
		(at 139.675 77.6)
		(size 0.4)
		(drill 0.15)
		(layers "F.Cu" "B.Cu")
		(net 109)
	)
	(segment
		(start 140.7584 77.7816)
		(end 141.117914 77.7816)
		(width 0.1016)
		(layer "B.Cu")
		(net 109)
	)
	(segment
		(start 152.749045 78.199087)
		(end 152.749046 78.199087)
		(width 0.1016)
		(layer "B.Cu")
		(net 109)
	)
	(segment
		(start 148.2216 78.8032)
		(end 148.5216 78.8032)
		(width 0.1016)
		(layer "B.Cu")
		(net 109)
	)
	(segment
		(start 145.645 77.3734)
		(end 145.645 77.475)
		(width 0.1016)
		(layer "B.Cu")
		(net 109)
	)
	(segment
		(start 141.117914 77.7816)
		(end 141.557914 78.2216)
		(width 0.1016)
		(layer "B.Cu")
		(net 109)
	)
	(segment
		(start 146.8982 78.3266)
		(end 146.8982 77.9516)
		(width 0.1016)
		(layer "B.Cu")
		(net 109)
	)
	(segment
		(start 142.652086 77.9516)
		(end 143.6184 77.9516)
		(width 0.1016)
		(layer "B.Cu")
		(net 109)
	)
	(segment
		(start 144.0558 78.2058)
		(end 144.0558 78.0974)
		(width 0.1016)
		(layer "B.Cu")
		(net 109)
	)
	(segment
		(start 145.0716 77.1)
		(end 145.3716 77.1)
		(width 0.1016)
		(layer "B.Cu")
		(net 109)
	)
	(segment
		(start 146.8982 77.9516)
		(end 146.8982 77.3734)
		(width 0.1016)
		(layer "B.Cu")
		(net 109)
	)
	(segment
		(start 144.2016 77.9516)
		(end 144.2516 77.9516)
		(width 0.1016)
		(layer "B.Cu")
		(net 109)
	)
	(segment
		(start 143.7642 78.0974)
		(end 143.7642 78.2058)
		(width 0.1016)
		(layer "B.Cu")
		(net 109)
	)
	(segment
		(start 155.0892 85.701754)
		(end 157.489046 88.1016)
		(width 0.1016)
		(layer "B.Cu")
		(net 109)
	)
	(segment
		(start 150.5 77.9516)
		(end 152.749046 77.9516)
		(width 0.1016)
		(layer "B.Cu")
		(net 109)
	)
	(segment
		(start 142.382086 78.2216)
		(end 142.652086 77.9516)
		(width 0.1016)
		(layer "B.Cu")
		(net 109)
	)
	(segment
		(start 163.747914 88.1016)
		(end 164.348399 88.702085)
		(width 0.1016)
		(layer "B.Cu")
		(net 109)
	)
	(segment
		(start 148.9982 78.3266)
		(end 148.9982 78.225)
		(width 0.1016)
		(layer "B.Cu")
		(net 109)
	)
	(segment
		(start 153.244019 78.446573)
		(end 155.0892 80.291754)
		(width 0.1016)
		(layer "B.Cu")
		(net 109)
	)
	(segment
		(start 152.71369 78.48193)
		(end 152.71369 78.481929)
		(width 0.1016)
		(layer "B.Cu")
		(net 109)
	)
	(segment
		(start 149.2716 77.9516)
		(end 150.5 77.9516)
		(width 0.1016)
		(layer "B.Cu")
		(net 109)
	)
	(segment
		(start 164.348399 88.702085)
		(end 164.348399 89.101601)
		(width 0.1016)
		(layer "B.Cu")
		(net 109)
	)
	(segment
		(start 139.675 77.6)
		(end 140.0258 77.9508)
		(width 0.1016)
		(layer "B.Cu")
		(net 109)
	)
	(segment
		(start 141.557914 78.2216)
		(end 142.382086 78.2216)
		(width 0.1016)
		(layer "B.Cu")
		(net 109)
	)
	(segment
		(start 140.0258 77.9508)
		(end 140.5892 77.9508)
		(width 0.1016)
		(layer "B.Cu")
		(net 109)
	)
	(segment
		(start 155.0892 80.291754)
		(end 155.0892 85.701754)
		(width 0.1016)
		(layer "B.Cu")
		(net 109)
	)
	(segment
		(start 153.24402 78.446573)
		(end 153.244019 78.446573)
		(width 0.1016)
		(layer "B.Cu")
		(net 109)
	)
	(segment
		(start 147.745 77.7484)
		(end 147.745 78.3266)
		(width 0.1016)
		(layer "B.Cu")
		(net 109)
	)
	(segment
		(start 152.961177 78.481928)
		(end 152.961177 78.481929)
		(width 0.1016)
		(layer "B.Cu")
		(net 109)
	)
	(segment
		(start 164.348399 89.101601)
		(end 163.985 89.465)
		(width 0.1016)
		(layer "B.Cu")
		(net 109)
	)
	(segment
		(start 163.95 90.415)
		(end 163.95 89.5)
		(width 0.1)
		(layer "B.Cu")
		(net 109)
	)
	(segment
		(start 152.961177 78.481929)
		(end 152.996532 78.446573)
		(width 0.1016)
		(layer "B.Cu")
		(net 109)
	)
	(segment
		(start 147.745 77.3734)
		(end 147.745 77.7484)
		(width 0.1016)
		(layer "B.Cu")
		(net 109)
	)
	(segment
		(start 146.1216 78.8032)
		(end 146.4216 78.8032)
		(width 0.1016)
		(layer "B.Cu")
		(net 109)
	)
	(segment
		(start 145.645 77.475)
		(end 145.645 78.3266)
		(width 0.1016)
		(layer "B.Cu")
		(net 109)
	)
	(segment
		(start 163.95 89.5)
		(end 163.985 89.465)
		(width 0.1)
		(layer "B.Cu")
		(net 109)
	)
	(segment
		(start 152.749046 78.199087)
		(end 152.71369 78.234442)
		(width 0.1016)
		(layer "B.Cu")
		(net 109)
	)
	(segment
		(start 157.489046 88.1016)
		(end 163.747914 88.1016)
		(width 0.1016)
		(layer "B.Cu")
		(net 109)
	)
	(segment
		(start 147.1716 77.1)
		(end 147.4716 77.1)
		(width 0.1016)
		(layer "B.Cu")
		(net 109)
	)
	(segment
		(start 140.5892 77.9508)
		(end 140.7584 77.7816)
		(width 0.1016)
		(layer "B.Cu")
		(net 109)
	)
	(segment
		(start 144.7982 77.475)
		(end 144.7982 77.3734)
		(width 0.1016)
		(layer "B.Cu")
		(net 109)
	)
	(segment
		(start 144.2516 77.9516)
		(end 144.3216 77.9516)
		(width 0.1016)
		(layer "B.Cu")
		(net 109)
	)
	(arc
		(start 147.745 78.3266)
		(mid 147.884593 78.663607)
		(end 148.2216 78.8032)
		(width 0.1016)
		(layer "B.Cu")
		(net 109)
	)
	(arc
		(start 148.5216 78.8032)
		(mid 148.858607 78.663607)
		(end 148.9982 78.3266)
		(width 0.1016)
		(layer "B.Cu")
		(net 109)
	)
	(arc
		(start 144.7982 77.3734)
		(mid 144.878277 77.180077)
		(end 145.0716 77.1)
		(width 0.1016)
		(layer "B.Cu")
		(net 109)
	)
	(arc
		(start 152.71369 78.481929)
		(mid 152.837434 78.533185)
		(end 152.961177 78.481928)
		(width 0.1016)
		(layer "B.Cu")
		(net 109)
	)
	(arc
		(start 144.3216 77.9516)
		(mid 144.658607 77.812007)
		(end 144.7982 77.475)
		(width 0.1016)
		(layer "B.Cu")
		(net 109)
	)
	(arc
		(start 147.4716 77.1)
		(mid 147.664923 77.180077)
		(end 147.745 77.3734)
		(width 0.1016)
		(layer "B.Cu")
		(net 109)
	)
	(arc
		(start 152.71369 78.234442)
		(mid 152.662434 78.358186)
		(end 152.71369 78.48193)
		(width 0.1016)
		(layer "B.Cu")
		(net 109)
	)
	(arc
		(start 143.6184 77.9516)
		(mid 143.721496 77.994304)
		(end 143.7642 78.0974)
		(width 0.1016)
		(layer "B.Cu")
		(net 109)
	)
	(arc
		(start 146.8982 77.3734)
		(mid 146.978277 77.180077)
		(end 147.1716 77.1)
		(width 0.1016)
		(layer "B.Cu")
		(net 109)
	)
	(arc
		(start 148.9982 78.225)
		(mid 149.078277 78.031677)
		(end 149.2716 77.9516)
		(width 0.1016)
		(layer "B.Cu")
		(net 109)
	)
	(arc
		(start 152.749046 77.9516)
		(mid 152.800302 78.075344)
		(end 152.749045 78.199087)
		(width 0.1016)
		(layer "B.Cu")
		(net 109)
	)
	(arc
		(start 143.91 78.3516)
		(mid 144.013096 78.308896)
		(end 144.0558 78.2058)
		(width 0.1016)
		(layer "B.Cu")
		(net 109)
	)
	(arc
		(start 145.3716 77.1)
		(mid 145.564923 77.180077)
		(end 145.645 77.3734)
		(width 0.1016)
		(layer "B.Cu")
		(net 109)
	)
	(arc
		(start 146.4216 78.8032)
		(mid 146.758607 78.663607)
		(end 146.8982 78.3266)
		(width 0.1016)
		(layer "B.Cu")
		(net 109)
	)
	(arc
		(start 143.7642 78.2058)
		(mid 143.806904 78.308896)
		(end 143.91 78.3516)
		(width 0.1016)
		(layer "B.Cu")
		(net 109)
	)
	(arc
		(start 145.645 78.3266)
		(mid 145.784593 78.663607)
		(end 146.1216 78.8032)
		(width 0.1016)
		(layer "B.Cu")
		(net 109)
	)
	(arc
		(start 144.0558 78.0974)
		(mid 144.098504 77.994304)
		(end 144.2016 77.9516)
		(width 0.1016)
		(layer "B.Cu")
		(net 109)
	)
	(arc
		(start 152.996532 78.446573)
		(mid 153.120276 78.395317)
		(end 153.24402 78.446573)
		(width 0.1016)
		(layer "B.Cu")
		(net 109)
	)
	(via
		(at 139.675 82.4)
		(size 0.4)
		(drill 0.15)
		(layers "F.Cu" "B.Cu")
		(net 110)
	)
	(segment
		(start 150.9916 82.1716)
		(end 151.077914 82.1716)
		(width 0.1016)
		(layer "B.Cu")
		(net 110)
	)
	(segment
		(start 153.46 90.3)
		(end 153.45 90.3)
		(width 0.1)
		(layer "B.Cu")
		(net 110)
	)
	(segment
		(start 151.077914 82.1716)
		(end 153.840899 84.934585)
		(width 0.1016)
		(layer "B.Cu")
		(net 110)
	)
	(segment
		(start 146.85 82.6716)
		(end 146.85 82.52)
		(width 0.1016)
		(layer "B.Cu")
		(net 110)
	)
	(segment
		(start 140.587914 81.9716)
		(end 140.837914 82.2216)
		(width 0.1016)
		(layer "B.Cu")
		(net 110)
	)
	(segment
		(start 145.05 81.62)
		(end 145.05 81.4684)
		(width 0.1016)
		(layer "B.Cu")
		(net 110)
	)
	(segment
		(start 139.675 82.4)
		(end 139.675 82.325)
		(width 0.1016)
		(layer "B.Cu")
		(net 110)
	)
	(segment
		(start 143.737914 82.6216)
		(end 143.737914 82.4716)
		(width 0.1016)
		(layer "B.Cu")
		(net 110)
	)
	(segment
		(start 153.85 89.69)
		(end 153.85 89.91)
		(width 0.1)
		(layer "B.Cu")
		(net 110)
	)
	(segment
		(start 144.087914 82.1716)
		(end 144.4984 82.1716)
		(width 0.1016)
		(layer "B.Cu")
		(net 110)
	)
	(segment
		(start 153.85 89.91)
		(end 153.46 90.3)
		(width 0.1)
		(layer "B.Cu")
		(net 110)
	)
	(segment
		(start 145.7468 81.62)
		(end 145.7468 82.6716)
		(width 0.1016)
		(layer "B.Cu")
		(net 110)
	)
	(segment
		(start 153.840899 85.784585)
		(end 153.840899 88.939101)
		(width 0.1016)
		(layer "B.Cu")
		(net 110)
	)
	(segment
		(start 147.1984 82.1716)
		(end 147.758586 82.1716)
		(width 0.1016)
		(layer "B.Cu")
		(net 110)
	)
	(segment
		(start 150.9416 82.1716)
		(end 150.9916 82.1716)
		(width 0.1016)
		(layer "B.Cu")
		(net 110)
	)
	(segment
		(start 141.722086 81.8816)
		(end 142.547914 81.8816)
		(width 0.1016)
		(layer "B.Cu")
		(net 110)
	)
	(segment
		(start 145.7468 81.4684)
		(end 145.7468 81.62)
		(width 0.1016)
		(layer "B.Cu")
		(net 110)
	)
	(segment
		(start 153.840899 88.939101)
		(end 153.47 89.31)
		(width 0.1016)
		(layer "B.Cu")
		(net 110)
	)
	(segment
		(start 140.837914 82.2216)
		(end 141.382086 82.2216)
		(width 0.1016)
		(layer "B.Cu")
		(net 110)
	)
	(segment
		(start 140.086849 81.9716)
		(end 140.587914 81.9716)
		(width 0.1016)
		(layer "B.Cu")
		(net 110)
	)
	(segment
		(start 143.137914 82.4716)
		(end 143.137914 82.6216)
		(width 0.1016)
		(layer "B.Cu")
		(net 110)
	)
	(segment
		(start 147.758586 82.1716)
		(end 150.1416 82.1716)
		(width 0.1016)
		(layer "B.Cu")
		(net 110)
	)
	(segment
		(start 144.037914 82.1716)
		(end 144.087914 82.1716)
		(width 0.1016)
		(layer "B.Cu")
		(net 110)
	)
	(segment
		(start 153.47 89.31)
		(end 153.85 89.69)
		(width 0.1)
		(layer "B.Cu")
		(net 110)
	)
	(segment
		(start 139.675 82.325)
		(end 139.846019 82.153981)
		(width 0.1016)
		(layer "B.Cu")
		(net 110)
	)
	(segment
		(start 139.846019 82.153981)
		(end 139.904468 82.153981)
		(width 0.1016)
		(layer "B.Cu")
		(net 110)
	)
	(segment
		(start 139.904468 82.153981)
		(end 140.086849 81.9716)
		(width 0.1016)
		(layer "B.Cu")
		(net 110)
	)
	(segment
		(start 142.547914 81.8816)
		(end 142.837914 82.1716)
		(width 0.1016)
		(layer "B.Cu")
		(net 110)
	)
	(segment
		(start 153.840899 85.734585)
		(end 153.840899 85.784585)
		(width 0.1016)
		(layer "B.Cu")
		(net 110)
	)
	(segment
		(start 141.382086 82.2216)
		(end 141.722086 81.8816)
		(width 0.1016)
		(layer "B.Cu")
		(net 110)
	)
	(arc
		(start 142.837914 82.1716)
		(mid 143.050046 82.259468)
		(end 143.137914 82.4716)
		(width 0.1016)
		(layer "B.Cu")
		(net 110)
	)
	(arc
		(start 153.640899 85.134585)
		(mid 153.499478 85.193164)
		(end 153.440899 85.334585)
		(width 0.1016)
		(layer "B.Cu")
		(net 110)
	)
	(arc
		(start 144.4984 82.1716)
		(mid 144.88844 82.01004)
		(end 145.05 81.62)
		(width 0.1016)
		(layer "B.Cu")
		(net 110)
	)
	(arc
		(start 145.7468 82.6716)
		(mid 145.90836 83.06164)
		(end 146.2984 83.2232)
		(width 0.1016)
		(layer "B.Cu")
		(net 110)
	)
	(arc
		(start 146.2984 83.2232)
		(mid 146.68844 83.06164)
		(end 146.85 82.6716)
		(width 0.1016)
		(layer "B.Cu")
		(net 110)
	)
	(arc
		(start 153.440899 85.334585)
		(mid 153.499478 85.476006)
		(end 153.640899 85.534585)
		(width 0.1016)
		(layer "B.Cu")
		(net 110)
	)
	(arc
		(start 143.437914 82.9216)
		(mid 143.650046 82.833732)
		(end 143.737914 82.6216)
		(width 0.1016)
		(layer "B.Cu")
		(net 110)
	)
	(arc
		(start 150.5416 82.5716)
		(mid 150.683021 82.513021)
		(end 150.7416 82.3716)
		(width 0.1016)
		(layer "B.Cu")
		(net 110)
	)
	(arc
		(start 143.137914 82.6216)
		(mid 143.225782 82.833732)
		(end 143.437914 82.9216)
		(width 0.1016)
		(layer "B.Cu")
		(net 110)
	)
	(arc
		(start 150.3416 82.3716)
		(mid 150.400179 82.513021)
		(end 150.5416 82.5716)
		(width 0.1016)
		(layer "B.Cu")
		(net 110)
	)
	(arc
		(start 143.737914 82.4716)
		(mid 143.825782 82.259468)
		(end 144.037914 82.1716)
		(width 0.1016)
		(layer "B.Cu")
		(net 110)
	)
	(arc
		(start 145.3984 81.12)
		(mid 145.644756 81.222044)
		(end 145.7468 81.4684)
		(width 0.1016)
		(layer "B.Cu")
		(net 110)
	)
	(arc
		(start 146.85 82.52)
		(mid 146.952044 82.273644)
		(end 147.1984 82.1716)
		(width 0.1016)
		(layer "B.Cu")
		(net 110)
	)
	(arc
		(start 153.840899 84.934585)
		(mid 153.78232 85.076006)
		(end 153.640899 85.134585)
		(width 0.1016)
		(layer "B.Cu")
		(net 110)
	)
	(arc
		(start 153.640899 85.534585)
		(mid 153.78232 85.593164)
		(end 153.840899 85.734585)
		(width 0.1016)
		(layer "B.Cu")
		(net 110)
	)
	(arc
		(start 145.05 81.4684)
		(mid 145.152044 81.222044)
		(end 145.3984 81.12)
		(width 0.1016)
		(layer "B.Cu")
		(net 110)
	)
	(arc
		(start 150.7416 82.3716)
		(mid 150.800179 82.230179)
		(end 150.9416 82.1716)
		(width 0.1016)
		(layer "B.Cu")
		(net 110)
	)
	(arc
		(start 150.1416 82.1716)
		(mid 150.283021 82.230179)
		(end 150.3416 82.3716)
		(width 0.1016)
		(layer "B.Cu")
		(net 110)
	)
	(via
		(at 138.975 83.2)
		(size 0.4)
		(drill 0.15)
		(layers "F.Cu" "B.Cu")
		(net 111)
	)
	(segment
		(start 139.515 82.02)
		(end 139.325 82.21)
		(width 0.1)
		(layer "B.Cu")
		(net 111)
	)
	(segment
		(start 154.044101 88.939101)
		(end 154.415 89.31)
		(width 0.1016)
		(layer "B.Cu")
		(net 111)
	)
	(segment
		(start 141.297914 82.0184)
		(end 141.637914 81.6784)
		(width 0.1016)
		(layer "B.Cu")
		(net 111)
	)
	(segment
		(start 139.325 82.85)
		(end 138.975 83.2)
		(width 0.1)
		(layer "B.Cu")
		(net 111)
	)
	(segment
		(start 140.922086 82.0184)
		(end 141.297914 82.0184)
		(width 0.1016)
		(layer "B.Cu")
		(net 111)
	)
	(segment
		(start 139.5842 81.9508)
		(end 139.820307 81.9508)
		(width 0.1016)
		(layer "B.Cu")
		(net 111)
	)
	(segment
		(start 145.95 81.62)
		(end 145.95 82.6716)
		(width 0.1016)
		(layer "B.Cu")
		(net 111)
	)
	(segment
		(start 154.05 89.9)
		(end 154.45 90.3)
		(width 0.1)
		(layer "B.Cu")
		(net 111)
	)
	(segment
		(start 144.8468 81.62)
		(end 144.8468 81.4684)
		(width 0.1016)
		(layer "B.Cu")
		(net 111)
	)
	(segment
		(start 139.325 82.21)
		(end 139.325 82.85)
		(width 0.1)
		(layer "B.Cu")
		(net 111)
	)
	(segment
		(start 140.002707 81.7684)
		(end 140.672086 81.7684)
		(width 0.1016)
		(layer "B.Cu")
		(net 111)
	)
	(segment
		(start 145.95 81.4684)
		(end 145.95 81.62)
		(width 0.1016)
		(layer "B.Cu")
		(net 111)
	)
	(segment
		(start 139.820307 81.9508)
		(end 140.002707 81.7684)
		(width 0.1016)
		(layer "B.Cu")
		(net 111)
	)
	(segment
		(start 154.044101 84.850415)
		(end 154.044101 88.939101)
		(width 0.1016)
		(layer "B.Cu")
		(net 111)
	)
	(segment
		(start 147.1984 81.9684)
		(end 147.758586 81.9684)
		(width 0.1016)
		(layer "B.Cu")
		(net 111)
	)
	(segment
		(start 154.05 89.675)
		(end 154.05 89.9)
		(width 0.1)
		(layer "B.Cu")
		(net 111)
	)
	(segment
		(start 146.6468 82.6716)
		(end 146.6468 82.52)
		(width 0.1016)
		(layer "B.Cu")
		(net 111)
	)
	(segment
		(start 142.922086 81.9684)
		(end 144.4984 81.9684)
		(width 0.1016)
		(layer "B.Cu")
		(net 111)
	)
	(segment
		(start 139.515 82.02)
		(end 139.5842 81.9508)
		(width 0.1016)
		(layer "B.Cu")
		(net 111)
	)
	(segment
		(start 151.162086 81.9684)
		(end 154.044101 84.850415)
		(width 0.1016)
		(layer "B.Cu")
		(net 111)
	)
	(segment
		(start 141.637914 81.6784)
		(end 142.632086 81.6784)
		(width 0.1016)
		(layer "B.Cu")
		(net 111)
	)
	(segment
		(start 140.672086 81.7684)
		(end 140.922086 82.0184)
		(width 0.1016)
		(layer "B.Cu")
		(net 111)
	)
	(segment
		(start 142.632086 81.6784)
		(end 142.922086 81.9684)
		(width 0.1016)
		(layer "B.Cu")
		(net 111)
	)
	(segment
		(start 147.758586 81.9684)
		(end 151.162086 81.9684)
		(width 0.1016)
		(layer "B.Cu")
		(net 111)
	)
	(segment
		(start 154.415 89.31)
		(end 154.05 89.675)
		(width 0.1)
		(layer "B.Cu")
		(net 111)
	)
	(arc
		(start 146.6468 82.52)
		(mid 146.80836 82.12996)
		(end 147.1984 81.9684)
		(width 0.1016)
		(layer "B.Cu")
		(net 111)
	)
	(arc
		(start 144.8468 81.4684)
		(mid 145.00836 81.07836)
		(end 145.3984 80.9168)
		(width 0.1016)
		(layer "B.Cu")
		(net 111)
	)
	(arc
		(start 144.4984 81.9684)
		(mid 144.744756 81.866356)
		(end 144.8468 81.62)
		(width 0.1016)
		(layer "B.Cu")
		(net 111)
	)
	(arc
		(start 145.3984 80.9168)
		(mid 145.78844 81.07836)
		(end 145.95 81.4684)
		(width 0.1016)
		(layer "B.Cu")
		(net 111)
	)
	(arc
		(start 146.2984 83.02)
		(mid 146.544756 82.917956)
		(end 146.6468 82.6716)
		(width 0.1016)
		(layer "B.Cu")
		(net 111)
	)
	(arc
		(start 145.95 82.6716)
		(mid 146.052044 82.917956)
		(end 146.2984 83.02)
		(width 0.1016)
		(layer "B.Cu")
		(net 111)
	)
	(segment
		(start 137.05 92.75)
		(end 136.9 92.6)
		(width 0.1)
		(layer "F.Cu")
		(net 112)
	)
	(segment
		(start 137.05 92.965)
		(end 137.05 92.75)
		(width 0.1)
		(layer "F.Cu")
		(net 112)
	)
	(segment
		(start 136.65 93.365)
		(end 137.05 92.965)
		(width 0.1)
		(layer "F.Cu")
		(net 112)
	)
	(via
		(at 136.875 80.8)
		(size 0.4)
		(drill 0.15)
		(layers "F.Cu" "B.Cu")
		(net 112)
	)
	(via
		(at 136.9 92.6)
		(size 0.4)
		(drill 0.2)
		(layers "F.Cu" "B.Cu")
		(net 112)
	)
	(segment
		(start 137.05 92.965)
		(end 136.65 93.365)
		(width 0.1)
		(layer "B.Cu")
		(net 112)
	)
	(segment
		(start 137.05 92.75)
		(end 137.05 92.965)
		(width 0.1)
		(layer "B.Cu")
		(net 112)
	)
	(segment
		(start 136.9 92.6)
		(end 137.05 92.75)
		(width 0.1)
		(layer "B.Cu")
		(net 112)
	)
	(segment
		(start 136.95 83.867462)
		(end 136.95 87.72)
		(width 0.1)
		(layer "In3.Cu")
		(net 112)
	)
	(segment
		(start 136.875 80.8)
		(end 136.625 81.05)
		(width 0.1)
		(layer "In3.Cu")
		(net 112)
	)
	(segment
		(start 137.05 92.75)
		(end 136.9 92.6)
		(width 0.1)
		(layer "In3.Cu")
		(net 112)
	)
	(segment
		(start 136.45 89.895)
		(end 136.45 90.095)
		(width 0.1)
		(layer "In3.Cu")
		(net 112)
	)
	(segment
		(start 137.381581 93.423003)
		(end 137.05 93.091422)
		(width 0.1)
		(layer "In3.Cu")
		(net 112)
	)
	(segment
		(start 137.025 87.795)
		(end 137.125 87.795)
		(width 0.1)
		(layer "In3.Cu")
		(net 112)
	)
	(segment
		(start 137.125 88.595)
		(end 137.025 88.595)
		(width 0.1)
		(layer "In3.Cu")
		(net 112)
	)
	(segment
		(start 136.75 88.995)
		(end 137.65 88.995)
		(width 0.1)
		(layer "In3.Cu")
		(net 112)
	)
	(segment
		(start 136.625 81.05)
		(end 136.625 81.351493)
		(width 0.1)
		(layer "In3.Cu")
		(net 112)
	)
	(segment
		(start 136.95 91.008578)
		(end 138.25 92.308578)
		(width 0.1)
		(layer "In3.Cu")
		(net 112)
	)
	(segment
		(start 138.25 92.308578)
		(end 138.25 93.041422)
		(width 0.1)
		(layer "In3.Cu")
		(net 112)
	)
	(segment
		(start 138.25 93.041422)
		(end 137.868419 93.423003)
		(width 0.1)
		(layer "In3.Cu")
		(net 112)
	)
	(segment
		(start 137.65 89.795)
		(end 136.95 89.795)
		(width 0.1)
		(layer "In3.Cu")
		(net 112)
	)
	(segment
		(start 136.95 89.795)
		(end 136.55 89.795)
		(width 0.1)
		(layer "In3.Cu")
		(net 112)
	)
	(segment
		(start 136.55 90.195)
		(end 136.65 90.195)
		(width 0.1)
		(layer "In3.Cu")
		(net 112)
	)
	(segment
		(start 136.95 90.495)
		(end 136.95 91.008578)
		(width 0.1)
		(layer "In3.Cu")
		(net 112)
	)
	(segment
		(start 137.4 88.07)
		(end 137.4 88.32)
		(width 0.1)
		(layer "In3.Cu")
		(net 112)
	)
	(segment
		(start 136.45 83.367462)
		(end 136.95 83.867462)
		(width 0.1)
		(layer "In3.Cu")
		(net 112)
	)
	(segment
		(start 137.025 88.595)
		(end 136.35 88.595)
		(width 0.1)
		(layer "In3.Cu")
		(net 112)
	)
	(segment
		(start 137.868419 93.423003)
		(end 137.381581 93.423003)
		(width 0.1)
		(layer "In3.Cu")
		(net 112)
	)
	(segment
		(start 136.35 88.995)
		(end 136.75 88.995)
		(width 0.1)
		(layer "In3.Cu")
		(net 112)
	)
	(segment
		(start 137.05 93.091422)
		(end 137.05 92.75)
		(width 0.1)
		(layer "In3.Cu")
		(net 112)
	)
	(segment
		(start 136.45 81.526493)
		(end 136.45 83.367462)
		(width 0.1)
		(layer "In3.Cu")
		(net 112)
	)
	(segment
		(start 136.625 81.351493)
		(end 136.45 81.526493)
		(width 0.1)
		(layer "In3.Cu")
		(net 112)
	)
	(arc
		(start 137.4 88.32)
		(mid 137.319454 88.514454)
		(end 137.125 88.595)
		(width 0.1)
		(layer "In3.Cu")
		(net 112)
	)
	(arc
		(start 138.05 89.395)
		(mid 137.932843 89.677843)
		(end 137.65 89.795)
		(width 0.1)
		(layer "In3.Cu")
		(net 112)
	)
	(arc
		(start 137.125 87.795)
		(mid 137.319454 87.875546)
		(end 137.4 88.07)
		(width 0.1)
		(layer "In3.Cu")
		(net 112)
	)
	(arc
		(start 136.35 88.595)
		(mid 136.208579 88.653579)
		(end 136.15 88.795)
		(width 0.1)
		(layer "In3.Cu")
		(net 112)
	)
	(arc
		(start 136.55 89.795)
		(mid 136.479289 89.824289)
		(end 136.45 89.895)
		(width 0.1)
		(layer "In3.Cu")
		(net 112)
	)
	(arc
		(start 136.15 88.795)
		(mid 136.208579 88.936421)
		(end 136.35 88.995)
		(width 0.1)
		(layer "In3.Cu")
		(net 112)
	)
	(arc
		(start 136.45 90.095)
		(mid 136.479289 90.165711)
		(end 136.55 90.195)
		(width 0.1)
		(layer "In3.Cu")
		(net 112)
	)
	(arc
		(start 136.65 90.195)
		(mid 136.862132 90.282868)
		(end 136.95 90.495)
		(width 0.1)
		(layer "In3.Cu")
		(net 112)
	)
	(arc
		(start 136.95 87.72)
		(mid 136.971967 87.773033)
		(end 137.025 87.795)
		(width 0.1)
		(layer "In3.Cu")
		(net 112)
	)
	(arc
		(start 137.65 88.995)
		(mid 137.932843 89.112157)
		(end 138.05 89.395)
		(width 0.1)
		(layer "In3.Cu")
		(net 112)
	)
	(segment
		(start 137.25 92.965)
		(end 137.25 92.75)
		(width 0.1)
		(layer "F.Cu")
		(net 113)
	)
	(segment
		(start 137.65 93.365)
		(end 137.25 92.965)
		(width 0.1)
		(layer "F.Cu")
		(net 113)
	)
	(segment
		(start 137.25 92.75)
		(end 137.4 92.6)
		(width 0.1)
		(layer "F.Cu")
		(net 113)
	)
	(via
		(at 137.4 92.6)
		(size 0.4)
		(drill 0.2)
		(layers "F.Cu" "B.Cu")
		(net 113)
	)
	(via
		(at 136.175 80.8)
		(size 0.4)
		(drill 0.15)
		(layers "F.Cu" "B.Cu")
		(net 113)
	)
	(segment
		(start 137.25 92.75)
		(end 137.25 92.965)
		(width 0.1)
		(layer "B.Cu")
		(net 113)
	)
	(segment
		(start 137.4 92.6)
		(end 137.25 92.75)
		(width 0.1)
		(layer "B.Cu")
		(net 113)
	)
	(segment
		(start 137.25 92.965)
		(end 137.65 93.365)
		(width 0.1)
		(layer "B.Cu")
		(net 113)
	)
	(segment
		(start 137.25 93.008578)
		(end 137.464425 93.223003)
		(width 0.1)
		(layer "In3.Cu")
		(net 113)
	)
	(segment
		(start 136.75 87.72)
		(end 136.75 83.950306)
		(width 0.1)
		(layer "In3.Cu")
		(net 113)
	)
	(segment
		(start 136.899691 91.241114)
		(end 136.75 91.091422)
		(width 0.1)
		(layer "In3.Cu")
		(net 113)
	)
	(segment
		(start 138.05 92.391422)
		(end 137.854289 92.195711)
		(width 0.1)
		(layer "In3.Cu")
		(net 113)
	)
	(segment
		(start 136.35 88.395)
		(end 137.025 88.395)
		(width 0.1)
		(layer "In3.Cu")
		(net 113)
	)
	(segment
		(start 137.2 88.32)
		(end 137.2 88.07)
		(width 0.1)
		(layer "In3.Cu")
		(net 113)
	)
	(segment
		(start 137.147181 91.700735)
		(end 137.14718 91.700735)
		(width 0.1)
		(layer "In3.Cu")
		(net 113)
	)
	(segment
		(start 136.935048 91.700736)
		(end 136.899692 91.66538)
		(width 0.1)
		(layer "In3.Cu")
		(net 113)
	)
	(segment
		(start 137.785575 93.223003)
		(end 138.05 92.958578)
		(width 0.1)
		(layer "In3.Cu")
		(net 113)
	)
	(segment
		(start 136.425 81.05)
		(end 136.175 80.8)
		(width 0.1)
		(layer "In3.Cu")
		(net 113)
	)
	(segment
		(start 136.425 81.268649)
		(end 136.425 81.05)
		(width 0.1)
		(layer "In3.Cu")
		(net 113)
	)
	(segment
		(start 137.464425 93.223003)
		(end 137.785575 93.223003)
		(width 0.1)
		(layer "In3.Cu")
		(net 113)
	)
	(segment
		(start 136.935046 91.700735)
		(end 136.935048 91.700736)
		(width 0.1)
		(layer "In3.Cu")
		(net 113)
	)
	(segment
		(start 137.642156 92.19571)
		(end 137.642155 92.19571)
		(width 0.1)
		(layer "In3.Cu")
		(net 113)
	)
	(segment
		(start 137.394666 91.736089)
		(end 137.359314 91.700736)
		(width 0.1)
		(layer "In3.Cu")
		(net 113)
	)
	(segment
		(start 137.430023 92.195711)
		(end 137.394667 92.160355)
		(width 0.1)
		(layer "In3.Cu")
		(net 113)
	)
	(segment
		(start 136.75 89.195)
		(end 136.35 89.195)
		(width 0.1)
		(layer "In3.Cu")
		(net 113)
	)
	(segment
		(start 137.125 87.995)
		(end 137.025 87.995)
		(width 0.1)
		(layer "In3.Cu")
		(net 113)
	)
	(segment
		(start 136.25 90.095)
		(end 136.25 89.895)
		(width 0.1)
		(layer "In3.Cu")
		(net 113)
	)
	(segment
		(start 137.025 88.395)
		(end 137.125 88.395)
		(width 0.1)
		(layer "In3.Cu")
		(net 113)
	)
	(segment
		(start 137.25 92.75)
		(end 137.25 93.008578)
		(width 0.1)
		(layer "In3.Cu")
		(net 113)
	)
	(segment
		(start 136.65 90.395)
		(end 136.55 90.395)
		(width 0.1)
		(layer "In3.Cu")
		(net 113)
	)
	(segment
		(start 136.55 89.595)
		(end 136.95 89.595)
		(width 0.1)
		(layer "In3.Cu")
		(net 113)
	)
	(segment
		(start 138.05 92.958578)
		(end 138.05 92.391422)
		(width 0.1)
		(layer "In3.Cu")
		(net 113)
	)
	(segment
		(start 136.899692 91.241114)
		(end 136.899691 91.241114)
		(width 0.1)
		(layer "In3.Cu")
		(net 113)
	)
	(segment
		(start 137.65 89.195)
		(end 136.75 89.195)
		(width 0.1)
		(layer "In3.Cu")
		(net 113)
	)
	(segment
		(start 136.75 91.091422)
		(end 136.75 90.495)
		(width 0.1)
		(layer "In3.Cu")
		(net 113)
	)
	(segment
		(start 137.430021 92.19571)
		(end 137.430023 92.195711)
		(width 0.1)
		(layer "In3.Cu")
		(net 113)
	)
	(segment
		(start 136.25 83.450306)
		(end 136.25 81.443649)
		(width 0.1)
		(layer "In3.Cu")
		(net 113)
	)
	(segment
		(start 136.95 89.595)
		(end 137.65 89.595)
		(width 0.1)
		(layer "In3.Cu")
		(net 113)
	)
	(segment
		(start 137.4 92.6)
		(end 137.25 92.75)
		(width 0.1)
		(layer "In3.Cu")
		(net 113)
	)
	(segment
		(start 136.75 83.950306)
		(end 136.25 83.450306)
		(width 0.1)
		(layer "In3.Cu")
		(net 113)
	)
	(segment
		(start 137.394667 91.736089)
		(end 137.394666 91.736089)
		(width 0.1)
		(layer "In3.Cu")
		(net 113)
	)
	(segment
		(start 136.25 81.443649)
		(end 136.425 81.268649)
		(width 0.1)
		(layer "In3.Cu")
		(net 113)
	)
	(arc
		(start 136.75 90.495)
		(mid 136.720711 90.424289)
		(end 136.65 90.395)
		(width 0.1)
		(layer "In3.Cu")
		(net 113)
	)
	(arc
		(start 137.14718 91.700735)
		(mid 137.041114 91.74467)
		(end 136.935046 91.700735)
		(width 0.1)
		(layer "In3.Cu")
		(net 113)
	)
	(arc
		(start 136.25 89.895)
		(mid 136.337868 89.682868)
		(end 136.55 89.595)
		(width 0.1)
		(layer "In3.Cu")
		(net 113)
	)
	(arc
		(start 136.55 90.395)
		(mid 136.337868 90.307132)
		(end 136.25 90.095)
		(width 0.1)
		(layer "In3.Cu")
		(net 113)
	)
	(arc
		(start 135.95 88.795)
		(mid 136.067157 88.512157)
		(end 136.35 88.395)
		(width 0.1)
		(layer "In3.Cu")
		(net 113)
	)
	(arc
		(start 137.854289 92.195711)
		(mid 137.748222 92.151775)
		(end 137.642156 92.19571)
		(width 0.1)
		(layer "In3.Cu")
		(net 113)
	)
	(arc
		(start 136.899692 91.453248)
		(mid 136.943625 91.34718)
		(end 136.899692 91.241114)
		(width 0.1)
		(layer "In3.Cu")
		(net 113)
	)
	(arc
		(start 137.359314 91.700736)
		(mid 137.253247 91.6568)
		(end 137.147181 91.700735)
		(width 0.1)
		(layer "In3.Cu")
		(net 113)
	)
	(arc
		(start 137.65 89.595)
		(mid 137.791421 89.536421)
		(end 137.85 89.395)
		(width 0.1)
		(layer "In3.Cu")
		(net 113)
	)
	(arc
		(start 137.394667 91.948223)
		(mid 137.4386 91.842155)
		(end 137.394667 91.736089)
		(width 0.1)
		(layer "In3.Cu")
		(net 113)
	)
	(arc
		(start 137.125 88.395)
		(mid 137.178033 88.373033)
		(end 137.2 88.32)
		(width 0.1)
		(layer "In3.Cu")
		(net 113)
	)
	(arc
		(start 137.642155 92.19571)
		(mid 137.536089 92.239645)
		(end 137.430021 92.19571)
		(width 0.1)
		(layer "In3.Cu")
		(net 113)
	)
	(arc
		(start 137.394667 92.160355)
		(mid 137.350733 92.054289)
		(end 137.394667 91.948223)
		(width 0.1)
		(layer "In3.Cu")
		(net 113)
	)
	(arc
		(start 137.025 87.995)
		(mid 136.830546 87.914454)
		(end 136.75 87.72)
		(width 0.1)
		(layer "In3.Cu")
		(net 113)
	)
	(arc
		(start 136.899692 91.66538)
		(mid 136.855758 91.559314)
		(end 136.899692 91.453248)
		(width 0.1)
		(layer "In3.Cu")
		(net 113)
	)
	(arc
		(start 137.85 89.395)
		(mid 137.791421 89.253579)
		(end 137.65 89.195)
		(width 0.1)
		(layer "In3.Cu")
		(net 113)
	)
	(arc
		(start 136.35 89.195)
		(mid 136.067157 89.077843)
		(end 135.95 88.795)
		(width 0.1)
		(layer "In3.Cu")
		(net 113)
	)
	(arc
		(start 137.2 88.07)
		(mid 137.178033 88.016967)
		(end 137.125 87.995)
		(width 0.1)
		(layer "In3.Cu")
		(net 113)
	)
	(segment
		(start 105.0135 71.8635)
		(end 105.025 71.875)
		(width 0.09)
		(layer "F.Cu")
		(net 117)
	)
	(segment
		(start 105.0135 70.988)
		(end 105.0135 71.8635)
		(width 0.09)
		(layer "F.Cu")
		(net 117)
	)
	(via
		(at 105.025 71.875)
		(size 0.4)
		(drill 0.15)
		(layers "F.Cu" "B.Cu")
		(net 117)
	)
	(segment
		(start 105.025 71.875)
		(end 105.025 71.275)
		(width 0.09)
		(layer "B.Cu")
		(net 117)
	)
	(segment
		(start 105.025 71.275)
		(end 104.875 71.125)
		(width 0.09)
		(layer "B.Cu")
		(net 117)
	)
	(segment
		(start 105.8495 96.744169)
		(end 105.8495 95.882608)
		(width 0.15)
		(layer "F.Cu")
		(net 118)
	)
	(segment
		(start 105.8495 95.882608)
		(end 107.125 94.607108)
		(width 0.15)
		(layer "F.Cu")
		(net 118)
	)
	(segment
		(start 105.925 98.625)
		(end 105.925 96.819669)
		(width 0.15)
		(layer "F.Cu")
		(net 118)
	)
	(segment
		(start 105.925 96.819669)
		(end 105.8495 96.744169)
		(width 0.15)
		(layer "F.Cu")
		(net 118)
	)
	(segment
		(start 107.125 94.607108)
		(end 107.125 94.285)
		(width 0.15)
		(layer "F.Cu")
		(net 118)
	)
	(segment
		(start 117.625 94.607108)
		(end 117.625 94.285)
		(width 0.15)
		(layer "F.Cu")
		(net 119)
	)
	(segment
		(start 116.3495 95.882608)
		(end 117.625 94.607108)
		(width 0.15)
		(layer "F.Cu")
		(net 119)
	)
	(segment
		(start 116.425 98.625)
		(end 116.425 96.819669)
		(width 0.15)
		(layer "F.Cu")
		(net 119)
	)
	(segment
		(start 116.425 96.819669)
		(end 116.3495 96.744169)
		(width 0.15)
		(layer "F.Cu")
		(net 119)
	)
	(segment
		(start 116.3495 96.744169)
		(end 116.3495 95.882608)
		(width 0.15)
		(layer "F.Cu")
		(net 119)
	)
	(segment
		(start 164.45 94.930105)
		(end 164.45 94.285)
		(width 0.15)
		(layer "F.Cu")
		(net 120)
	)
	(segment
		(start 165.6755 96.155605)
		(end 164.45 94.930105)
		(width 0.15)
		(layer "F.Cu")
		(net 120)
	)
	(via
		(at 165.6755 96.155605)
		(size 0.4)
		(drill 0.2)
		(layers "F.Cu" "B.Cu")
		(net 120)
	)
	(segment
		(start 165.7758 96.693869)
		(end 165.65 96.819669)
		(width 0.15)
		(layer "B.Cu")
		(net 120)
	)
	(segment
		(start 165.6755 96.155605)
		(end 165.7758 96.255905)
		(width 0.15)
		(layer "B.Cu")
		(net 120)
	)
	(segment
		(start 165.7758 96.255905)
		(end 165.7758 96.693869)
		(width 0.15)
		(layer "B.Cu")
		(net 120)
	)
	(segment
		(start 165.65 96.819669)
		(end 165.65 98.625)
		(width 0.15)
		(layer "B.Cu")
		(net 120)
	)
	(segment
		(start 155.2255 96.2)
		(end 155.2255 95.882608)
		(width 0.15)
		(layer "F.Cu")
		(net 121)
	)
	(segment
		(start 155.2255 95.882608)
		(end 153.95 94.607108)
		(width 0.15)
		(layer "F.Cu")
		(net 121)
	)
	(segment
		(start 153.95 94.607108)
		(end 153.95 94.285)
		(width 0.15)
		(layer "F.Cu")
		(net 121)
	)
	(via
		(at 155.2255 96.2)
		(size 0.4)
		(drill 0.2)
		(layers "F.Cu" "B.Cu")
		(net 121)
	)
	(segment
		(start 155.15 96.819669)
		(end 155.2255 96.744169)
		(width 0.15)
		(layer "B.Cu")
		(net 121)
	)
	(segment
		(start 155.15 98.625)
		(end 155.15 96.819669)
		(width 0.15)
		(layer "B.Cu")
		(net 121)
	)
	(segment
		(start 155.2255 96.744169)
		(end 155.2255 96.2)
		(width 0.15)
		(layer "B.Cu")
		(net 121)
	)
	(segment
		(start 167.6 96.2)
		(end 167.6 95.95)
		(width 0.15)
		(layer "F.Cu")
		(net 122)
	)
	(segment
		(start 167.0875 95.4375)
		(end 167.0875 94.25)
		(width 0.15)
		(layer "F.Cu")
		(net 122)
	)
	(segment
		(start 167.6 95.95)
		(end 167.0875 95.4375)
		(width 0.15)
		(layer "F.Cu")
		(net 122)
	)
	(via
		(at 167.6 96.2)
		(size 0.4)
		(drill 0.2)
		(layers "F.Cu" "B.Cu")
		(net 122)
	)
	(segment
		(start 167.6 96.2)
		(end 167.65 96.25)
		(width 0.15)
		(layer "B.Cu")
		(net 122)
	)
	(segment
		(start 167.65 96.25)
		(end 167.65 98.625)
		(width 0.15)
		(layer "B.Cu")
		(net 122)
	)
	(segment
		(start 165.95 95.4)
		(end 165.95 94.25)
		(width 0.15)
		(layer "F.Cu")
		(net 123)
	)
	(segment
		(start 166.6 96.2)
		(end 166.6 96.05)
		(width 0.15)
		(layer "F.Cu")
		(net 123)
	)
	(segment
		(start 166.6 96.05)
		(end 165.95 95.4)
		(width 0.15)
		(layer "F.Cu")
		(net 123)
	)
	(via
		(at 166.6 96.2)
		(size 0.4)
		(drill 0.2)
		(layers "F.Cu" "B.Cu")
		(net 123)
	)
	(segment
		(start 166.65 96.25)
		(end 166.65 98.65)
		(width 0.15)
		(layer "B.Cu")
		(net 123)
	)
	(segment
		(start 166.6 96.2)
		(end 166.65 96.25)
		(width 0.15)
		(layer "B.Cu")
		(net 123)
	)
	(segment
		(start 167.425 96.725)
		(end 167.1 96.4)
		(width 0.15)
		(layer "F.Cu")
		(net 124)
	)
	(segment
		(start 167.425 98.6)
		(end 167.425 96.725)
		(width 0.15)
		(layer "F.Cu")
		(net 124)
	)
	(segment
		(start 167.4 98.625)
		(end 167.425 98.6)
		(width 0.15)
		(layer "F.Cu")
		(net 124)
	)
	(segment
		(start 166.45 95.35)
		(end 166.45 94.25)
		(width 0.15)
		(layer "F.Cu")
		(net 124)
	)
	(segment
		(start 167.1 96)
		(end 166.45 95.35)
		(width 0.15)
		(layer "F.Cu")
		(net 124)
	)
	(segment
		(start 167.1 96.4)
		(end 167.1 96)
		(width 0.15)
		(layer "F.Cu")
		(net 124)
	)
	(segment
		(start 166.05 96)
		(end 165.3125 95.2625)
		(width 0.15)
		(layer "F.Cu")
		(net 125)
	)
	(segment
		(start 166.4 98.625)
		(end 166.425 98.6)
		(width 0.15)
		(layer "F.Cu")
		(net 125)
	)
	(segment
		(start 165.3125 95.2625)
		(end 165.3125 94.25)
		(width 0.15)
		(layer "F.Cu")
		(net 125)
	)
	(segment
		(start 166.425 98.6)
		(end 166.425 96.725)
		(width 0.15)
		(layer "F.Cu")
		(net 125)
	)
	(segment
		(start 166.425 96.725)
		(end 166.05 96.35)
		(width 0.15)
		(layer "F.Cu")
		(net 125)
	)
	(segment
		(start 166.05 96.35)
		(end 166.05 96)
		(width 0.15)
		(layer "F.Cu")
		(net 125)
	)
	(segment
		(start 165.4 97.244975)
		(end 165.5 97.144975)
		(width 0.1)
		(layer "F.Cu")
		(net 126)
	)
	(segment
		(start 165.5 97.144975)
		(end 165.5 96.855025)
		(width 0.1)
		(layer "F.Cu")
		(net 126)
	)
	(segment
		(start 165.4 98.625)
		(end 165.4 97.244975)
		(width 0.1)
		(layer "F.Cu")
		(net 126)
	)
	(segment
		(start 165.368964 96.549987)
		(end 165.5 96.681023)
		(width 0.1016)
		(layer "F.Cu")
		(net 126)
	)
	(segment
		(start 165.5 96.681023)
		(end 165.5 96.855025)
		(width 0.1016)
		(layer "F.Cu")
		(net 126)
	)
	(via
		(at 165.368964 96.549987)
		(size 0.4)
		(drill 0.2)
		(layers "F.Cu" "B.Cu")
		(net 126)
	)
	(segment
		(start 165.150793 96.135694)
		(end 165.150793 95.907107)
		(width 0.1016)
		(layer "B.Cu")
		(net 126)
	)
	(segment
		(start 164.5516 95.307914)
		(end 164.551601 91.783399)
		(width 0.1016)
		(layer "B.Cu")
		(net 126)
	)
	(segment
		(start 164.551601 91.783399)
		(end 164.95 91.385)
		(width 0.1016)
		(layer "B.Cu")
		(net 126)
	)
	(segment
		(start 165.368964 96.549987)
		(end 165.25 96.431023)
		(width 0.1016)
		(layer "B.Cu")
		(net 126)
	)
	(segment
		(start 165.150793 95.907107)
		(end 164.5516 95.307914)
		(width 0.1016)
		(layer "B.Cu")
		(net 126)
	)
	(segment
		(start 165.25 96.234901)
		(end 165.150793 96.135694)
		(width 0.1016)
		(layer "B.Cu")
		(net 126)
	)
	(segment
		(start 165.25 96.431023)
		(end 165.25 96.234901)
		(width 0.1016)
		(layer "B.Cu")
		(net 126)
	)
	(segment
		(start 164.8 96.479408)
		(end 164.8992 96.380208)
		(width 0.1016)
		(layer "F.Cu")
		(net 127)
	)
	(segment
		(start 164.9 98.625)
		(end 164.9 97.244975)
		(width 0.1)
		(layer "F.Cu")
		(net 127)
	)
	(segment
		(start 164.8 96.855025)
		(end 164.8 96.479408)
		(width 0.1016)
		(layer "F.Cu")
		(net 127)
	)
	(segment
		(start 164.8 97.144975)
		(end 164.8 96.855025)
		(width 0.1)
		(layer "F.Cu")
		(net 127)
	)
	(segment
		(start 164.9 97.244975)
		(end 164.8 97.144975)
		(width 0.1)
		(layer "F.Cu")
		(net 127)
	)
	(via
		(at 164.8992 96.380208)
		(size 0.4)
		(drill 0.2)
		(layers "F.Cu" "B.Cu")
		(net 127)
	)
	(segment
		(start 164.947592 96.331816)
		(end 164.947592 95.991278)
		(width 0.1016)
		(layer "B.Cu")
		(net 127)
	)
	(segment
		(start 164.348399 91.783399)
		(end 163.95 91.385)
		(width 0.1016)
		(layer "B.Cu")
		(net 127)
	)
	(segment
		(start 164.8992 96.380208)
		(end 164.947592 96.331816)
		(width 0.1016)
		(layer "B.Cu")
		(net 127)
	)
	(segment
		(start 164.947592 95.991278)
		(end 164.3484 95.392086)
		(width 0.1016)
		(layer "B.Cu")
		(net 127)
	)
	(segment
		(start 164.3484 95.392086)
		(end 164.348399 91.783399)
		(width 0.1016)
		(layer "B.Cu")
		(net 127)
	)
	(segment
		(start 108.925 96.645023)
		(end 108.925 98.625)
		(width 0.15)
		(layer "F.Cu")
		(net 128)
	)
	(segment
		(start 104.4875 92.7875)
		(end 104.4875 93.35)
		(width 0.15)
		(layer "F.Cu")
		(net 128)
	)
	(segment
		(start 129.875 74.075)
		(end 129.875 74.4)
		(width 0.15)
		(layer "F.Cu")
		(net 128)
	)
	(segment
		(start 104.575 92.7)
		(end 104.4875 92.7875)
		(width 0.15)
		(layer "F.Cu")
		(net 128)
	)
	(segment
		(start 109.025 96.545023)
		(end 108.925 96.645023)
		(width 0.15)
		(layer "F.Cu")
		(net 128)
	)
	(segment
		(start 104.575 92.7)
		(end 104.575 85.75)
		(width 0.15)
		(layer "F.Cu")
		(net 128)
	)
	(segment
		(start 104.575 85.75)
		(end 117.125 73.2)
		(width 0.15)
		(layer "F.Cu")
		(net 128)
	)
	(segment
		(start 117.125 73.2)
		(end 129 73.2)
		(width 0.15)
		(layer "F.Cu")
		(net 128)
	)
	(segment
		(start 129 73.2)
		(end 129.875 74.075)
		(width 0.15)
		(layer "F.Cu")
		(net 128)
	)
	(via
		(at 104.575 92.7)
		(size 0.4)
		(drill 0.2)
		(layers "F.Cu" "B.Cu")
		(net 128)
	)
	(via
		(at 109.025 96.545023)
		(size 0.4)
		(drill 0.2)
		(layers "F.Cu" "B.Cu")
		(net 128)
	)
	(segment
		(start 104.4875 92.7875)
		(end 104.575 92.7)
		(width 0.15)
		(layer "B.Cu")
		(net 128)
	)
	(segment
		(start 104.4875 93.35)
		(end 104.4875 92.7875)
		(width 0.15)
		(layer "B.Cu")
		(net 128)
	)
	(segment
		(start 108.279977 95.8)
		(end 107.175 95.8)
		(width 0.15)
		(layer "In3.Cu")
		(net 128)
	)
	(segment
		(start 107.175 95.8)
		(end 104.575 93.2)
		(width 0.15)
		(layer "In3.Cu")
		(net 128)
	)
	(segment
		(start 104.575 93.2)
		(end 104.575 92.7)
		(width 0.15)
		(layer "In3.Cu")
		(net 128)
	)
	(segment
		(start 109.025 96.545023)
		(end 108.279977 95.8)
		(width 0.15)
		(layer "In3.Cu")
		(net 128)
	)
	(segment
		(start 162.4625 95.2625)
		(end 162.4625 94.25)
		(width 0.15)
		(layer "F.Cu")
		(net 129)
	)
	(segment
		(start 163.4245 96.4)
		(end 163.4245 96.2245)
		(width 0.15)
		(layer "F.Cu")
		(net 129)
	)
	(segment
		(start 163.4245 96.2245)
		(end 162.4625 95.2625)
		(width 0.15)
		(layer "F.Cu")
		(net 129)
	)
	(via
		(at 163.4245 96.4)
		(size 0.4)
		(drill 0.2)
		(layers "F.Cu" "B.Cu")
		(net 129)
	)
	(segment
		(start 163.675 98.6)
		(end 163.65 98.625)
		(width 0.15)
		(layer "B.Cu")
		(net 129)
	)
	(segment
		(start 163.4245 96.4)
		(end 163.675 96.6505)
		(width 0.15)
		(layer "B.Cu")
		(net 129)
	)
	(segment
		(start 163.675 96.6505)
		(end 163.675 98.6)
		(width 0.15)
		(layer "B.Cu")
		(net 129)
	)
	(segment
		(start 161.825 95.225)
		(end 161.825 94.25)
		(width 0.15)
		(layer "F.Cu")
		(net 130)
	)
	(segment
		(start 162.9 98.625)
		(end 162.9 96.819669)
		(width 0.15)
		(layer "F.Cu")
		(net 130)
	)
	(segment
		(start 162.9 96.819669)
		(end 163 96.719669)
		(width 0.15)
		(layer "F.Cu")
		(net 130)
	)
	(segment
		(start 163 96.4)
		(end 161.825 95.225)
		(width 0.15)
		(layer "F.Cu")
		(net 130)
	)
	(segment
		(start 163 96.719669)
		(end 163 96.4)
		(width 0.15)
		(layer "F.Cu")
		(net 130)
	)
	(segment
		(start 163.9 98.625)
		(end 163.875 98.6)
		(width 0.15)
		(layer "F.Cu")
		(net 131)
	)
	(segment
		(start 164 96.2625)
		(end 162.9625 95.225)
		(width 0.15)
		(layer "F.Cu")
		(net 131)
	)
	(segment
		(start 164 96.684314)
		(end 164 96.2625)
		(width 0.15)
		(layer "F.Cu")
		(net 131)
	)
	(segment
		(start 162.9625 95.225)
		(end 162.9625 94.25)
		(width 0.15)
		(layer "F.Cu")
		(net 131)
	)
	(segment
		(start 163.875 96.809314)
		(end 164 96.684314)
		(width 0.15)
		(layer "F.Cu")
		(net 131)
	)
	(segment
		(start 163.875 98.6)
		(end 163.875 96.809314)
		(width 0.15)
		(layer "F.Cu")
		(net 131)
	)
	(segment
		(start 163.6 95.2)
		(end 163.6 94.25)
		(width 0.15)
		(layer "F.Cu")
		(net 132)
	)
	(segment
		(start 164.4 96)
		(end 163.6 95.2)
		(width 0.15)
		(layer "F.Cu")
		(net 132)
	)
	(segment
		(start 164.4 96.4)
		(end 164.4 96)
		(width 0.15)
		(layer "F.Cu")
		(net 132)
	)
	(via
		(at 164.4 96.4)
		(size 0.4)
		(drill 0.2)
		(layers "F.Cu" "B.Cu")
		(net 132)
	)
	(segment
		(start 164.65 96.819669)
		(end 164.65 98.625)
		(width 0.15)
		(layer "B.Cu")
		(net 132)
	)
	(segment
		(start 164.4 96.4)
		(end 164.4 96.569669)
		(width 0.15)
		(layer "B.Cu")
		(net 132)
	)
	(segment
		(start 164.4 96.569669)
		(end 164.65 96.819669)
		(width 0.15)
		(layer "B.Cu")
		(net 132)
	)
	(segment
		(start 155.9 98.625)
		(end 155.925 98.6)
		(width 0.15)
		(layer "F.Cu")
		(net 133)
	)
	(segment
		(start 154.8125 95.116054)
		(end 154.8125 94.25)
		(width 0.15)
		(layer "F.Cu")
		(net 133)
	)
	(segment
		(start 155.925 98.6)
		(end 155.925 96.725)
		(width 0.15)
		(layer "F.Cu")
		(net 133)
	)
	(segment
		(start 155.925 96.725)
		(end 155.6 96.4)
		(width 0.15)
		(layer "F.Cu")
		(net 133)
	)
	(segment
		(start 155.6 95.903554)
		(end 154.8125 95.116054)
		(width 0.15)
		(layer "F.Cu")
		(net 133)
	)
	(segment
		(start 155.6 96.4)
		(end 155.6 95.903554)
		(width 0.15)
		(layer "F.Cu")
		(net 133)
	)
	(segment
		(start 156.1 96.2)
		(end 156.1 96.05)
		(width 0.15)
		(layer "F.Cu")
		(net 134)
	)
	(segment
		(start 156.1 96.05)
		(end 155.45 95.4)
		(width 0.15)
		(layer "F.Cu")
		(net 134)
	)
	(segment
		(start 155.45 95.4)
		(end 155.45 94.25)
		(width 0.15)
		(layer "F.Cu")
		(net 134)
	)
	(via
		(at 156.1 96.2)
		(size 0.4)
		(drill 0.2)
		(layers "F.Cu" "B.Cu")
		(net 134)
	)
	(segment
		(start 156.15 96.25)
		(end 156.15 98.65)
		(width 0.15)
		(layer "B.Cu")
		(net 134)
	)
	(segment
		(start 156.1 96.2)
		(end 156.15 96.25)
		(width 0.15)
		(layer "B.Cu")
		(net 134)
	)
	(segment
		(start 157.1 96.2)
		(end 157.1 95.9)
		(width 0.15)
		(layer "F.Cu")
		(net 135)
	)
	(segment
		(start 156.5875 95.3875)
		(end 156.5875 94.25)
		(width 0.15)
		(layer "F.Cu")
		(net 135)
	)
	(segment
		(start 157.1 95.9)
		(end 156.5875 95.3875)
		(width 0.15)
		(layer "F.Cu")
		(net 135)
	)
	(via
		(at 157.1 96.2)
		(size 0.4)
		(drill 0.2)
		(layers "F.Cu" "B.Cu")
		(net 135)
	)
	(segment
		(start 157.15 96.25)
		(end 157.15 98.625)
		(width 0.15)
		(layer "B.Cu")
		(net 135)
	)
	(segment
		(start 157.1 96.2)
		(end 157.15 96.25)
		(width 0.15)
		(layer "B.Cu")
		(net 135)
	)
	(segment
		(start 156.9 98.625)
		(end 156.925 98.6)
		(width 0.15)
		(layer "F.Cu")
		(net 136)
	)
	(segment
		(start 155.95 95.35)
		(end 155.95 94.25)
		(width 0.15)
		(layer "F.Cu")
		(net 136)
	)
	(segment
		(start 156.925 96.725)
		(end 156.6 96.4)
		(width 0.15)
		(layer "F.Cu")
		(net 136)
	)
	(segment
		(start 156.6 96)
		(end 155.95 95.35)
		(width 0.15)
		(layer "F.Cu")
		(net 136)
	)
	(segment
		(start 156.6 96.4)
		(end 156.6 96)
		(width 0.15)
		(layer "F.Cu")
		(net 136)
	)
	(segment
		(start 156.925 98.6)
		(end 156.925 96.725)
		(width 0.15)
		(layer "F.Cu")
		(net 136)
	)
	(segment
		(start 155 96.718494)
		(end 155 96.855025)
		(width 0.1016)
		(layer "F.Cu")
		(net 137)
	)
	(segment
		(start 154.9 98.625)
		(end 154.9 97.244975)
		(width 0.1)
		(layer "F.Cu")
		(net 137)
	)
	(segment
		(start 155 97.144975)
		(end 155 96.855025)
		(width 0.1)
		(layer "F.Cu")
		(net 137)
	)
	(segment
		(start 154.806546 96.52504)
		(end 155 96.718494)
		(width 0.1016)
		(layer "F.Cu")
		(net 137)
	)
	(segment
		(start 154.9 97.244975)
		(end 155 97.144975)
		(width 0.1)
		(layer "F.Cu")
		(net 137)
	)
	(via
		(at 154.806546 96.52504)
		(size 0.4)
		(drill 0.2)
		(layers "F.Cu" "B.Cu")
		(net 137)
	)
	(segment
		(start 154.0516 95.057914)
		(end 154.601886 95.6082)
		(width 0.1016)
		(layer "B.Cu")
		(net 137)
	)
	(segment
		(start 154.45 91.27)
		(end 154.051601 91.668399)
		(width 0.1016)
		(layer "B.Cu")
		(net 137)
	)
	(segment
		(start 154.051601 91.668399)
		(end 154.0516 95.057914)
		(width 0.1016)
		(layer "B.Cu")
		(net 137)
	)
	(segment
		(start 154.601886 96.176155)
		(end 154.675144 96.249413)
		(width 0.1016)
		(layer "B.Cu")
		(net 137)
	)
	(segment
		(start 154.675144 96.249413)
		(end 154.675144 96.393638)
		(width 0.1016)
		(layer "B.Cu")
		(net 137)
	)
	(segment
		(start 154.601886 95.6082)
		(end 154.601886 96.176155)
		(width 0.1016)
		(layer "B.Cu")
		(net 137)
	)
	(segment
		(start 154.675144 96.393638)
		(end 154.806546 96.52504)
		(width 0.1016)
		(layer "B.Cu")
		(net 137)
	)
	(segment
		(start 154.3 97.144975)
		(end 154.3 96.855025)
		(width 0.1)
		(layer "F.Cu")
		(net 138)
	)
	(segment
		(start 154.4 98.625)
		(end 154.4 97.244975)
		(width 0.1)
		(layer "F.Cu")
		(net 138)
	)
	(segment
		(start 154.3 96.419064)
		(end 154.3 96.855025)
		(width 0.1016)
		(layer "F.Cu")
		(net 138)
	)
	(segment
		(start 154.4 97.244975)
		(end 154.3 97.144975)
		(width 0.1)
		(layer "F.Cu")
		(net 138)
	)
	(segment
		(start 154.324344 96.39472)
		(end 154.3 96.419064)
		(width 0.1016)
		(layer "F.Cu")
		(net 138)
	)
	(via
		(at 154.324344 96.39472)
		(size 0.4)
		(drill 0.2)
		(layers "F.Cu" "B.Cu")
		(net 138)
	)
	(segment
		(start 153.45 91.27)
		(end 153.848399 91.668399)
		(width 0.1016)
		(layer "B.Cu")
		(net 138)
	)
	(segment
		(start 154.398684 96.32038)
		(end 154.324344 96.39472)
		(width 0.1016)
		(layer "B.Cu")
		(net 138)
	)
	(segment
		(start 153.8484 95.142086)
		(end 154.398684 95.69237)
		(width 0.1016)
		(layer "B.Cu")
		(net 138)
	)
	(segment
		(start 154.398684 95.69237)
		(end 154.398684 96.32038)
		(width 0.1016)
		(layer "B.Cu")
		(net 138)
	)
	(segment
		(start 153.848399 91.668399)
		(end 153.8484 95.142086)
		(width 0.1016)
		(layer "B.Cu")
		(net 138)
	)
	(segment
		(start 106.85 84.35)
		(end 117.4 73.8)
		(width 0.15)
		(layer "F.Cu")
		(net 139)
	)
	(segment
		(start 106.805025 84.35)
		(end 106.85 84.35)
		(width 0.15)
		(layer "F.Cu")
		(net 139)
	)
	(segment
		(start 105.125 92.7)
		(end 105.125 86.030025)
		(width 0.15)
		(layer "F.Cu")
		(net 139)
	)
	(segment
		(start 105.125 93.35)
		(end 105.125 92.7)
		(width 0.15)
		(layer "F.Cu")
		(net 139)
	)
	(segment
		(start 105.125 86.030025)
		(end 106.805025 84.35)
		(width 0.15)
		(layer "F.Cu")
		(net 139)
	)
	(segment
		(start 127.242022 73.8)
		(end 127.4 73.642022)
		(width 0.15)
		(layer "F.Cu")
		(net 139)
	)
	(segment
		(start 129.525 74.125)
		(end 129.525 74.544975)
		(width 0.09)
		(layer "F.Cu")
		(net 139)
	)
	(segment
		(start 127.4 73.642022)
		(end 129.042022 73.642022)
		(width 0.15)
		(layer "F.Cu")
		(net 139)
	)
	(segment
		(start 129.730025 74.75)
		(end 130.125 74.75)
		(width 0.09)
		(layer "F.Cu")
		(net 139)
	)
	(segment
		(start 130.125 74.75)
		(end 130.575 75.2)
		(width 0.09)
		(layer "F.Cu")
		(net 139)
	)
	(segment
		(start 129.042022 73.642022)
		(end 129.425 74.025)
		(width 0.15)
		(layer "F.Cu")
		(net 139)
	)
	(segment
		(start 117.4 73.8)
		(end 127.242022 73.8)
		(width 0.15)
		(layer "F.Cu")
		(net 139)
	)
	(segment
		(start 129.525 74.544975)
		(end 129.730025 74.75)
		(width 0.09)
		(layer "F.Cu")
		(net 139)
	)
	(segment
		(start 129.425 74.025)
		(end 129.525 74.125)
		(width 0.09)
		(layer "F.Cu")
		(net 139)
	)
	(via
		(at 105.125 92.7)
		(size 0.4)
		(drill 0.2)
		(layers "F.Cu" "B.Cu")
		(net 139)
	)
	(via
		(at 109.533711 96.533546)
		(size 0.4)
		(drill 0.2)
		(layers "F.Cu" "B.Cu")
		(net 139)
	)
	(segment
		(start 109.675 96.674835)
		(end 109.533711 96.533546)
		(width 0.15)
		(layer "B.Cu")
		(net 139)
	)
	(segment
		(start 105.125 93.35)
		(end 105.125 92.7)
		(width 0.15)
		(layer "B.Cu")
		(net 139)
	)
	(segment
		(start 109.675 98.625)
		(end 109.675 96.674835)
		(width 0.15)
		(layer "B.Cu")
		(net 139)
	)
	(segment
		(start 108.510308 95.5)
		(end 107.475 95.5)
		(width 0.15)
		(layer "In3.Cu")
		(net 139)
	)
	(segment
		(start 105.125 93.15)
		(end 105.125 92.7)
		(width 0.15)
		(layer "In3.Cu")
		(net 139)
	)
	(segment
		(start 107.475 95.5)
		(end 105.125 93.15)
		(width 0.15)
		(layer "In3.Cu")
		(net 139)
	)
	(segment
		(start 109.533711 96.523403)
		(end 108.510308 95.5)
		(width 0.15)
		(layer "In3.Cu")
		(net 139)
	)
	(segment
		(start 109.533711 96.533546)
		(end 109.533711 96.523403)
		(width 0.15)
		(layer "In3.Cu")
		(net 139)
	)
	(segment
		(start 153.85 95.6)
		(end 153.1 94.85)
		(width 0.15)
		(layer "F.Cu")
		(net 140)
	)
	(segment
		(start 153.1 94.85)
		(end 153.1 94.25)
		(width 0.15)
		(layer "F.Cu")
		(net 140)
	)
	(segment
		(start 153.85 96.2)
		(end 153.85 95.6)
		(width 0.15)
		(layer "F.Cu")
		(net 140)
	)
	(via
		(at 153.85 96.2)
		(size 0.4)
		(drill 0.2)
		(layers "F.Cu" "B.Cu")
		(net 140)
	)
	(segment
		(start 153.85 96.2)
		(end 153.85 96.45)
		(width 0.15)
		(layer "B.Cu")
		(net 140)
	)
	(segment
		(start 154.175 96.775)
		(end 154.175 98.6)
		(width 0.15)
		(layer "B.Cu")
		(net 140)
	)
	(segment
		(start 154.175 98.6)
		(end 154.15 98.625)
		(width 0.15)
		(layer "B.Cu")
		(net 140)
	)
	(segment
		(start 153.85 96.45)
		(end 154.175 96.775)
		(width 0.15)
		(layer "B.Cu")
		(net 140)
	)
	(segment
		(start 153.031992 96.081992)
		(end 151.9625 95.0125)
		(width 0.15)
		(layer "F.Cu")
		(net 141)
	)
	(segment
		(start 153.031992 96.54668)
		(end 153.031992 96.081992)
		(width 0.15)
		(layer "F.Cu")
		(net 141)
	)
	(segment
		(start 151.9625 95.0125)
		(end 151.9625 94.25)
		(width 0.15)
		(layer "F.Cu")
		(net 141)
	)
	(via
		(at 153.031992 96.54668)
		(size 0.4)
		(drill 0.2)
		(layers "F.Cu" "B.Cu")
		(net 141)
	)
	(segment
		(start 153.175 98.6)
		(end 153.175 96.689688)
		(width 0.15)
		(layer "B.Cu")
		(net 141)
	)
	(segment
		(start 153.175 96.689688)
		(end 153.031992 96.54668)
		(width 0.15)
		(layer "B.Cu")
		(net 141)
	)
	(segment
		(start 153.15 98.625)
		(end 153.175 98.6)
		(width 0.15)
		(layer "B.Cu")
		(net 141)
	)
	(segment
		(start 153.375 98.6)
		(end 153.375 96.809314)
		(width 0.15)
		(layer "F.Cu")
		(net 142)
	)
	(segment
		(start 152.4625 95.0125)
		(end 152.4625 94.25)
		(width 0.15)
		(layer "F.Cu")
		(net 142)
	)
	(segment
		(start 153.375 96.809314)
		(end 153.45 96.734314)
		(width 0.15)
		(layer "F.Cu")
		(net 142)
	)
	(segment
		(start 153.45 96)
		(end 152.4625 95.0125)
		(width 0.15)
		(layer "F.Cu")
		(net 142)
	)
	(segment
		(start 153.45 96.734314)
		(end 153.45 96)
		(width 0.15)
		(layer "F.Cu")
		(net 142)
	)
	(segment
		(start 153.4 98.625)
		(end 153.375 98.6)
		(width 0.15)
		(layer "F.Cu")
		(net 142)
	)
	(segment
		(start 152.55 96.1)
		(end 151.325 94.875)
		(width 0.15)
		(layer "F.Cu")
		(net 143)
	)
	(segment
		(start 151.325 94.875)
		(end 151.325 94.25)
		(width 0.15)
		(layer "F.Cu")
		(net 143)
	)
	(segment
		(start 152.55 96.669669)
		(end 152.55 96.1)
		(width 0.15)
		(layer "F.Cu")
		(net 143)
	)
	(segment
		(start 152.4 96.819669)
		(end 152.55 96.669669)
		(width 0.15)
		(layer "F.Cu")
		(net 143)
	)
	(segment
		(start 152.4 98.625)
		(end 152.4 96.819669)
		(width 0.15)
		(layer "F.Cu")
		(net 143)
	)
	(segment
		(start 143.9 96.833812)
		(end 143.9 98.625)
		(width 0.15)
		(layer "F.Cu")
		(net 144)
	)
	(segment
		(start 144.45 96.34)
		(end 144.393812 96.34)
		(width 0.15)
		(layer "F.Cu")
		(net 144)
	)
	(segment
		(start 144.393812 96.34)
		(end 143.9 96.833812)
		(width 0.15)
		(layer "F.Cu")
		(net 144)
	)
	(via
		(at 144.45 96.34)
		(size 0.4)
		(drill 0.2)
		(layers "F.Cu" "B.Cu")
		(net 144)
	)
	(segment
		(start 144.45 96.34)
		(end 144.45 94.25)
		(width 0.15)
		(layer "B.Cu")
		(net 144)
	)
	(segment
		(start 143.65 95.15)
		(end 143.95 94.85)
		(width 0.15)
		(layer "B.Cu")
		(net 145)
	)
	(segment
		(start 143.95 94.85)
		(end 143.95 94.25)
		(width 0.15)
		(layer "B.Cu")
		(net 145)
	)
	(segment
		(start 143.65 98.625)
		(end 143.65 95.15)
		(width 0.15)
		(layer "B.Cu")
		(net 145)
	)
	(segment
		(start 143.3125 94.8375)
		(end 143.3125 94.25)
		(width 0.15)
		(layer "B.Cu")
		(net 146)
	)
	(segment
		(start 143.15 95)
		(end 143.3125 94.8375)
		(width 0.15)
		(layer "B.Cu")
		(net 146)
	)
	(segment
		(start 143.15 98.625)
		(end 143.15 95)
		(width 0.15)
		(layer "B.Cu")
		(net 146)
	)
	(segment
		(start 142.9 96.88)
		(end 144.83 94.95)
		(width 0.15)
		(layer "F.Cu")
		(net 147)
	)
	(segment
		(start 144.83 94.95)
		(end 145.05 94.95)
		(width 0.15)
		(layer "F.Cu")
		(net 147)
	)
	(segment
		(start 142.9 98.625)
		(end 142.9 96.88)
		(width 0.15)
		(layer "F.Cu")
		(net 147)
	)
	(via
		(at 145.05 94.95)
		(size 0.4)
		(drill 0.2)
		(layers "F.Cu" "B.Cu")
		(net 147)
	)
	(segment
		(start 145.05 94.2875)
		(end 145.0875 94.25)
		(width 0.15)
		(layer "B.Cu")
		(net 147)
	)
	(segment
		(start 145.05 94.95)
		(end 145.05 94.2875)
		(width 0.15)
		(layer "B.Cu")
		(net 147)
	)
	(segment
		(start 142.4875 94.9625)
		(end 142.4875 94.25)
		(width 0.15)
		(layer "B.Cu")
		(net 148)
	)
	(segment
		(start 142.15 98.625)
		(end 142.15 95.3)
		(width 0.15)
		(layer "B.Cu")
		(net 148)
	)
	(segment
		(start 142.15 95.3)
		(end 142.4875 94.9625)
		(width 0.15)
		(layer "B.Cu")
		(net 148)
	)
	(segment
		(start 141.9 94.9)
		(end 141.9 98.625)
		(width 0.15)
		(layer "F.Cu")
		(net 149)
	)
	(segment
		(start 141.85 94.85)
		(end 141.9 94.9)
		(width 0.15)
		(layer "F.Cu")
		(net 149)
	)
	(via
		(at 141.85 94.85)
		(size 0.4)
		(drill 0.2)
		(layers "F.Cu" "B.Cu")
		(net 149)
	)
	(segment
		(start 141.85 94.25)
		(end 141.85 94.85)
		(width 0.15)
		(layer "B.Cu")
		(net 149)
	)
	(segment
		(start 141.65 98.625)
		(end 141.65 95.3)
		(width 0.15)
		(layer "B.Cu")
		(net 150)
	)
	(segment
		(start 141.35 95)
		(end 141.35 94.25)
		(width 0.15)
		(layer "B.Cu")
		(net 150)
	)
	(segment
		(start 141.65 95.3)
		(end 141.35 95)
		(width 0.15)
		(layer "B.Cu")
		(net 150)
	)
	(segment
		(start 141.2755 95.489812)
		(end 141.4 95.614312)
		(width 0.15)
		(layer "F.Cu")
		(net 151)
	)
	(segment
		(start 141.4 95.614312)
		(end 141.4 98.625)
		(width 0.15)
		(layer "F.Cu")
		(net 151)
	)
	(via
		(at 141.2755 95.489812)
		(size 0.4)
		(drill 0.2)
		(layers "F.Cu" "B.Cu")
		(net 151)
	)
	(segment
		(start 140.7125 94.926812)
		(end 141.2755 95.489812)
		(width 0.15)
		(layer "B.Cu")
		(net 151)
	)
	(segment
		(start 140.7125 94.25)
		(end 140.7125 94.926812)
		(width 0.15)
		(layer "B.Cu")
		(net 151)
	)
	(segment
		(start 139.75 95.15)
		(end 139.75 94.335)
		(width 0.15)
		(layer "F.Cu")
		(net 152)
	)
	(via
		(at 139.75 95.15)
		(size 0.4)
		(drill 0.2)
		(layers "F.Cu" "B.Cu")
		(net 152)
	)
	(segment
		(start 140.65 98.625)
		(end 140.65 96.05)
		(width 0.15)
		(layer "B.Cu")
		(net 152)
	)
	(segment
		(start 140.65 96.05)
		(end 139.75 95.15)
		(width 0.15)
		(layer "B.Cu")
		(net 152)
	)
	(segment
		(start 137.2508 94.7342)
		(end 137.65 94.335)
		(width 0.1016)
		(layer "F.Cu")
		(net 153)
	)
	(segment
		(start 137.2516 95.992086)
		(end 137.2516 96.714099)
		(width 0.1016)
		(layer "F.Cu")
		(net 153)
	)
	(segment
		(start 137.2516 95.992086)
		(end 137.2508 95.991286)
		(width 0.1016)
		(layer "F.Cu")
		(net 153)
	)
	(segment
		(start 137.2508 95.991286)
		(end 137.2508 94.7342)
		(width 0.1016)
		(layer "F.Cu")
		(net 153)
	)
	(segment
		(start 137.4 96.862499)
		(end 137.4 98.625)
		(width 0.1016)
		(layer "F.Cu")
		(net 153)
	)
	(segment
		(start 137.2516 96.714099)
		(end 137.4 96.862499)
		(width 0.1016)
		(layer "F.Cu")
		(net 153)
	)
	(segment
		(start 137.0484 96.714099)
		(end 136.9 96.862499)
		(width 0.1016)
		(layer "F.Cu")
		(net 154)
	)
	(segment
		(start 137.0492 95.907114)
		(end 137.0492 94.7342)
		(width 0.1016)
		(layer "F.Cu")
		(net 154)
	)
	(segment
		(start 136.9 96.862499)
		(end 136.9 98.625)
		(width 0.1016)
		(layer "F.Cu")
		(net 154)
	)
	(segment
		(start 137.0484 95.907914)
		(end 137.0492 95.907114)
		(width 0.1016)
		(layer "F.Cu")
		(net 154)
	)
	(segment
		(start 137.0492 94.7342)
		(end 136.65 94.335)
		(width 0.1016)
		(layer "F.Cu")
		(net 154)
	)
	(segment
		(start 137.0484 95.907914)
		(end 137.0484 96.714099)
		(width 0.1016)
		(layer "F.Cu")
		(net 154)
	)
	(segment
		(start 136.45 95.64)
		(end 135.95 95.64)
		(width 0.1)
		(layer "F.Cu")
		(net 155)
	)
	(segment
		(start 135.9 96.862499)
		(end 135.9 98.625)
		(width 0.1)
		(layer "F.Cu")
		(net 155)
	)
	(segment
		(start 134.65 93.64)
		(end 135.55 93.64)
		(width 0.1)
		(layer "F.Cu")
		(net 155)
	)
	(segment
		(start 136.25 92.74)
		(end 136.25 92.94)
		(width 0.1)
		(layer "F.Cu")
		(net 155)
	)
	(segment
		(start 135.9 94.44)
		(end 135.75 94.44)
		(width 0.1)
		(layer "F.Cu")
		(net 155)
	)
	(segment
		(start 135.75 95.84)
		(end 135.75 96.712499)
		(width 0.1)
		(layer "F.Cu")
		(net 155)
	)
	(segment
		(start 135.95 93.24)
		(end 135.85 93.24)
		(width 0.1)
		(layer "F.Cu")
		(net 155)
	)
	(segment
		(start 135.75 94.44)
		(end 134.65 94.44)
		(width 0.1)
		(layer "F.Cu")
		(net 155)
	)
	(segment
		(start 135.85 93.24)
		(end 134.65 93.24)
		(width 0.1)
		(layer "F.Cu")
		(net 155)
	)
	(segment
		(start 135.75 92.235)
		(end 135.75 92.34)
		(width 0.1)
		(layer "F.Cu")
		(net 155)
	)
	(segment
		(start 135.55 94.84)
		(end 136.45 94.84)
		(width 0.1)
		(layer "F.Cu")
		(net 155)
	)
	(segment
		(start 135.85 92.44)
		(end 135.95 92.44)
		(width 0.1)
		(layer "F.Cu")
		(net 155)
	)
	(segment
		(start 136.15 93.89)
		(end 136.15 94.19)
		(width 0.1)
		(layer "F.Cu")
		(net 155)
	)
	(segment
		(start 134.65 94.84)
		(end 135.55 94.84)
		(width 0.1)
		(layer "F.Cu")
		(net 155)
	)
	(segment
		(start 135.75 96.712499)
		(end 135.9 96.862499)
		(width 0.1)
		(layer "F.Cu")
		(net 155)
	)
	(segment
		(start 136.15 91.835)
		(end 135.75 92.235)
		(width 0.1)
		(layer "F.Cu")
		(net 155)
	)
	(segment
		(start 135.55 93.64)
		(end 135.9 93.64)
		(width 0.1)
		(layer "F.Cu")
		(net 155)
	)
	(arc
		(start 134.45 93.44)
		(mid 134.508579 93.581421)
		(end 134.65 93.64)
		(width 0.1)
		(layer "F.Cu")
		(net 155)
	)
	(arc
		(start 134.65 93.24)
		(mid 134.508579 93.298579)
		(end 134.45 93.44)
		(width 0.1)
		(layer "F.Cu")
		(net 155)
	)
	(arc
		(start 136.85 95.24)
		(mid 136.732843 95.522843)
		(end 136.45 95.64)
		(width 0.1)
		(layer "F.Cu")
		(net 155)
	)
	(arc
		(start 136.45 94.84)
		(mid 136.732843 94.957157)
		(end 136.85 95.24)
		(width 0.1)
		(layer "F.Cu")
		(net 155)
	)
	(arc
		(start 135.95 95.64)
		(mid 135.808579 95.698579)
		(end 135.75 95.84)
		(width 0.1)
		(layer "F.Cu")
		(net 155)
	)
	(arc
		(start 134.65 94.44)
		(mid 134.508579 94.498579)
		(end 134.45 94.64)
		(width 0.1)
		(layer "F.Cu")
		(net 155)
	)
	(arc
		(start 136.15 94.19)
		(mid 136.076777 94.366777)
		(end 135.9 94.44)
		(width 0.1)
		(layer "F.Cu")
		(net 155)
	)
	(arc
		(start 136.25 92.94)
		(mid 136.162132 93.152132)
		(end 135.95 93.24)
		(width 0.1)
		(layer "F.Cu")
		(net 155)
	)
	(arc
		(start 134.45 94.64)
		(mid 134.508579 94.781421)
		(end 134.65 94.84)
		(width 0.1)
		(layer "F.Cu")
		(net 155)
	)
	(arc
		(start 135.95 92.44)
		(mid 136.162132 92.527868)
		(end 136.25 92.74)
		(width 0.1)
		(layer "F.Cu")
		(net 155)
	)
	(arc
		(start 135.75 92.34)
		(mid 135.779289 92.410711)
		(end 135.85 92.44)
		(width 0.1)
		(layer "F.Cu")
		(net 155)
	)
	(arc
		(start 135.9 93.64)
		(mid 136.076777 93.713223)
		(end 136.15 93.89)
		(width 0.1)
		(layer "F.Cu")
		(net 155)
	)
	(segment
		(start 135.55 96.712499)
		(end 135.4 96.862499)
		(width 0.1)
		(layer "F.Cu")
		(net 156)
	)
	(segment
		(start 135.55 92.235)
		(end 135.55 92.34)
		(width 0.1)
		(layer "F.Cu")
		(net 156)
	)
	(segment
		(start 135.15 91.835)
		(end 135.55 92.235)
		(width 0.1)
		(layer "F.Cu")
		(net 156)
	)
	(segment
		(start 135.85 93.04)
		(end 134.65 93.04)
		(width 0.1)
		(layer "F.Cu")
		(net 156)
	)
	(segment
		(start 135.9 94.24)
		(end 135.75 94.24)
		(width 0.1)
		(layer "F.Cu")
		(net 156)
	)
	(segment
		(start 136.05 92.74)
		(end 136.05 92.94)
		(width 0.1)
		(layer "F.Cu")
		(net 156)
	)
	(segment
		(start 135.55 93.84)
		(end 135.9 93.84)
		(width 0.1)
		(layer "F.Cu")
		(net 156)
	)
	(segment
		(start 135.55 95.84)
		(end 135.55 96.712499)
		(width 0.1)
		(layer "F.Cu")
		(net 156)
	)
	(segment
		(start 136.45 95.44)
		(end 135.95 95.44)
		(width 0.1)
		(layer "F.Cu")
		(net 156)
	)
	(segment
		(start 135.95 93.89)
		(end 135.95 94.19)
		(width 0.1)
		(layer "F.Cu")
		(net 156)
	)
	(segment
		(start 135.95 93.04)
		(end 135.85 93.04)
		(width 0.1)
		(layer "F.Cu")
		(net 156)
	)
	(segment
		(start 135.4 96.862499)
		(end 135.4 98.625)
		(width 0.1)
		(layer "F.Cu")
		(net 156)
	)
	(segment
		(start 135.75 94.24)
		(end 134.65 94.24)
		(width 0.1)
		(layer "F.Cu")
		(net 156)
	)
	(segment
		(start 134.65 93.84)
		(end 135.55 93.84)
		(width 0.1)
		(layer "F.Cu")
		(net 156)
	)
	(segment
		(start 135.55 95.04)
		(end 136.45 95.04)
		(width 0.1)
		(layer "F.Cu")
		(net 156)
	)
	(segment
		(start 135.85 92.64)
		(end 135.95 92.64)
		(width 0.1)
		(layer "F.Cu")
		(net 156)
	)
	(segment
		(start 134.65 95.04)
		(end 135.55 95.04)
		(width 0.1)
		(layer "F.Cu")
		(net 156)
	)
	(arc
		(start 134.65 93.04)
		(mid 134.367157 93.157157)
		(end 134.25 93.44)
		(width 0.1)
		(layer "F.Cu")
		(net 156)
	)
	(arc
		(start 135.95 94.19)
		(mid 135.935355 94.225355)
		(end 135.9 94.24)
		(width 0.1)
		(layer "F.Cu")
		(net 156)
	)
	(arc
		(start 135.55 92.34)
		(mid 135.637868 92.552132)
		(end 135.85 92.64)
		(width 0.1)
		(layer "F.Cu")
		(net 156)
	)
	(arc
		(start 134.25 94.64)
		(mid 134.367157 94.922843)
		(end 134.65 95.04)
		(width 0.1)
		(layer "F.Cu")
		(net 156)
	)
	(arc
		(start 136.05 92.94)
		(mid 136.020711 93.010711)
		(end 135.95 93.04)
		(width 0.1)
		(layer "F.Cu")
		(net 156)
	)
	(arc
		(start 135.95 92.64)
		(mid 136.020711 92.669289)
		(end 136.05 92.74)
		(width 0.1)
		(layer "F.Cu")
		(net 156)
	)
	(arc
		(start 134.25 93.44)
		(mid 134.367157 93.722843)
		(end 134.65 93.84)
		(width 0.1)
		(layer "F.Cu")
		(net 156)
	)
	(arc
		(start 135.95 95.44)
		(mid 135.667157 95.557157)
		(end 135.55 95.84)
		(width 0.1)
		(layer "F.Cu")
		(net 156)
	)
	(arc
		(start 134.65 94.24)
		(mid 134.367157 94.357157)
		(end 134.25 94.64)
		(width 0.1)
		(layer "F.Cu")
		(net 156)
	)
	(arc
		(start 135.9 93.84)
		(mid 135.935355 93.854645)
		(end 135.95 93.89)
		(width 0.1)
		(layer "F.Cu")
		(net 156)
	)
	(arc
		(start 136.65 95.24)
		(mid 136.591421 95.381421)
		(end 136.45 95.44)
		(width 0.1)
		(layer "F.Cu")
		(net 156)
	)
	(arc
		(start 136.45 95.04)
		(mid 136.591421 95.098579)
		(end 136.65 95.24)
		(width 0.1)
		(layer "F.Cu")
		(net 156)
	)
	(segment
		(start 130.9 98.625)
		(end 130.9 96.7)
		(width 0.15)
		(layer "F.Cu")
		(net 157)
	)
	(segment
		(start 132 95.6)
		(end 132 94.285)
		(width 0.15)
		(layer "F.Cu")
		(net 157)
	)
	(segment
		(start 130.9 96.7)
		(end 132 95.6)
		(width 0.15)
		(layer "F.Cu")
		(net 157)
	)
	(segment
		(start 131.1 95.8)
		(end 131.1 94.25)
		(width 0.15)
		(layer "F.Cu")
		(net 158)
	)
	(via
		(at 131.1 95.8)
		(size 0.4)
		(drill 0.2)
		(layers "F.Cu" "B.Cu")
		(net 158)
	)
	(segment
		(start 130.15 96.75)
		(end 131.1 95.8)
		(width 0.15)
		(layer "B.Cu")
		(net 158)
	)
	(segment
		(start 130.15 98.625)
		(end 130.15 96.75)
		(width 0.15)
		(layer "B.Cu")
		(net 158)
	)
	(segment
		(start 130.57 95.83)
		(end 130.57 94.25)
		(width 0.15)
		(layer "F.Cu")
		(net 159)
	)
	(segment
		(start 129.9 96.5)
		(end 130.57 95.83)
		(width 0.15)
		(layer "F.Cu")
		(net 159)
	)
	(segment
		(start 129.9 98.625)
		(end 129.9 96.5)
		(width 0.15)
		(layer "F.Cu")
		(net 159)
	)
	(segment
		(start 130 95.8)
		(end 130 94.278)
		(width 0.15)
		(layer "F.Cu")
		(net 160)
	)
	(segment
		(start 130 94.278)
		(end 130.028 94.25)
		(width 0.15)
		(layer "F.Cu")
		(net 160)
	)
	(via
		(at 130 95.8)
		(size 0.4)
		(drill 0.2)
		(layers "F.Cu" "B.Cu")
		(net 160)
	)
	(segment
		(start 129.65 96.15)
		(end 130 95.8)
		(width 0.15)
		(layer "B.Cu")
		(net 160)
	)
	(segment
		(start 129.65 98.625)
		(end 129.65 96.15)
		(width 0.15)
		(layer "B.Cu")
		(net 160)
	)
	(segment
		(start 129.4 98.625)
		(end 129.4 94.348)
		(width 0.15)
		(layer "F.Cu")
		(net 161)
	)
	(segment
		(start 129.4 94.348)
		(end 129.498 94.25)
		(width 0.15)
		(layer "F.Cu")
		(net 161)
	)
	(segment
		(start 127.45 95.75)
		(end 127.45 94.25)
		(width 0.15)
		(layer "F.Cu")
		(net 162)
	)
	(segment
		(start 127.5 95.8)
		(end 127.45 95.75)
		(width 0.15)
		(layer "F.Cu")
		(net 162)
	)
	(via
		(at 127.5 95.8)
		(size 0.4)
		(drill 0.2)
		(layers "F.Cu" "B.Cu")
		(net 162)
	)
	(segment
		(start 127.5 95.81)
		(end 127.5 95.8)
		(width 0.15)
		(layer "B.Cu")
		(net 162)
	)
	(segment
		(start 128.65 96.96)
		(end 127.5 95.81)
		(width 0.15)
		(layer "B.Cu")
		(net 162)
	)
	(segment
		(start 128.65 98.625)
		(end 128.65 96.96)
		(width 0.15)
		(layer "B.Cu")
		(net 162)
	)
	(segment
		(start 128.4 95.9)
		(end 128.6 95.7)
		(width 0.15)
		(layer "F.Cu")
		(net 163)
	)
	(segment
		(start 128.6 94.2625)
		(end 128.5875 94.25)
		(width 0.15)
		(layer "F.Cu")
		(net 163)
	)
	(segment
		(start 128.4 98.625)
		(end 128.4 95.9)
		(width 0.15)
		(layer "F.Cu")
		(net 163)
	)
	(segment
		(start 128.6 95.7)
		(end 128.6 94.2625)
		(width 0.15)
		(layer "F.Cu")
		(net 163)
	)
	(segment
		(start 127.9 98.625)
		(end 127.95 98.575)
		(width 0.15)
		(layer "F.Cu")
		(net 164)
	)
	(segment
		(start 127.95 98.575)
		(end 127.95 94.25)
		(width 0.15)
		(layer "F.Cu")
		(net 164)
	)
	(segment
		(start 127 96.1)
		(end 126.85 95.95)
		(width 0.15)
		(layer "F.Cu")
		(net 165)
	)
	(segment
		(start 126.85 95.95)
		(end 126.85 94.2875)
		(width 0.15)
		(layer "F.Cu")
		(net 165)
	)
	(segment
		(start 126.85 94.2875)
		(end 126.8125 94.25)
		(width 0.15)
		(layer "F.Cu")
		(net 165)
	)
	(via
		(at 127 96.1)
		(size 0.4)
		(drill 0.2)
		(layers "F.Cu" "B.Cu")
		(net 165)
	)
	(segment
		(start 127 96.1)
		(end 127.65 96.75)
		(width 0.15)
		(layer "B.Cu")
		(net 165)
	)
	(segment
		(start 127.65 96.75)
		(end 127.65 98.625)
		(width 0.15)
		(layer "B.Cu")
		(net 165)
	)
	(segment
		(start 118.925 96.2)
		(end 120.25 94.875)
		(width 0.15)
		(layer "F.Cu")
		(net 166)
	)
	(segment
		(start 120.25 94.875)
		(end 120.25 94.25)
		(width 0.15)
		(layer "F.Cu")
		(net 166)
	)
	(segment
		(start 118.925 96.5)
		(end 118.925 96.2)
		(width 0.15)
		(layer "F.Cu")
		(net 166)
	)
	(via
		(at 118.92712 96.491944)
		(size 0.4)
		(drill 0.2)
		(layers "F.Cu" "B.Cu")
		(net 166)
	)
	(segment
		(start 119.175 98.625)
		(end 119.175 96.75)
		(width 0.15)
		(layer "B.Cu")
		(net 166)
	)
	(segment
		(start 119.175 96.75)
		(end 118.92712 96.50212)
		(width 0.15)
		(layer "B.Cu")
		(net 166)
	)
	(segment
		(start 118.92712 96.50212)
		(end 118.92712 96.491944)
		(width 0.15)
		(layer "B.Cu")
		(net 166)
	)
	(segment
		(start 118.525 96.719669)
		(end 118.525 96.1)
		(width 0.15)
		(layer "F.Cu")
		(net 167)
	)
	(segment
		(start 118.525 96.1)
		(end 119.6125 95.0125)
		(width 0.15)
		(layer "F.Cu")
		(net 167)
	)
	(segment
		(start 118.425 96.819669)
		(end 118.525 96.719669)
		(width 0.15)
		(layer "F.Cu")
		(net 167)
	)
	(segment
		(start 118.425 98.625)
		(end 118.425 96.819669)
		(width 0.15)
		(layer "F.Cu")
		(net 167)
	)
	(segment
		(start 119.6125 95.0125)
		(end 119.6125 94.25)
		(width 0.15)
		(layer "F.Cu")
		(net 167)
	)
	(segment
		(start 119.1125 95.0125)
		(end 119.1125 94.25)
		(width 0.15)
		(layer "F.Cu")
		(net 168)
	)
	(segment
		(start 118.125 96)
		(end 119.1125 95.0125)
		(width 0.15)
		(layer "F.Cu")
		(net 168)
	)
	(segment
		(start 118.125 96.399915)
		(end 118.125 96)
		(width 0.15)
		(layer "F.Cu")
		(net 168)
	)
	(via
		(at 118.125 96.399915)
		(size 0.4)
		(drill 0.2)
		(layers "F.Cu" "B.Cu")
		(net 168)
	)
	(segment
		(start 118.175 98.6)
		(end 118.15 98.625)
		(width 0.15)
		(layer "B.Cu")
		(net 168)
	)
	(segment
		(start 118.175 96.449915)
		(end 118.175 98.6)
		(width 0.15)
		(layer "B.Cu")
		(net 168)
	)
	(segment
		(start 118.125 96.399915)
		(end 118.175 96.449915)
		(width 0.15)
		(layer "B.Cu")
		(net 168)
	)
	(segment
		(start 118.175 98.625)
		(end 118.2 98.6)
		(width 0.15)
		(layer "B.Cu")
		(net 168)
	)
	(segment
		(start 117.725 95.6)
		(end 117.725 96.45)
		(width 0.15)
		(layer "F.Cu")
		(net 169)
	)
	(segment
		(start 117.725 95.6)
		(end 118.475 94.85)
		(width 0.15)
		(layer "F.Cu")
		(net 169)
	)
	(segment
		(start 118.475 94.85)
		(end 118.475 94.25)
		(width 0.15)
		(layer "F.Cu")
		(net 169)
	)
	(segment
		(start 117.725 96.45)
		(end 117.4 96.775)
		(width 0.15)
		(layer "F.Cu")
		(net 169)
	)
	(segment
		(start 117.4 98.6)
		(end 117.425 98.625)
		(width 0.15)
		(layer "F.Cu")
		(net 169)
	)
	(segment
		(start 117.4 96.775)
		(end 117.4 98.6)
		(width 0.15)
		(layer "F.Cu")
		(net 169)
	)
	(segment
		(start 117.175 97.246107)
		(end 117.175 98.625)
		(width 0.1016)
		(layer "B.Cu")
		(net 170)
	)
	(segment
		(start 117.2758 97.145307)
		(end 117.175 97.246107)
		(width 0.1016)
		(layer "B.Cu")
		(net 170)
	)
	(segment
		(start 117.175 98.625)
		(end 117.175 97.244975)
		(width 0.1)
		(layer "B.Cu")
		(net 170)
	)
	(segment
		(start 117.2758 96.854693)
		(end 117.2758 97.145307)
		(width 0.1016)
		(layer "B.Cu")
		(net 170)
	)
	(segment
		(start 117.0266 95.977086)
		(end 117.0266 96.605493)
		(width 0.1016)
		(layer "B.Cu")
		(net 170)
	)
	(segment
		(start 117.0266 96.605493)
		(end 117.2758 96.854693)
		(width 0.1016)
		(layer "B.Cu")
		(net 170)
	)
	(segment
		(start 118.13 91.425)
		(end 117.731601 91.823399)
		(width 0.1016)
		(layer "B.Cu")
		(net 170)
	)
	(segment
		(start 117.731601 91.823399)
		(end 117.731601 95.272085)
		(width 0.1016)
		(layer "B.Cu")
		(net 170)
	)
	(segment
		(start 117.731601 95.272085)
		(end 117.0266 95.977086)
		(width 0.1016)
		(layer "B.Cu")
		(net 170)
	)
	(segment
		(start 116.5742 97.145307)
		(end 116.675 97.246107)
		(width 0.1016)
		(layer "B.Cu")
		(net 171)
	)
	(segment
		(start 116.8234 96.605493)
		(end 116.5742 96.854693)
		(width 0.1016)
		(layer "B.Cu")
		(net 171)
	)
	(segment
		(start 116.675 98.625)
		(end 116.675 97.244975)
		(width 0.1)
		(layer "B.Cu")
		(net 171)
	)
	(segment
		(start 117.13 91.425)
		(end 117.528399 91.823399)
		(width 0.1016)
		(layer "B.Cu")
		(net 171)
	)
	(segment
		(start 117.528399 91.823399)
		(end 117.528399 95.187915)
		(width 0.1016)
		(layer "B.Cu")
		(net 171)
	)
	(segment
		(start 116.5742 96.854693)
		(end 116.5742 97.145307)
		(width 0.1016)
		(layer "B.Cu")
		(net 171)
	)
	(segment
		(start 117.528399 95.187915)
		(end 116.8234 95.892914)
		(width 0.1016)
		(layer "B.Cu")
		(net 171)
	)
	(segment
		(start 116.8234 95.892914)
		(end 116.8234 96.605493)
		(width 0.1016)
		(layer "B.Cu")
		(net 171)
	)
	(segment
		(start 116.675 97.246107)
		(end 116.675 98.625)
		(width 0.1016)
		(layer "B.Cu")
		(net 171)
	)
	(segment
		(start 116.185782 75.872795)
		(end 116.327204 76.014218)
		(width 0.15)
		(layer "F.Cu")
		(net 172)
	)
	(segment
		(start 128.825 74.1)
		(end 128.825 74.85)
		(width 0.09)
		(layer "F.Cu")
		(net 172)
	)
	(segment
		(start 115.90294 76.438485)
		(end 115.902939 76.438484)
		(width 0.15)
		(layer "F.Cu")
		(net 172)
	)
	(segment
		(start 128.825 74.85)
		(end 129.175 75.2)
		(width 0.09)
		(layer "F.Cu")
		(net 172)
	)
	(segment
		(start 115.33725 76.721325)
		(end 115.337251 76.721326)
		(width 0.15)
		(layer "F.Cu")
		(net 172)
	)
	(segment
		(start 117.034312 75.024263)
		(end 117.034313 75.024264)
		(width 0.15)
		(layer "F.Cu")
		(net 172)
	)
	(segment
		(start 115.337251 76.721326)
		(end 115.478673 76.862749)
		(width 0.15)
		(layer "F.Cu")
		(net 172)
	)
	(segment
		(start 114.630142 77.852702)
		(end 114.347299 78.135546)
		(width 0.15)
		(layer "F.Cu")
		(net 172)
	)
	(segment
		(start 115.902939 76.438484)
		(end 115.761516 76.297062)
		(width 0.15)
		(layer "F.Cu")
		(net 172)
	)
	(segment
		(start 117.8 74.4)
		(end 117.6 74.6)
		(width 0.15)
		(layer "F.Cu")
		(net 172)
	)
	(segment
		(start 117.317157 74.599999)
		(end 117.317156 74.6)
		(width 0.15)
		(layer "F.Cu")
		(net 172)
	)
	(segment
		(start 107.585188 84.614812)
		(end 105.671902 86.528098)
		(width 0.15)
		(layer "F.Cu")
		(net 172)
	)
	(segment
		(start 115.478673 77.004171)
		(end 115.19583 77.287015)
		(width 0.15)
		(layer "F.Cu")
		(net 172)
	)
	(segment
		(start 115.054408 77.287015)
		(end 114.912985 77.145593)
		(width 0.15)
		(layer "F.Cu")
		(net 172)
	)
	(segment
		(start 116.185781 75.872794)
		(end 116.185782 75.872795)
		(width 0.15)
		(layer "F.Cu")
		(net 172)
	)
	(segment
		(start 114.771563 77.145593)
		(end 114.48872 77.428435)
		(width 0.15)
		(layer "F.Cu")
		(net 172)
	)
	(segment
		(start 114.205878 78.135547)
		(end 114.205877 78.135546)
		(width 0.15)
		(layer "F.Cu")
		(net 172)
	)
	(segment
		(start 127.617598 74.02)
		(end 127.237598 74.4)
		(width 0.15)
		(layer "F.Cu")
		(net 172)
	)
	(segment
		(start 105.625 92.746902)
		(end 105.671902 92.7)
		(width 0.15)
		(layer "F.Cu")
		(net 172)
	)
	(segment
		(start 116.751471 75.589954)
		(end 116.75147 75.589953)
		(width 0.15)
		(layer "F.Cu")
		(net 172)
	)
	(segment
		(start 115.054409 77.287016)
		(end 115.054408 77.287015)
		(width 0.15)
		(layer "F.Cu")
		(net 172)
	)
	(segment
		(start 105.625 93.35)
		(end 105.625 92.746902)
		(width 0.15)
		(layer "F.Cu")
		(net 172)
	)
	(segment
		(start 117.175735 75.307109)
		(end 116.892892 75.589953)
		(width 0.15)
		(layer "F.Cu")
		(net 172)
	)
	(segment
		(start 109.925 96.660025)
		(end 110.032867 96.552158)
		(width 0.15)
		(layer "F.Cu")
		(net 172)
	)
	(segment
		(start 127.237598 74.4)
		(end 117.8 74.4)
		(width 0.15)
		(layer "F.Cu")
		(net 172)
	)
	(segment
		(start 116.468625 75.448531)
		(end 116.185782 75.731373)
		(width 0.15)
		(layer "F.Cu")
		(net 172)
	)
	(segment
		(start 128.745 74.02)
		(end 127.617598 74.02)
		(width 0.15)
		(layer "F.Cu")
		(net 172)
	)
	(segment
		(start 117.317156 74.6)
		(end 117.034313 74.882842)
		(width 0.15)
		(layer "F.Cu")
		(net 172)
	)
	(segment
		(start 114.48872 77.569857)
		(end 114.630142 77.71128)
		(width 0.15)
		(layer "F.Cu")
		(net 172)
	)
	(segment
		(start 116.75147 75.589953)
		(end 116.610047 75.448531)
		(width 0.15)
		(layer "F.Cu")
		(net 172)
	)
	(segment
		(start 116.327204 76.15564)
		(end 116.044361 76.438484)
		(width 0.15)
		(layer "F.Cu")
		(net 172)
	)
	(segment
		(start 114.064456 78.135547)
		(end 114.064457 78.135545)
		(width 0.15)
		(layer "F.Cu")
		(net 172)
	)
	(segment
		(start 105.671902 86.528098)
		(end 105.671902 92.7)
		(width 0.15)
		(layer "F.Cu")
		(net 172)
	)
	(segment
		(start 115.620094 76.297062)
		(end 115.337251 76.579904)
		(width 0.15)
		(layer "F.Cu")
		(net 172)
	)
	(segment
		(start 117.034313 75.024264)
		(end 117.175735 75.165687)
		(width 0.15)
		(layer "F.Cu")
		(net 172)
	)
	(segment
		(start 109.925 98.625)
		(end 109.925 96.660025)
		(width 0.15)
		(layer "F.Cu")
		(net 172)
	)
	(segment
		(start 128.825 74.1)
		(end 128.745 74.02)
		(width 0.15)
		(layer "F.Cu")
		(net 172)
	)
	(segment
		(start 114.064457 78.135545)
		(end 107.814812 84.385188)
		(width 0.15)
		(layer "F.Cu")
		(net 172)
	)
	(segment
		(start 114.488719 77.569856)
		(end 114.48872 77.569857)
		(width 0.15)
		(layer "F.Cu")
		(net 172)
	)
	(segment
		(start 107.814812 84.409787)
		(end 107.609787 84.614812)
		(width 0.15)
		(layer "F.Cu")
		(net 172)
	)
	(segment
		(start 107.609787 84.614812)
		(end 107.585188 84.614812)
		(width 0.15)
		(layer "F.Cu")
		(net 172)
	)
	(segment
		(start 107.814812 84.385188)
		(end 107.814812 84.409787)
		(width 0.15)
		(layer "F.Cu")
		(net 172)
	)
	(via
		(at 105.671902 92.7)
		(size 0.4)
		(drill 0.2)
		(layers "F.Cu" "B.Cu")
		(net 172)
	)
	(via
		(at 110.032867 96.552158)
		(size 0.4)
		(drill 0.2)
		(layers "F.Cu" "B.Cu")
		(net 172)
	)
	(arc
		(start 117.175735 75.165687)
		(mid 117.205024 75.236398)
		(end 117.175735 75.307109)
		(width 0.15)
		(layer "F.Cu")
		(net 172)
	)
	(arc
		(start 114.912985 77.145593)
		(mid 114.842274 77.116304)
		(end 114.771563 77.145593)
		(width 0.15)
		(layer "F.Cu")
		(net 172)
	)
	(arc
		(start 116.044361 76.438484)
		(mid 115.973651 76.467774)
		(end 115.90294 76.438485)
		(width 0.15)
		(layer "F.Cu")
		(net 172)
	)
	(arc
		(start 116.185782 75.731373)
		(mid 116.156492 75.802083)
		(end 116.185781 75.872794)
		(width 0.15)
		(layer "F.Cu")
		(net 172)
	)
	(arc
		(start 115.19583 77.287015)
		(mid 115.12512 77.316305)
		(end 115.054409 77.287016)
		(width 0.15)
		(layer "F.Cu")
		(net 172)
	)
	(arc
		(start 114.48872 77.428435)
		(mid 114.45943 77.499145)
		(end 114.488719 77.569856)
		(width 0.15)
		(layer "F.Cu")
		(net 172)
	)
	(arc
		(start 115.337251 76.579904)
		(mid 115.307961 76.650614)
		(end 115.33725 76.721325)
		(width 0.15)
		(layer "F.Cu")
		(net 172)
	)
	(arc
		(start 114.630142 77.71128)
		(mid 114.659431 77.781991)
		(end 114.630142 77.852702)
		(width 0.15)
		(layer "F.Cu")
		(net 172)
	)
	(arc
		(start 116.610047 75.448531)
		(mid 116.539336 75.419242)
		(end 116.468625 75.448531)
		(width 0.15)
		(layer "F.Cu")
		(net 172)
	)
	(arc
		(start 114.347299 78.135546)
		(mid 114.276589 78.164836)
		(end 114.205878 78.135547)
		(width 0.15)
		(layer "F.Cu")
		(net 172)
	)
	(arc
		(start 115.761516 76.297062)
		(mid 115.690805 76.267773)
		(end 115.620094 76.297062)
		(width 0.15)
		(layer "F.Cu")
		(net 172)
	)
	(arc
		(start 117.458578 74.6)
		(mid 117.387868 74.57071)
		(end 117.317157 74.599999)
		(width 0.15)
		(layer "F.Cu")
		(net 172)
	)
	(arc
		(start 117.034313 74.882842)
		(mid 117.005023 74.953552)
		(end 117.034312 75.024263)
		(width 0.15)
		(layer "F.Cu")
		(net 172)
	)
	(arc
		(start 117.6 74.6)
		(mid 117.529289 74.629289)
		(end 117.458578 74.6)
		(width 0.15)
		(layer "F.Cu")
		(net 172)
	)
	(arc
		(start 115.478673 76.862749)
		(mid 115.507962 76.93346)
		(end 115.478673 77.004171)
		(width 0.15)
		(layer "F.Cu")
		(net 172)
	)
	(arc
		(start 114.205877 78.135546)
		(mid 114.135166 78.106257)
		(end 114.064456 78.135547)
		(width 0.15)
		(layer "F.Cu")
		(net 172)
	)
	(arc
		(start 116.892892 75.589953)
		(mid 116.822182 75.619243)
		(end 116.751471 75.589954)
		(width 0.15)
		(layer "F.Cu")
		(net 172)
	)
	(arc
		(start 116.327204 76.014218)
		(mid 116.356493 76.084929)
		(end 116.327204 76.15564)
		(width 0.15)
		(layer "F.Cu")
		(net 172)
	)
	(segment
		(start 105.625 92.746902)
		(end 105.671902 92.7)
		(width 0.15)
		(layer "B.Cu")
		(net 172)
	)
	(segment
		(start 105.625 93.35)
		(end 105.625 92.746902)
		(width 0.15)
		(layer "B.Cu")
		(net 172)
	)
	(segment
		(start 110.032867 96.457867)
		(end 110.032867 96.552158)
		(width 0.15)
		(layer "In3.Cu")
		(net 172)
	)
	(segment
		(start 105.671902 93.096902)
		(end 107.775 95.2)
		(width 0.15)
		(layer "In3.Cu")
		(net 172)
	)
	(segment
		(start 107.775 95.2)
		(end 108.775 95.2)
		(width 0.15)
		(layer "In3.Cu")
		(net 172)
	)
	(segment
		(start 105.671902 92.7)
		(end 105.671902 93.096902)
		(width 0.15)
		(layer "In3.Cu")
		(net 172)
	)
	(segment
		(start 108.775 95.2)
		(end 110.032867 96.457867)
		(width 0.15)
		(layer "In3.Cu")
		(net 172)
	)
	(segment
		(start 115.975 96.4)
		(end 115.975 95.903554)
		(width 0.15)
		(layer "F.Cu")
		(net 173)
	)
	(segment
		(start 116.7625 95.116054)
		(end 116.7625 94.25)
		(width 0.15)
		(layer "F.Cu")
		(net 173)
	)
	(segment
		(start 115.975 95.903554)
		(end 116.7625 95.116054)
		(width 0.15)
		(layer "F.Cu")
		(net 173)
	)
	(via
		(at 115.975 96.4)
		(size 0.4)
		(drill 0.2)
		(layers "F.Cu" "B.Cu")
		(net 173)
	)
	(segment
		(start 115.65 98.6)
		(end 115.65 96.725)
		(width 0.15)
		(layer "B.Cu")
		(net 173)
	)
	(segment
		(start 115.65 96.725)
		(end 115.975 96.4)
		(width 0.15)
		(layer "B.Cu")
		(net 173)
	)
	(segment
		(start 115.425 96.1)
		(end 115.425 98.65)
		(width 0.15)
		(layer "F.Cu")
		(net 174)
	)
	(segment
		(start 116.125 95.4)
		(end 115.425 96.1)
		(width 0.15)
		(layer "F.Cu")
		(net 174)
	)
	(segment
		(start 116.125 94.25)
		(end 116.125 95.4)
		(width 0.15)
		(layer "F.Cu")
		(net 174)
	)
	(segment
		(start 115.625 95.35)
		(end 115.625 94.25)
		(width 0.15)
		(layer "F.Cu")
		(net 175)
	)
	(segment
		(start 114.975 96.4)
		(end 114.975 96)
		(width 0.15)
		(layer "F.Cu")
		(net 175)
	)
	(segment
		(start 114.975 96)
		(end 115.625 95.35)
		(width 0.15)
		(layer "F.Cu")
		(net 175)
	)
	(via
		(at 114.975 96.4)
		(size 0.4)
		(drill 0.2)
		(layers "F.Cu" "B.Cu")
		(net 175)
	)
	(segment
		(start 114.65 98.6)
		(end 114.65 96.725)
		(width 0.15)
		(layer "B.Cu")
		(net 175)
	)
	(segment
		(start 114.65 96.725)
		(end 114.975 96.4)
		(width 0.15)
		(layer "B.Cu")
		(net 175)
	)
	(segment
		(start 114.425 98.625)
		(end 114.425 95.95)
		(width 0.15)
		(layer "F.Cu")
		(net 176)
	)
	(segment
		(start 114.425 95.95)
		(end 114.9875 95.3875)
		(width 0.15)
		(layer "F.Cu")
		(net 176)
	)
	(segment
		(start 114.9875 95.3875)
		(end 114.9875 94.25)
		(width 0.15)
		(layer "F.Cu")
		(net 176)
	)
	(segment
		(start 107.225 95.6)
		(end 107.225 96.45)
		(width 0.15)
		(layer "F.Cu")
		(net 177)
	)
	(segment
		(start 106.9 96.775)
		(end 106.9 98.6)
		(width 0.15)
		(layer "F.Cu")
		(net 177)
	)
	(segment
		(start 107.225 95.6)
		(end 107.975 94.85)
		(width 0.15)
		(layer "F.Cu")
		(net 177)
	)
	(segment
		(start 106.9 98.6)
		(end 106.925 98.625)
		(width 0.15)
		(layer "F.Cu")
		(net 177)
	)
	(segment
		(start 107.975 94.85)
		(end 107.975 94.25)
		(width 0.15)
		(layer "F.Cu")
		(net 177)
	)
	(segment
		(start 107.225 96.45)
		(end 106.9 96.775)
		(width 0.15)
		(layer "F.Cu")
		(net 177)
	)
	(segment
		(start 108.025 96.719669)
		(end 108.025 96.1)
		(width 0.15)
		(layer "F.Cu")
		(net 178)
	)
	(segment
		(start 108.025 96.1)
		(end 109.1125 95.0125)
		(width 0.15)
		(layer "F.Cu")
		(net 178)
	)
	(segment
		(start 109.1125 95.0125)
		(end 109.1125 94.25)
		(width 0.15)
		(layer "F.Cu")
		(net 178)
	)
	(segment
		(start 107.925 96.819669)
		(end 108.025 96.719669)
		(width 0.15)
		(layer "F.Cu")
		(net 178)
	)
	(segment
		(start 107.925 98.625)
		(end 107.925 96.819669)
		(width 0.15)
		(layer "F.Cu")
		(net 178)
	)
	(segment
		(start 108.425 96.2)
		(end 109.75 94.875)
		(width 0.15)
		(layer "F.Cu")
		(net 179)
	)
	(segment
		(start 108.425 96.5)
		(end 108.425 96.2)
		(width 0.15)
		(layer "F.Cu")
		(net 179)
	)
	(segment
		(start 109.75 94.875)
		(end 109.75 94.25)
		(width 0.15)
		(layer "F.Cu")
		(net 179)
	)
	(via
		(at 108.42712 96.491944)
		(size 0.4)
		(drill 0.2)
		(layers "F.Cu" "B.Cu")
		(net 179)
	)
	(segment
		(start 108.675 96.75)
		(end 108.42712 96.50212)
		(width 0.15)
		(layer "B.Cu")
		(net 179)
	)
	(segment
		(start 108.675 98.625)
		(end 108.675 96.75)
		(width 0.15)
		(layer "B.Cu")
		(net 179)
	)
	(segment
		(start 108.42712 96.50212)
		(end 108.42712 96.491944)
		(width 0.15)
		(layer "B.Cu")
		(net 179)
	)
	(segment
		(start 107.625 96.399915)
		(end 107.625 96)
		(width 0.15)
		(layer "F.Cu")
		(net 180)
	)
	(segment
		(start 108.6125 95.0125)
		(end 108.6125 94.25)
		(width 0.15)
		(layer "F.Cu")
		(net 180)
	)
	(segment
		(start 107.625 96)
		(end 108.6125 95.0125)
		(width 0.15)
		(layer "F.Cu")
		(net 180)
	)
	(via
		(at 107.625 96.399915)
		(size 0.4)
		(drill 0.2)
		(layers "F.Cu" "B.Cu")
		(net 180)
	)
	(segment
		(start 107.675 98.6)
		(end 107.65 98.625)
		(width 0.15)
		(layer "B.Cu")
		(net 180)
	)
	(segment
		(start 107.625 96.399915)
		(end 107.675 96.449915)
		(width 0.15)
		(layer "B.Cu")
		(net 180)
	)
	(segment
		(start 107.675 96.449915)
		(end 107.675 98.6)
		(width 0.15)
		(layer "B.Cu")
		(net 180)
	)
	(segment
		(start 107.675 98.625)
		(end 107.7 98.6)
		(width 0.15)
		(layer "B.Cu")
		(net 180)
	)
	(segment
		(start 106.5266 95.977086)
		(end 106.5266 96.605493)
		(width 0.1016)
		(layer "B.Cu")
		(net 181)
	)
	(segment
		(start 106.7758 97.145307)
		(end 106.675 97.246107)
		(width 0.1016)
		(layer "B.Cu")
		(net 181)
	)
	(segment
		(start 106.675 97.246107)
		(end 106.675 98.625)
		(width 0.1016)
		(layer "B.Cu")
		(net 181)
	)
	(segment
		(start 106.7758 96.854693)
		(end 106.7758 97.145307)
		(width 0.1016)
		(layer "B.Cu")
		(net 181)
	)
	(segment
		(start 106.675 98.625)
		(end 106.675 97.244975)
		(width 0.1)
		(layer "B.Cu")
		(net 181)
	)
	(segment
		(start 107.231601 95.272085)
		(end 106.5266 95.977086)
		(width 0.1016)
		(layer "B.Cu")
		(net 181)
	)
	(segment
		(start 107.231601 91.853399)
		(end 107.63 91.455)
		(width 0.1016)
		(layer "B.Cu")
		(net 181)
	)
	(segment
		(start 106.5266 96.605493)
		(end 106.7758 96.854693)
		(width 0.1016)
		(layer "B.Cu")
		(net 181)
	)
	(segment
		(start 107.231601 95.272085)
		(end 107.231601 91.853399)
		(width 0.1016)
		(layer "B.Cu")
		(net 181)
	)
	(segment
		(start 106.0742 97.145307)
		(end 106.175 97.246107)
		(width 0.1016)
		(layer "B.Cu")
		(net 182)
	)
	(segment
		(start 107.028399 95.187915)
		(end 107.028399 91.853399)
		(width 0.1016)
		(layer "B.Cu")
		(net 182)
	)
	(segment
		(start 106.3234 96.605493)
		(end 106.0742 96.854693)
		(width 0.1016)
		(layer "B.Cu")
		(net 182)
	)
	(segment
		(start 107.028399 95.187915)
		(end 106.3234 95.892914)
		(width 0.1016)
		(layer "B.Cu")
		(net 182)
	)
	(segment
		(start 107.028399 91.853399)
		(end 106.63 91.455)
		(width 0.1016)
		(layer "B.Cu")
		(net 182)
	)
	(segment
		(start 106.3234 95.892914)
		(end 106.3234 96.605493)
		(width 0.1016)
		(layer "B.Cu")
		(net 182)
	)
	(segment
		(start 106.175 97.246107)
		(end 106.175 98.625)
		(width 0.1016)
		(layer "B.Cu")
		(net 182)
	)
	(segment
		(start 106.0742 96.854693)
		(end 106.0742 97.145307)
		(width 0.1016)
		(layer "B.Cu")
		(net 182)
	)
	(segment
		(start 106.175 98.625)
		(end 106.175 97.244975)
		(width 0.1)
		(layer "B.Cu")
		(net 182)
	)
	(segment
		(start 123.8 74.8)
		(end 123.4 74.8)
		(width 0.15)
		(layer "F.Cu")
		(net 183)
	)
	(segment
		(start 124.4 75.2)
		(end 124 75.2)
		(width 0.15)
		(layer "F.Cu")
		(net 183)
	)
	(segment
		(start 126.3 75)
		(end 126.3 74.9)
		(width 0.15)
		(layer "F.Cu")
		(net 183)
	)
	(segment
		(start 127.525 74.8)
		(end 127.325 75)
		(width 0.15)
		(layer "F.Cu")
		(net 183)
	)
	(segment
		(start 106.225 92.7)
		(end 106.2625 92.7375)
		(width 0.15)
		(layer "F.Cu")
		(net 183)
	)
	(segment
		(start 128.330025 75.55)
		(end 128.125 75.344975)
		(width 0.09)
		(layer "F.Cu")
		(net 183)
	)
	(segment
		(start 128.125 75)
		(end 127.925 74.8)
		(width 0.09)
		(layer "F.Cu")
		(net 183)
	)
	(segment
		(start 125.7 75)
		(end 125.7 75.1)
		(width 0.15)
		(layer "F.Cu")
		(net 183)
	)
	(segment
		(start 123.9 75)
		(end 123.9 74.9)
		(width 0.15)
		(layer "F.Cu")
		(net 183)
	)
	(segment
		(start 122.7 75)
		(end 122.7 74.9)
		(width 0.15)
		(layer "F.Cu")
		(net 183)
	)
	(segment
		(start 129.425 75.55)
		(end 128.330025 75.55)
		(width 0.09)
		(layer "F.Cu")
		(net 183)
	)
	(segment
		(start 125 74.8)
		(end 124.6 74.8)
		(width 0.15)
		(layer "F.Cu")
		(net 183)
	)
	(segment
		(start 122 75.2)
		(end 121.6 75.2)
		(width 0.15)
		(layer "F.Cu")
		(net 183)
	)
	(segment
		(start 124.5 74.9)
		(end 124.5 75)
		(width 0.15)
		(layer "F.Cu")
		(net 183)
	)
	(segment
		(start 126.3 75.1)
		(end 126.3 75)
		(width 0.15)
		(layer "F.Cu")
		(net 183)
	)
	(segment
		(start 127.325 75)
		(end 127 75)
		(width 0.15)
		(layer "F.Cu")
		(net 183)
	)
	(segment
		(start 125.7 74.9)
		(end 125.7 75)
		(width 0.15)
		(layer "F.Cu")
		(net 183)
	)
	(segment
		(start 123.3 74.9)
		(end 123.3 75)
		(width 0.15)
		(layer "F.Cu")
		(net 183)
	)
	(segment
		(start 123.9 75.1)
		(end 123.9 75)
		(width 0.15)
		(layer "F.Cu")
		(net 183)
	)
	(segment
		(start 125.1 75.1)
		(end 125.1 75)
		(width 0.15)
		(layer "F.Cu")
		(net 183)
	)
	(segment
		(start 121.5 75.1)
		(end 121.5 75)
		(width 0.15)
		(layer "F.Cu")
		(net 183)
	)
	(segment
		(start 128.125 75.344975)
		(end 128.125 75)
		(width 0.09)
		(layer "F.Cu")
		(net 183)
	)
	(segment
		(start 127.925 74.8)
		(end 127.525 74.8)
		(width 0.09)
		(layer "F.Cu")
		(net 183)
	)
	(segment
		(start 124.5 75)
		(end 124.5 75.1)
		(width 0.15)
		(layer "F.Cu")
		(net 183)
	)
	(segment
		(start 122.6 74.8)
		(end 122.2 74.8)
		(width 0.15)
		(layer "F.Cu")
		(net 183)
	)
	(segment
		(start 106.225 86.975)
		(end 106.225 92.7)
		(width 0.15)
		(layer "F.Cu")
		(net 183)
	)
	(segment
		(start 122.7 75.1)
		(end 122.7 75)
		(width 0.15)
		(layer "F.Cu")
		(net 183)
	)
	(segment
		(start 126.8 75.2)
		(end 126.4 75.2)
		(width 0.15)
		(layer "F.Cu")
		(net 183)
	)
	(segment
		(start 123.3 75)
		(end 123.3 75.1)
		(width 0.15)
		(layer "F.Cu")
		(net 183)
	)
	(segment
		(start 106.2625 92.7375)
		(end 106.2625 93.35)
		(width 0.15)
		(layer "F.Cu")
		(net 183)
	)
	(segment
		(start 121.5 75)
		(end 121.5 74.9)
		(width 0.15)
		(layer "F.Cu")
		(net 183)
	)
	(segment
		(start 123.2 75.2)
		(end 122.8 75.2)
		(width 0.15)
		(layer "F.Cu")
		(net 183)
	)
	(segment
		(start 118.2 75)
		(end 120.8 75)
		(width 0.15)
		(layer "F.Cu")
		(net 183)
	)
	(segment
		(start 125.6 75.2)
		(end 125.2 75.2)
		(width 0.15)
		(layer "F.Cu")
		(net 183)
	)
	(segment
		(start 121.4 74.8)
		(end 121 74.8)
		(width 0.15)
		(layer "F.Cu")
		(net 183)
	)
	(segment
		(start 118.2 75)
		(end 106.225 86.975)
		(width 0.15)
		(layer "F.Cu")
		(net 183)
	)
	(segment
		(start 122.1 74.9)
		(end 122.1 75)
		(width 0.15)
		(layer "F.Cu")
		(net 183)
	)
	(segment
		(start 125.1 75)
		(end 125.1 74.9)
		(width 0.15)
		(layer "F.Cu")
		(net 183)
	)
	(segment
		(start 126.2 74.8)
		(end 125.8 74.8)
		(width 0.15)
		(layer "F.Cu")
		(net 183)
	)
	(segment
		(start 122.1 75)
		(end 122.1 75.1)
		(width 0.15)
		(layer "F.Cu")
		(net 183)
	)
	(segment
		(start 129.875 76)
		(end 129.425 75.55)
		(width 0.09)
		(layer "F.Cu")
		(net 183)
	)
	(via
		(at 106.225 92.7)
		(size 0.4)
		(drill 0.2)
		(layers "F.Cu" "B.Cu")
		(net 183)
	)
	(via
		(at 110.539499 96.536659)
		(size 0.4)
		(drill 0.2)
		(layers "F.Cu" "B.Cu")
		(net 183)
	)
	(arc
		(start 126.3 74.9)
		(mid 126.270711 74.829289)
		(end 126.2 74.8)
		(width 0.15)
		(layer "F.Cu")
		(net 183)
	)
	(arc
		(start 121.5 74.9)
		(mid 121.470711 74.829289)
		(end 121.4 74.8)
		(width 0.15)
		(layer "F.Cu")
		(net 183)
	)
	(arc
		(start 122.2 74.8)
		(mid 122.129289 74.829289)
		(end 122.1 74.9)
		(width 0.15)
		(layer "F.Cu")
		(net 183)
	)
	(arc
		(start 121.6 75.2)
		(mid 121.529289 75.170711)
		(end 121.5 75.1)
		(width 0.15)
		(layer "F.Cu")
		(net 183)
	)
	(arc
		(start 125.1 74.9)
		(mid 125.070711 74.829289)
		(end 125 74.8)
		(width 0.15)
		(layer "F.Cu")
		(net 183)
	)
	(arc
		(start 123.9 74.9)
		(mid 123.870711 74.829289)
		(end 123.8 74.8)
		(width 0.15)
		(layer "F.Cu")
		(net 183)
	)
	(arc
		(start 124.5 75.1)
		(mid 124.470711 75.170711)
		(end 124.4 75.2)
		(width 0.15)
		(layer "F.Cu")
		(net 183)
	)
	(arc
		(start 125.2 75.2)
		(mid 125.129289 75.170711)
		(end 125.1 75.1)
		(width 0.15)
		(layer "F.Cu")
		(net 183)
	)
	(arc
		(start 127 75)
		(mid 126.929289 75.029289)
		(end 126.9 75.1)
		(width 0.15)
		(layer "F.Cu")
		(net 183)
	)
	(arc
		(start 124 75.2)
		(mid 123.929289 75.170711)
		(end 123.9 75.1)
		(width 0.15)
		(layer "F.Cu")
		(net 183)
	)
	(arc
		(start 122.7 74.9)
		(mid 122.670711 74.829289)
		(end 122.6 74.8)
		(width 0.15)
		(layer "F.Cu")
		(net 183)
	)
	(arc
		(start 120.9 74.9)
		(mid 120.870711 74.970711)
		(end 120.8 75)
		(width 0.15)
		(layer "F.Cu")
		(net 183)
	)
	(arc
		(start 126.9 75.1)
		(mid 126.870711 75.170711)
		(end 126.8 75.2)
		(width 0.15)
		(layer "F.Cu")
		(net 183)
	)
	(arc
		(start 122.8 75.2)
		(mid 122.729289 75.170711)
		(end 122.7 75.1)
		(width 0.15)
		(layer "F.Cu")
		(net 183)
	)
	(arc
		(start 126.4 75.2)
		(mid 126.329289 75.170711)
		(end 126.3 75.1)
		(width 0.15)
		(layer "F.Cu")
		(net 183)
	)
	(arc
		(start 123.4 74.8)
		(mid 123.329289 74.829289)
		(end 123.3 74.9)
		(width 0.15)
		(layer "F.Cu")
		(net 183)
	)
	(arc
		(start 123.3 75.1)
		(mid 123.270711 75.170711)
		(end 123.2 75.2)
		(width 0.15)
		(layer "F.Cu")
		(net 183)
	)
	(arc
		(start 122.1 75.1)
		(mid 122.070711 75.170711)
		(end 122 75.2)
		(width 0.15)
		(layer "F.Cu")
		(net 183)
	)
	(arc
		(start 121 74.8)
		(mid 120.929289 74.829289)
		(end 120.9 74.9)
		(width 0.15)
		(layer "F.Cu")
		(net 183)
	)
	(arc
		(start 125.7 75.1)
		(mid 125.670711 75.170711)
		(end 125.6 75.2)
		(width 0.15)
		(layer "F.Cu")
		(net 183)
	)
	(arc
		(start 125.8 74.8)
		(mid 125.729289 74.829289)
		(end 125.7 74.9)
		(width 0.15)
		(layer "F.Cu")
		(net 183)
	)
	(arc
		(start 124.6 74.8)
		(mid 124.529289 74.829289)
		(end 124.5 74.9)
		(width 0.15)
		(layer "F.Cu")
		(net 183)
	)
	(segment
		(start 106.2625 92.7375)
		(end 106.225 92.7)
		(width 0.15)
		(layer "B.Cu")
		(net 183)
	)
	(segment
		(start 110.675 96.67216)
		(end 110.539499 96.536659)
		(width 0.15)
		(layer "B.Cu")
		(net 183)
	)
	(segment
		(start 106.2625 93.35)
		(end 106.2625 92.7375)
		(width 0.15)
		(layer "B.Cu")
		(net 183)
	)
	(segment
		(start 110.675 98.625)
		(end 110.675 96.67216)
		(width 0.15)
		(layer "B.Cu")
		(net 183)
	)
	(segment
		(start 108.075 94.9)
		(end 106.225 93.05)
		(width 0.15)
		(layer "In3.Cu")
		(net 183)
	)
	(segment
		(start 110.539499 96.368053)
		(end 109.071446 94.9)
		(width 0.15)
		(layer "In3.Cu")
		(net 183)
	)
	(segment
		(start 109.071446 94.9)
		(end 108.075 94.9)
		(width 0.15)
		(layer "In3.Cu")
		(net 183)
	)
	(segment
		(start 106.225 93.05)
		(end 106.225 92.7)
		(width 0.15)
		(layer "In3.Cu")
		(net 183)
	)
	(segment
		(start 110.539499 96.536659)
		(end 110.539499 96.368053)
		(width 0.15)
		(layer "In3.Cu")
		(net 183)
	)
	(segment
		(start 105.475 95.903554)
		(end 106.2625 95.116054)
		(width 0.15)
		(layer "F.Cu")
		(net 184)
	)
	(segment
		(start 105.475 96.4)
		(end 105.475 95.903554)
		(width 0.15)
		(layer "F.Cu")
		(net 184)
	)
	(segment
		(start 106.2625 95.116054)
		(end 106.2625 94.25)
		(width 0.15)
		(layer "F.Cu")
		(net 184)
	)
	(via
		(at 105.475 96.4)
		(size 0.4)
		(drill 0.2)
		(layers "F.Cu" "B.Cu")
		(net 184)
	)
	(segment
		(start 105.15 98.6)
		(end 105.15 96.725)
		(width 0.15)
		(layer "B.Cu")
		(net 184)
	)
	(segment
		(start 105.15 96.725)
		(end 105.475 96.4)
		(width 0.15)
		(layer "B.Cu")
		(net 184)
	)
	(segment
		(start 104.475 96.4)
		(end 104.475 96)
		(width 0.15)
		(layer "F.Cu")
		(net 185)
	)
	(segment
		(start 105.125 95.35)
		(end 105.125 94.25)
		(width 0.15)
		(layer "F.Cu")
		(net 185)
	)
	(segment
		(start 104.475 96)
		(end 105.125 95.35)
		(width 0.15)
		(layer "F.Cu")
		(net 185)
	)
	(via
		(at 104.475 96.4)
		(size 0.4)
		(drill 0.2)
		(layers "F.Cu" "B.Cu")
		(net 185)
	)
	(segment
		(start 104.15 96.725)
		(end 104.475 96.4)
		(width 0.15)
		(layer "B.Cu")
		(net 185)
	)
	(segment
		(start 104.15 98.6)
		(end 104.15 96.725)
		(width 0.15)
		(layer "B.Cu")
		(net 185)
	)
	(segment
		(start 104.925 96.1)
		(end 104.925 98.65)
		(width 0.15)
		(layer "F.Cu")
		(net 186)
	)
	(segment
		(start 105.625 95.4)
		(end 104.925 96.1)
		(width 0.15)
		(layer "F.Cu")
		(net 186)
	)
	(segment
		(start 105.625 94.25)
		(end 105.625 95.4)
		(width 0.15)
		(layer "F.Cu")
		(net 186)
	)
	(segment
		(start 104.4875 95.3875)
		(end 104.4875 94.25)
		(width 0.15)
		(layer "F.Cu")
		(net 187)
	)
	(segment
		(start 103.925 98.625)
		(end 103.925 95.95)
		(width 0.15)
		(layer "F.Cu")
		(net 187)
	)
	(segment
		(start 103.925 95.95)
		(end 104.4875 95.3875)
		(width 0.15)
		(layer "F.Cu")
		(net 187)
	)
	(segment
		(start 112.748399 86.375516)
		(end 112.5992 86.226317)
		(width 0.1016)
		(layer "F.Cu")
		(net 188)
	)
	(segment
		(start 110.825 96.798897)
		(end 110.825 96.796912)
		(width 0.1016)
		(layer "F.Cu")
		(net 188)
	)
	(segment
		(start 110.825 96.796912)
		(end 111.0734 96.548512)
		(width 0.1016)
		(layer "F.Cu")
		(net 188)
	)
	(segment
		(start 110.925 98.625)
		(end 110.925 97.244975)
		(width 0.1)
		(layer "F.Cu")
		(net 188)
	)
	(segment
		(start 112.748399 88.087915)
		(end 112.748399 86.375516)
		(width 0.1016)
		(layer "F.Cu")
		(net 188)
	)
	(segment
		(start 111.0734 89.762914)
		(end 112.748399 88.087915)
		(width 0.1016)
		(layer "F.Cu")
		(net 188)
	)
	(segment
		(start 110.825 97.144975)
		(end 110.825 96.798897)
		(width 0.1)
		(layer "F.Cu")
		(net 188)
	)
	(segment
		(start 111.0734 96.548512)
		(end 111.0734 89.762914)
		(width 0.1016)
		(layer "F.Cu")
		(net 188)
	)
	(segment
		(start 110.925 97.244975)
		(end 110.825 97.144975)
		(width 0.1)
		(layer "F.Cu")
		(net 188)
	)
	(via
		(at 112.5992 86.226317)
		(size 0.4)
		(drill 0.2)
		(layers "F.Cu" "B.Cu")
		(net 188)
	)
	(via
		(at 129.175 76.8)
		(size 0.4)
		(drill 0.15)
		(layers "F.Cu" "B.Cu")
		(net 188)
	)
	(segment
		(start 128.825 76.45)
		(end 128.825 75.85)
		(width 0.1)
		(layer "B.Cu")
		(net 188)
	)
	(segment
		(start 119.4384 76.58)
		(end 119.4384 76.8308)
		(width 0.1016)
		(layer "B.Cu")
		(net 188)
	)
	(segment
		(start 128.825 75.85)
		(end 128.575 75.6)
		(width 0.1)
		(layer "B.Cu")
		(net 188)
	)
	(segment
		(start 129.175 76.8)
		(end 128.825 76.45)
		(width 0.1)
		(layer "B.Cu")
		(net 188)
	)
	(segment
		(start 115.4892 76.0292)
		(end 114.778246 76.0292)
		(width 0.1016)
		(layer "B.Cu")
		(net 188)
	)
	(segment
		(start 128.115912 75.374821)
		(end 127.849023 75.374821)
		(width 0.1)
		(layer "B.Cu")
		(net 188)
	)
	(segment
		(start 127.849023 75.374821)
		(end 127.432625 75.374821)
		(width 0.1016)
		(layer "B.Cu")
		(net 188)
	)
	(segment
		(start 117.6384 75.4292)
		(end 117.6384 76.8308)
		(width 0.1016)
		(layer "B.Cu")
		(net 188)
	)
	(segment
		(start 128.575 75.6)
		(end 128.341091 75.6)
		(width 0.1)
		(layer "B.Cu")
		(net 188)
	)
	(segment
		(start 128.341091 75.6)
		(end 128.115912 75.374821)
		(width 0.1)
		(layer "B.Cu")
		(net 188)
	)
	(segment
		(start 115.8384 75.4292)
		(end 115.8384 75.68)
		(width 0.1016)
		(layer "B.Cu")
		(net 188)
	)
	(segment
		(start 116.94 76.8308)
		(end 116.94 75.4292)
		(width 0.1016)
		(layer "B.Cu")
		(net 188)
	)
	(segment
		(start 114.778246 76.0292)
		(end 112.748399 78.059047)
		(width 0.1016)
		(layer "B.Cu")
		(net 188)
	)
	(segment
		(start 118.74 76.8308)
		(end 118.74 75.4292)
		(width 0.1016)
		(layer "B.Cu")
		(net 188)
	)
	(segment
		(start 127.432625 75.374821)
		(end 126.778246 76.0292)
		(width 0.1016)
		(layer "B.Cu")
		(net 188)
	)
	(segment
		(start 112.748399 78.059047)
		(end 112.748399 86.077118)
		(width 0.1016)
		(layer "B.Cu")
		(net 188)
	)
	(segment
		(start 126.778246 76.0292)
		(end 119.9892 76.0292)
		(width 0.1016)
		(layer "B.Cu")
		(net 188)
	)
	(segment
		(start 112.748399 86.077118)
		(end 112.5992 86.226317)
		(width 0.1016)
		(layer "B.Cu")
		(net 188)
	)
	(arc
		(start 116.94 75.4292)
		(mid 116.778674 75.039726)
		(end 116.3892 74.8784)
		(width 0.1016)
		(layer "B.Cu")
		(net 188)
	)
	(arc
		(start 118.1892 74.8784)
		(mid 117.799726 75.039726)
		(end 117.6384 75.4292)
		(width 0.1016)
		(layer "B.Cu")
		(net 188)
	)
	(arc
		(start 119.9892 76.0292)
		(mid 119.599726 76.190526)
		(end 119.4384 76.58)
		(width 0.1016)
		(layer "B.Cu")
		(net 188)
	)
	(arc
		(start 119.4384 76.8308)
		(mid 119.336122 77.077722)
		(end 119.0892 77.18)
		(width 0.1016)
		(layer "B.Cu")
		(net 188)
	)
	(arc
		(start 116.3892 74.8784)
		(mid 115.999726 75.039726)
		(end 115.8384 75.4292)
		(width 0.1016)
		(layer "B.Cu")
		(net 188)
	)
	(arc
		(start 119.0892 77.18)
		(mid 118.842278 77.077722)
		(end 118.74 76.8308)
		(width 0.1016)
		(layer "B.Cu")
		(net 188)
	)
	(arc
		(start 117.6384 76.8308)
		(mid 117.536122 77.077722)
		(end 117.2892 77.18)
		(width 0.1016)
		(layer "B.Cu")
		(net 188)
	)
	(arc
		(start 115.8384 75.68)
		(mid 115.736122 75.926922)
		(end 115.4892 76.0292)
		(width 0.1016)
		(layer "B.Cu")
		(net 188)
	)
	(arc
		(start 117.2892 77.18)
		(mid 117.042278 77.077722)
		(end 116.94 76.8308)
		(width 0.1016)
		(layer "B.Cu")
		(net 188)
	)
	(arc
		(start 118.74 75.4292)
		(mid 118.578674 75.039726)
		(end 118.1892 74.8784)
		(width 0.1016)
		(layer "B.Cu")
		(net 188)
	)
	(segment
		(start 111.525 96.798897)
		(end 111.525 96.796912)
		(width 0.1016)
		(layer "F.Cu")
		(net 189)
	)
	(segment
		(start 111.525 97.144975)
		(end 111.525 96.798897)
		(width 0.1)
		(layer "F.Cu")
		(net 189)
	)
	(segment
		(start 111.425 98.625)
		(end 111.425 97.244975)
		(width 0.1)
		(layer "F.Cu")
		(net 189)
	)
	(segment
		(start 112.951601 88.172085)
		(end 112.951601 86.375516)
		(width 0.1016)
		(layer "F.Cu")
		(net 189)
	)
	(segment
		(start 112.951601 86.375516)
		(end 113.1008 86.226317)
		(width 0.1016)
		(layer "F.Cu")
		(net 189)
	)
	(segment
		(start 111.425 97.244975)
		(end 111.525 97.144975)
		(width 0.1)
		(layer "F.Cu")
		(net 189)
	)
	(segment
		(start 111.2766 96.548512)
		(end 111.2766 89.847086)
		(width 0.1016)
		(layer "F.Cu")
		(net 189)
	)
	(segment
		(start 111.525 96.796912)
		(end 111.2766 96.548512)
		(width 0.1016)
		(layer "F.Cu")
		(net 189)
	)
	(segment
		(start 111.2766 89.847086)
		(end 112.951601 88.172085)
		(width 0.1016)
		(layer "F.Cu")
		(net 189)
	)
	(via
		(at 128.475 76)
		(size 0.4)
		(drill 0.15)
		(layers "F.Cu" "B.Cu")
		(net 189)
	)
	(via
		(at 113.1008 86.226317)
		(size 0.4)
		(drill 0.2)
		(layers "F.Cu" "B.Cu")
		(net 189)
	)
	(segment
		(start 127.096381 76.178891)
		(end 127.090442 76.172952)
		(width 0.1016)
		(layer "B.Cu")
		(net 189)
	)
	(segment
		(start 126.919605 76.172951)
		(end 126.919604 76.172953)
		(width 0.1016)
		(layer "B.Cu")
		(net 189)
	)
	(segment
		(start 128.458247 76)
		(end 128.036268 75.578021)
		(width 0.1)
		(layer "B.Cu")
		(net 189)
	)
	(segment
		(start 125.861754 76.4308)
		(end 125.861754 76.5808)
		(width 0.1016)
		(layer "B.Cu")
		(net 189)
	)
	(segment
		(start 127.261277 76.002115)
		(end 127.261276 76.002115)
		(width 0.1016)
		(layer "B.Cu")
		(net 189)
	)
	(segment
		(start 128.475 76)
		(end 128.458247 76)
		(width 0.1)
		(layer "B.Cu")
		(net 189)
	)
	(segment
		(start 118.5384 76.8308)
		(end 118.5384 75.4292)
		(width 0.1016)
		(layer "B.Cu")
		(net 189)
	)
	(segment
		(start 112.951601 78.140953)
		(end 112.951601 86.077118)
		(width 0.1016)
		(layer "B.Cu")
		(net 189)
	)
	(segment
		(start 126.919604 76.172953)
		(end 126.861754 76.2308)
		(width 0.1016)
		(layer "B.Cu")
		(net 189)
	)
	(segment
		(start 125.211754 76.2308)
		(end 119.9892 76.2308)
		(width 0.1016)
		(layer "B.Cu")
		(net 189)
	)
	(segment
		(start 119.64 76.58)
		(end 119.64 76.8308)
		(width 0.1016)
		(layer "B.Cu")
		(net 189)
	)
	(segment
		(start 125.461754 76.5808)
		(end 125.461754 76.4308)
		(width 0.1016)
		(layer "B.Cu")
		(net 189)
	)
	(segment
		(start 112.951601 86.077118)
		(end 113.1008 86.226317)
		(width 0.1016)
		(layer "B.Cu")
		(net 189)
	)
	(segment
		(start 127.514533 75.578021)
		(end 127.261277 75.831277)
		(width 0.1016)
		(layer "B.Cu")
		(net 189)
	)
	(segment
		(start 126.661754 76.4308)
		(end 126.661754 76.5808)
		(width 0.1016)
		(layer "B.Cu")
		(net 189)
	)
	(segment
		(start 126.261754 76.5808)
		(end 126.261754 76.4308)
		(width 0.1016)
		(layer "B.Cu")
		(net 189)
	)
	(segment
		(start 128.036268 75.578021)
		(end 127.849023 75.578021)
		(width 0.1)
		(layer "B.Cu")
		(net 189)
	)
	(segment
		(start 114.861754 76.2308)
		(end 112.951601 78.140953)
		(width 0.1016)
		(layer "B.Cu")
		(net 189)
	)
	(segment
		(start 125.261754 76.2308)
		(end 125.211754 76.2308)
		(width 0.1016)
		(layer "B.Cu")
		(net 189)
	)
	(segment
		(start 127.267217 76.178892)
		(end 127.267217 76.178891)
		(width 0.1016)
		(layer "B.Cu")
		(net 189)
	)
	(segment
		(start 117.84 75.4292)
		(end 117.84 76.8308)
		(width 0.1016)
		(layer "B.Cu")
		(net 189)
	)
	(segment
		(start 127.261276 76.002115)
		(end 127.267216 76.008055)
		(width 0.1016)
		(layer "B.Cu")
		(net 189)
	)
	(segment
		(start 116.04 75.4292)
		(end 116.04 75.68)
		(width 0.1016)
		(layer "B.Cu")
		(net 189)
	)
	(segment
		(start 116.7384 76.8308)
		(end 116.7384 75.4292)
		(width 0.1016)
		(layer "B.Cu")
		(net 189)
	)
	(segment
		(start 115.4892 76.2308)
		(end 114.861754 76.2308)
		(width 0.1016)
		(layer "B.Cu")
		(net 189)
	)
	(segment
		(start 127.849023 75.578021)
		(end 127.514533 75.578021)
		(width 0.1016)
		(layer "B.Cu")
		(net 189)
	)
	(arc
		(start 116.3892 75.08)
		(mid 116.142278 75.182278)
		(end 116.04 75.4292)
		(width 0.1016)
		(layer "B.Cu")
		(net 189)
	)
	(arc
		(start 118.1892 75.08)
		(mid 117.942278 75.182278)
		(end 117.84 75.4292)
		(width 0.1016)
		(layer "B.Cu")
		(net 189)
	)
	(arc
		(start 117.2892 77.3816)
		(mid 116.899726 77.220274)
		(end 116.7384 76.8308)
		(width 0.1016)
		(layer "B.Cu")
		(net 189)
	)
	(arc
		(start 126.661754 76.5808)
		(mid 126.603175 76.722221)
		(end 126.461754 76.7808)
		(width 0.1016)
		(layer "B.Cu")
		(net 189)
	)
	(arc
		(start 118.5384 75.4292)
		(mid 118.436122 75.182278)
		(end 118.1892 75.08)
		(width 0.1016)
		(layer "B.Cu")
		(net 189)
	)
	(arc
		(start 126.461754 76.7808)
		(mid 126.320333 76.722221)
		(end 126.261754 76.5808)
		(width 0.1016)
		(layer "B.Cu")
		(net 189)
	)
	(arc
		(start 116.7384 75.4292)
		(mid 116.636122 75.182278)
		(end 116.3892 75.08)
		(width 0.1016)
		(layer "B.Cu")
		(net 189)
	)
	(arc
		(start 127.090442 76.172952)
		(mid 127.005024 76.13757)
		(end 126.919605 76.172951)
		(width 0.1016)
		(layer "B.Cu")
		(net 189)
	)
	(arc
		(start 126.861754 76.2308)
		(mid 126.720333 76.289379)
		(end 126.661754 76.4308)
		(width 0.1016)
		(layer "B.Cu")
		(net 189)
	)
	(arc
		(start 127.267216 76.008055)
		(mid 127.302598 76.093473)
		(end 127.267217 76.178892)
		(width 0.1016)
		(layer "B.Cu")
		(net 189)
	)
	(arc
		(start 126.061754 76.2308)
		(mid 125.920333 76.289379)
		(end 125.861754 76.4308)
		(width 0.1016)
		(layer "B.Cu")
		(net 189)
	)
	(arc
		(start 116.04 75.68)
		(mid 115.878674 76.069474)
		(end 115.4892 76.2308)
		(width 0.1016)
		(layer "B.Cu")
		(net 189)
	)
	(arc
		(start 119.9892 76.2308)
		(mid 119.742278 76.333078)
		(end 119.64 76.58)
		(width 0.1016)
		(layer "B.Cu")
		(net 189)
	)
	(arc
		(start 125.661754 76.7808)
		(mid 125.520333 76.722221)
		(end 125.461754 76.5808)
		(width 0.1016)
		(layer "B.Cu")
		(net 189)
	)
	(arc
		(start 117.84 76.8308)
		(mid 117.678674 77.220274)
		(end 117.2892 77.3816)
		(width 0.1016)
		(layer "B.Cu")
		(net 189)
	)
	(arc
		(start 127.267217 76.178891)
		(mid 127.181798 76.214273)
		(end 127.096381 76.178891)
		(width 0.1016)
		(layer "B.Cu")
		(net 189)
	)
	(arc
		(start 126.261754 76.4308)
		(mid 126.203175 76.289379)
		(end 126.061754 76.2308)
		(width 0.1016)
		(layer "B.Cu")
		(net 189)
	)
	(arc
		(start 119.64 76.8308)
		(mid 119.478674 77.220274)
		(end 119.0892 77.3816)
		(width 0.1016)
		(layer "B.Cu")
		(net 189)
	)
	(arc
		(start 127.261277 75.831277)
		(mid 127.225894 75.916697)
		(end 127.261277 76.002115)
		(width 0.1016)
		(layer "B.Cu")
		(net 189)
	)
	(arc
		(start 119.0892 77.3816)
		(mid 118.699726 77.220274)
		(end 118.5384 76.8308)
		(width 0.1016)
		(layer "B.Cu")
		(net 189)
	)
	(arc
		(start 125.861754 76.5808)
		(mid 125.803175 76.722221)
		(end 125.661754 76.7808)
		(width 0.1016)
		(layer "B.Cu")
		(net 189)
	)
	(arc
		(start 125.461754 76.4308)
		(mid 125.403175 76.289379)
		(end 125.261754 76.2308)
		(width 0.1016)
		(layer "B.Cu")
		(net 189)
	)
	(segment
		(start 117.551471 76.825308)
		(end 117.374692 76.64853)
		(width 0.15)
		(layer "F.Cu")
		(net 190)
	)
	(segment
		(start 106.5995 87.6005)
		(end 106.5995 92.1)
		(width 0.15)
		(layer "F.Cu")
		(net 190)
	)
	(segment
		(start 115.253365 78.769856)
		(end 115.430143 78.946635)
		(width 0.15)
		(layer "F.Cu")
		(net 190)
	)
	(segment
		(start 118.223222 75.8)
		(end 118.223223 75.8)
		(width 0.15)
		(layer "F.Cu")
		(net 190)
	)
	(segment
		(start 118.6 75.6)
		(end 118.4 75.8)
		(width 0.15)
		(layer "F.Cu")
		(net 190)
	)
	(segment
		(start 116.702942 77.673838)
		(end 116.70294 77.673839)
		(width 0.15)
		(layer "F.Cu")
		(net 190)
	)
	(segment
		(start 118.046446 75.799999)
		(end 118.046446 75.8)
		(width 0.15)
		(layer "F.Cu")
		(net 190)
	)
	(segment
		(start 117.798958 76.224263)
		(end 117.798958 76.224264)
		(width 0.15)
		(layer "F.Cu")
		(net 190)
	)
	(segment
		(start 115.430142 79.123413)
		(end 115.182656 79.3709)
		(width 0.15)
		(layer "F.Cu")
		(net 190)
	)
	(segment
		(start 115.00588 79.3709)
		(end 115.005878 79.370901)
		(width 0.15)
		(layer "F.Cu")
		(net 190)
	)
	(segment
		(start 117.551473 76.825307)
		(end 117.551471 76.825308)
		(width 0.15)
		(layer "F.Cu")
		(net 190)
	)
	(segment
		(start 117.197915 76.64853)
		(end 116.950427 76.896017)
		(width 0.15)
		(layer "F.Cu")
		(net 190)
	)
	(segment
		(start 117.975735 76.577819)
		(end 117.975735 76.57782)
		(width 0.15)
		(layer "F.Cu")
		(net 190)
	)
	(segment
		(start 115.854409 78.52237)
		(end 115.67763 78.345592)
		(width 0.15)
		(layer "F.Cu")
		(net 190)
	)
	(segment
		(start 117.127204 77.426351)
		(end 116.879718 77.673838)
		(width 0.15)
		(layer "F.Cu")
		(net 190)
	)
	(segment
		(start 113.980201 80.219799)
		(end 106.5995 87.6005)
		(width 0.15)
		(layer "F.Cu")
		(net 190)
	)
	(segment
		(start 115.430142 79.123412)
		(end 115.430142 79.123413)
		(width 0.15)
		(layer "F.Cu")
		(net 190)
	)
	(segment
		(start 116.70294 77.673839)
		(end 116.526161 77.497061)
		(width 0.15)
		(layer "F.Cu")
		(net 190)
	)
	(segment
		(start 114.404834 79.795163)
		(end 113.980201 80.219799)
		(width 0.15)
		(layer "F.Cu")
		(net 190)
	)
	(segment
		(start 118.046446 75.8)
		(end 117.798958 76.047487)
		(width 0.15)
		(layer "F.Cu")
		(net 190)
	)
	(segment
		(start 116.278673 78.274882)
		(end 116.031187 78.522369)
		(width 0.15)
		(layer "F.Cu")
		(net 190)
	)
	(segment
		(start 116.349384 77.497061)
		(end 116.101896 77.744548)
		(width 0.15)
		(layer "F.Cu")
		(net 190)
	)
	(segment
		(start 114.652322 79.194123)
		(end 114.404834 79.44161)
		(width 0.15)
		(layer "F.Cu")
		(net 190)
	)
	(segment
		(start 117.975735 76.57782)
		(end 117.728249 76.825307)
		(width 0.15)
		(layer "F.Cu")
		(net 190)
	)
	(segment
		(start 115.500853 78.345592)
		(end 115.253365 78.593079)
		(width 0.15)
		(layer "F.Cu")
		(net 190)
	)
	(segment
		(start 117.127204 77.42635)
		(end 117.127204 77.426351)
		(width 0.15)
		(layer "F.Cu")
		(net 190)
	)
	(segment
		(start 116.101896 77.921325)
		(end 116.278674 78.098104)
		(width 0.15)
		(layer "F.Cu")
		(net 190)
	)
	(segment
		(start 115.005878 79.370901)
		(end 114.829099 79.194123)
		(width 0.15)
		(layer "F.Cu")
		(net 190)
	)
	(segment
		(start 116.278673 78.274881)
		(end 116.278673 78.274882)
		(width 0.15)
		(layer "F.Cu")
		(net 190)
	)
	(segment
		(start 115.500853 78.345593)
		(end 115.500853 78.345592)
		(width 0.15)
		(layer "F.Cu")
		(net 190)
	)
	(segment
		(start 117.798958 76.224264)
		(end 117.975736 76.401042)
		(width 0.15)
		(layer "F.Cu")
		(net 190)
	)
	(segment
		(start 115.253365 78.769855)
		(end 115.253365 78.769856)
		(width 0.15)
		(layer "F.Cu")
		(net 190)
	)
	(segment
		(start 114.652322 79.194124)
		(end 114.652322 79.194123)
		(width 0.15)
		(layer "F.Cu")
		(net 190)
	)
	(segment
		(start 116.950427 77.072793)
		(end 116.950427 77.072794)
		(width 0.15)
		(layer "F.Cu")
		(net 190)
	)
	(segment
		(start 126 75.6)
		(end 118.6 75.6)
		(width 0.15)
		(layer "F.Cu")
		(net 190)
	)
	(segment
		(start 117.197915 76.648531)
		(end 117.197915 76.64853)
		(width 0.15)
		(layer "F.Cu")
		(net 190)
	)
	(segment
		(start 116.101896 77.921324)
		(end 116.101896 77.921325)
		(width 0.15)
		(layer "F.Cu")
		(net 190)
	)
	(segment
		(start 114.404833 79.795164)
		(end 114.404834 79.795163)
		(width 0.15)
		(layer "F.Cu")
		(net 190)
	)
	(segment
		(start 106.5995 92.7645)
		(end 106.5995 92.1)
		(width 0.15)
		(layer "F.Cu")
		(net 190)
	)
	(segment
		(start 114.404834 79.618386)
		(end 114.404834 79.618387)
		(width 0.15)
		(layer "F.Cu")
		(net 190)
	)
	(segment
		(start 107.125 93.29)
		(end 106.5995 92.7645)
		(width 0.15)
		(layer "F.Cu")
		(net 190)
	)
	(segment
		(start 116.950427 77.072794)
		(end 117.127205 77.249573)
		(width 0.15)
		(layer "F.Cu")
		(net 190)
	)
	(segment
		(start 116.349384 77.497062)
		(end 116.349384 77.497061)
		(width 0.15)
		(layer "F.Cu")
		(net 190)
	)
	(segment
		(start 115.854411 78.522369)
		(end 115.854409 78.52237)
		(width 0.15)
		(layer "F.Cu")
		(net 190)
	)
	(via
		(at 127.775 76.8)
		(size 0.4)
		(drill 0.15)
		(layers "F.Cu" "B.Cu")
		(net 190)
	)
	(via
		(at 111.775497 96.45)
		(size 0.4)
		(drill 0.2)
		(layers "F.Cu" "B.Cu")
		(net 190)
	)
	(via
		(at 106.5995 92.1)
		(size 0.4)
		(drill 0.2)
		(layers "F.Cu" "B.Cu")
		(net 190)
	)
	(via
		(at 126 75.6)
		(size 0.4)
		(drill 0.2)
		(layers "F.Cu" "B.Cu")
		(net 190)
	)
	(arc
		(start 117.975736 76.401042)
		(mid 118.012347 76.489431)
		(end 117.975735 76.577819)
		(width 0.15)
		(layer "F.Cu")
		(net 190)
	)
	(arc
		(start 116.526161 77.497061)
		(mid 116.437772 77.46045)
		(end 116.349384 77.497062)
		(width 0.15)
		(layer "F.Cu")
		(net 190)
	)
	(arc
		(start 115.430143 78.946635)
		(mid 115.466754 79.035024)
		(end 115.430142 79.123412)
		(width 0.15)
		(layer "F.Cu")
		(net 190)
	)
	(arc
		(start 118.223223 75.8)
		(mid 118.134835 75.763388)
		(end 118.046446 75.799999)
		(width 0.15)
		(layer "F.Cu")
		(net 190)
	)
	(arc
		(start 114.829099 79.194123)
		(mid 114.74071 79.157512)
		(end 114.652322 79.194124)
		(width 0.15)
		(layer "F.Cu")
		(net 190)
	)
	(arc
		(start 115.253365 78.593079)
		(mid 115.216753 78.681467)
		(end 115.253365 78.769855)
		(width 0.15)
		(layer "F.Cu")
		(net 190)
	)
	(arc
		(start 117.374692 76.64853)
		(mid 117.286303 76.611919)
		(end 117.197915 76.648531)
		(width 0.15)
		(layer "F.Cu")
		(net 190)
	)
	(arc
		(start 117.728249 76.825307)
		(mid 117.639861 76.861919)
		(end 117.551473 76.825307)
		(width 0.15)
		(layer "F.Cu")
		(net 190)
	)
	(arc
		(start 116.101896 77.744548)
		(mid 116.065284 77.832936)
		(end 116.101896 77.921324)
		(width 0.15)
		(layer "F.Cu")
		(net 190)
	)
	(arc
		(start 116.950427 76.896017)
		(mid 116.913815 76.984405)
		(end 116.950427 77.072793)
		(width 0.15)
		(layer "F.Cu")
		(net 190)
	)
	(arc
		(start 115.182656 79.3709)
		(mid 115.094268 79.407512)
		(end 115.00588 79.3709)
		(width 0.15)
		(layer "F.Cu")
		(net 190)
	)
	(arc
		(start 118.4 75.8)
		(mid 118.311611 75.836612)
		(end 118.223222 75.8)
		(width 0.15)
		(layer "F.Cu")
		(net 190)
	)
	(arc
		(start 117.127205 77.249573)
		(mid 117.163816 77.337962)
		(end 117.127204 77.42635)
		(width 0.15)
		(layer "F.Cu")
		(net 190)
	)
	(arc
		(start 114.404834 79.618387)
		(mid 114.441445 79.706776)
		(end 114.404833 79.795164)
		(width 0.15)
		(layer "F.Cu")
		(net 190)
	)
	(arc
		(start 117.798958 76.047487)
		(mid 117.762346 76.135875)
		(end 117.798958 76.224263)
		(width 0.15)
		(layer "F.Cu")
		(net 190)
	)
	(arc
		(start 116.278674 78.098104)
		(mid 116.315285 78.186493)
		(end 116.278673 78.274881)
		(width 0.15)
		(layer "F.Cu")
		(net 190)
	)
	(arc
		(start 114.404834 79.44161)
		(mid 114.368222 79.529998)
		(end 114.404834 79.618386)
		(width 0.15)
		(layer "F.Cu")
		(net 190)
	)
	(arc
		(start 116.879718 77.673838)
		(mid 116.79133 77.71045)
		(end 116.702942 77.673838)
		(width 0.15)
		(layer "F.Cu")
		(net 190)
	)
	(arc
		(start 116.031187 78.522369)
		(mid 115.942799 78.558981)
		(end 115.854411 78.522369)
		(width 0.15)
		(layer "F.Cu")
		(net 190)
	)
	(arc
		(start 115.67763 78.345592)
		(mid 115.589241 78.308981)
		(end 115.500853 78.345593)
		(width 0.15)
		(layer "F.Cu")
		(net 190)
	)
	(segment
		(start 111.775497 96.45)
		(end 111.675 96.550497)
		(width 0.15)
		(layer "B.Cu")
		(net 190)
	)
	(segment
		(start 111.675 96.550497)
		(end 111.675 98.625)
		(width 0.15)
		(layer "B.Cu")
		(net 190)
	)
	(segment
		(start 106.5995 92.1)
		(end 106.4495 91.95)
		(width 0.15)
		(layer "B.Cu")
		(net 190)
	)
	(segment
		(start 106.4495 91.95)
		(end 105.61 91.95)
		(width 0.15)
		(layer "B.Cu")
		(net 190)
	)
	(segment
		(start 126 75.6)
		(end 127.2 76.8)
		(width 0.15)
		(layer "In3.Cu")
		(net 190)
	)
	(segment
		(start 109.125 94.6)
		(end 110.025 95.5)
		(width 0.15)
		(layer "In3.Cu")
		(net 190)
	)
	(segment
		(start 106.5995 92.8245)
		(end 108.375 94.6)
		(width 0.15)
		(layer "In3.Cu")
		(net 190)
	)
	(segment
		(start 106.5995 92.1)
		(end 106.5995 92.8245)
		(width 0.15)
		(layer "In3.Cu")
		(net 190)
	)
	(segment
		(start 127.2 76.8)
		(end 127.775 76.8)
		(width 0.15)
		(layer "In3.Cu")
		(net 190)
	)
	(segment
		(start 110.825497 95.5)
		(end 111.775497 96.45)
		(width 0.15)
		(layer "In3.Cu")
		(net 190)
	)
	(segment
		(start 110.025 95.5)
		(end 110.825497 95.5)
		(width 0.15)
		(layer "In3.Cu")
		(net 190)
	)
	(segment
		(start 108.375 94.6)
		(end 109.125 94.6)
		(width 0.15)
		(layer "In3.Cu")
		(net 190)
	)
	(segment
		(start 126.775 76.2)
		(end 126.4 76.2)
		(width 0.15)
		(layer "F.Cu")
		(net 191)
	)
	(segment
		(start 122.7 76.3)
		(end 122.7 76.2)
		(width 0.15)
		(layer "F.Cu")
		(net 191)
	)
	(segment
		(start 122.6 76)
		(end 122.2 76)
		(width 0.15)
		(layer "F.Cu")
		(net 191)
	)
	(segment
		(start 127.4 75.575)
		(end 126.775 76.2)
		(width 0.15)
		(layer "F.Cu")
		(net 191)
	)
	(segment
		(start 112.275 96.45)
		(end 112.425 96.6)
		(width 0.15)
		(layer "F.Cu")
		(net 191)
	)
	(segment
		(start 122.1 76.1)
		(end 122.1 76.2)
		(width 0.15)
		(layer "F.Cu")
		(net 191)
	)
	(segment
		(start 125 76)
		(end 124.6 76)
		(width 0.15)
		(layer "F.Cu")
		(net 191)
	)
	(segment
		(start 119 76.2)
		(end 120.2 76.2)
		(width 0.15)
		(layer "F.Cu")
		(net 191)
	)
	(segment
		(start 125.6 76.4)
		(end 125.2 76.4)
		(width 0.15)
		(layer "F.Cu")
		(net 191)
	)
	(segment
		(start 120.9 76.1)
		(end 120.9 76.2)
		(width 0.15)
		(layer "F.Cu")
		(net 191)
	)
	(segment
		(start 124.5 76.2)
		(end 124.5 76.3)
		(width 0.15)
		(layer "F.Cu")
		(net 191)
	)
	(segment
		(start 123.3 76.1)
		(end 123.3 76.2)
		(width 0.15)
		(layer "F.Cu")
		(net 191)
	)
	(segment
		(start 107.975 93.35)
		(end 107.975 92.75)
		(width 0.15)
		(layer "F.Cu")
		(net 191)
	)
	(segment
		(start 127.4 75.575)
		(end 127.95 75.575)
		(width 0.09)
		(layer "F.Cu")
		(net 191)
	)
	(segment
		(start 125.7 76.1)
		(end 125.7 76.2)
		(width 0.15)
		(layer "F.Cu")
		(net 191)
	)
	(segment
		(start 127.95 75.575)
		(end 128.125 75.75)
		(width 0.09)
		(layer "F.Cu")
		(net 191)
	)
	(segment
		(start 122.1 76.2)
		(end 122.1 76.3)
		(width 0.15)
		(layer "F.Cu")
		(net 191)
	)
	(segment
		(start 122.7 76.2)
		(end 122.7 76.1)
		(width 0.15)
		(layer "F.Cu")
		(net 191)
	)
	(segment
		(start 123.2 76.4)
		(end 122.8 76.4)
		(width 0.15)
		(layer "F.Cu")
		(net 191)
	)
	(segment
		(start 123.9 76.2)
		(end 123.9 76.1)
		(width 0.15)
		(layer "F.Cu")
		(net 191)
	)
	(segment
		(start 124.5 76.1)
		(end 124.5 76.2)
		(width 0.15)
		(layer "F.Cu")
		(net 191)
	)
	(segment
		(start 121.5 76.3)
		(end 121.5 76.2)
		(width 0.15)
		(layer "F.Cu")
		(net 191)
	)
	(segment
		(start 125.1 76.3)
		(end 125.1 76.2)
		(width 0.15)
		(layer "F.Cu")
		(net 191)
	)
	(segment
		(start 119 76.2)
		(end 108.025 87.175)
		(width 0.15)
		(layer "F.Cu")
		(net 191)
	)
	(segment
		(start 123.9 76.3)
		(end 123.9 76.2)
		(width 0.15)
		(layer "F.Cu")
		(net 191)
	)
	(segment
		(start 128.380025 76.4)
		(end 130.669975 76.4)
		(width 0.09)
		(layer "F.Cu")
		(net 191)
	)
	(segment
		(start 125.1 76.2)
		(end 125.1 76.1)
		(width 0.15)
		(layer "F.Cu")
		(net 191)
	)
	(segment
		(start 122 76.4)
		(end 121.6 76.4)
		(width 0.15)
		(layer "F.Cu")
		(net 191)
	)
	(segment
		(start 121.4 76)
		(end 121 76)
		(width 0.15)
		(layer "F.Cu")
		(net 191)
	)
	(segment
		(start 107.975 92.75)
		(end 108.025 92.7)
		(width 0.15)
		(layer "F.Cu")
		(net 191)
	)
	(segment
		(start 126.2 76)
		(end 125.8 76)
		(width 0.15)
		(layer "F.Cu")
		(net 191)
	)
	(segment
		(start 120.8 76.4)
		(end 120.4 76.4)
		(width 0.15)
		(layer "F.Cu")
		(net 191)
	)
	(segment
		(start 130.669975 76.4)
		(end 130.925 76.655025)
		(width 0.09)
		(layer "F.Cu")
		(net 191)
	)
	(segment
		(start 130.925 77.25)
		(end 130.925 76.655025)
		(width 0.09)
		(layer "F.Cu")
		(net 191)
	)
	(segment
		(start 123.8 76)
		(end 123.4 76)
		(width 0.15)
		(layer "F.Cu")
		(net 191)
	)
	(segment
		(start 124.4 76.4)
		(end 124 76.4)
		(width 0.15)
		(layer "F.Cu")
		(net 191)
	)
	(segment
		(start 112.425 96.6)
		(end 112.425 98.625)
		(width 0.15)
		(layer "F.Cu")
		(net 191)
	)
	(segment
		(start 128.125 76.144975)
		(end 128.380025 76.4)
		(width 0.09)
		(layer "F.Cu")
		(net 191)
	)
	(segment
		(start 120.9 76.2)
		(end 120.9 76.3)
		(width 0.15)
		(layer "F.Cu")
		(net 191)
	)
	(segment
		(start 130.925 77.25)
		(end 131.275 77.6)
		(width 0.09)
		(layer "F.Cu")
		(net 191)
	)
	(segment
		(start 125.7 76.2)
		(end 125.7 76.3)
		(width 0.15)
		(layer "F.Cu")
		(net 191)
	)
	(segment
		(start 123.3 76.2)
		(end 123.3 76.3)
		(width 0.15)
		(layer "F.Cu")
		(net 191)
	)
	(segment
		(start 128.125 75.75)
		(end 128.125 76.144975)
		(width 0.09)
		(layer "F.Cu")
		(net 191)
	)
	(segment
		(start 108.025 87.175)
		(end 108.025 92.7)
		(width 0.15)
		(layer "F.Cu")
		(net 191)
	)
	(segment
		(start 121.5 76.2)
		(end 121.5 76.1)
		(width 0.15)
		(layer "F.Cu")
		(net 191)
	)
	(via
		(at 112.275 96.45)
		(size 0.4)
		(drill 0.2)
		(layers "F.Cu" "B.Cu")
		(net 191)
	)
	(via
		(at 108.025 92.7)
		(size 0.4)
		(drill 0.2)
		(layers "F.Cu" "B.Cu")
		(net 191)
	)
	(arc
		(start 123.9 76.1)
		(mid 123.870711 76.029289)
		(end 123.8 76)
		(width 0.15)
		(layer "F.Cu")
		(net 191)
	)
	(arc
		(start 125.2 76.4)
		(mid 125.129289 76.370711)
		(end 125.1 76.3)
		(width 0.15)
		(layer "F.Cu")
		(net 191)
	)
	(arc
		(start 121 76)
		(mid 120.929289 76.029289)
		(end 120.9 76.1)
		(width 0.15)
		(layer "F.Cu")
		(net 191)
	)
	(arc
		(start 125.7 76.3)
		(mid 125.670711 76.370711)
		(end 125.6 76.4)
		(width 0.15)
		(layer "F.Cu")
		(net 191)
	)
	(arc
		(start 121.6 76.4)
		(mid 121.529289 76.370711)
		(end 121.5 76.3)
		(width 0.15)
		(layer "F.Cu")
		(net 191)
	)
	(arc
		(start 125.8 76)
		(mid 125.729289 76.029289)
		(end 125.7 76.1)
		(width 0.15)
		(layer "F.Cu")
		(net 191)
	)
	(arc
		(start 122.2 76)
		(mid 122.129289 76.029289)
		(end 122.1 76.1)
		(width 0.15)
		(layer "F.Cu")
		(net 191)
	)
	(arc
		(start 123.4 76)
		(mid 123.329289 76.029289)
		(end 123.3 76.1)
		(width 0.15)
		(layer "F.Cu")
		(net 191)
	)
	(arc
		(start 122.8 76.4)
		(mid 122.729289 76.370711)
		(end 122.7 76.3)
		(width 0.15)
		(layer "F.Cu")
		(net 191)
	)
	(arc
		(start 126.3 76.1)
		(mid 126.270711 76.029289)
		(end 126.2 76)
		(width 0.15)
		(layer "F.Cu")
		(net 191)
	)
	(arc
		(start 125.1 76.1)
		(mid 125.070711 76.029289)
		(end 125 76)
		(width 0.15)
		(layer "F.Cu")
		(net 191)
	)
	(arc
		(start 126.4 76.2)
		(mid 126.329289 76.170711)
		(end 126.3 76.1)
		(width 0.15)
		(layer "F.Cu")
		(net 191)
	)
	(arc
		(start 120.9 76.3)
		(mid 120.870711 76.370711)
		(end 120.8 76.4)
		(width 0.15)
		(layer "F.Cu")
		(net 191)
	)
	(arc
		(start 124.5 76.3)
		(mid 124.470711 76.370711)
		(end 124.4 76.4)
		(width 0.15)
		(layer "F.Cu")
		(net 191)
	)
	(arc
		(start 123.3 76.3)
		(mid 123.270711 76.370711)
		(end 123.2 76.4)
		(width 0.15)
		(layer "F.Cu")
		(net 191)
	)
	(arc
		(start 124 76.4)
		(mid 123.929289 76.370711)
		(end 123.9 76.3)
		(width 0.15)
		(layer "F.Cu")
		(net 191)
	)
	(arc
		(start 122.7 76.1)
		(mid 122.670711 76.029289)
		(end 122.6 76)
		(width 0.15)
		(layer "F.Cu")
		(net 191)
	)
	(arc
		(start 122.1 76.3)
		(mid 122.070711 76.370711)
		(end 122 76.4)
		(width 0.15)
		(layer "F.Cu")
		(net 191)
	)
	(arc
		(start 121.5 76.1)
		(mid 121.470711 76.029289)
		(end 121.4 76)
		(width 0.15)
		(layer "F.Cu")
		(net 191)
	)
	(arc
		(start 124.6 76)
		(mid 124.529289 76.029289)
		(end 124.5 76.1)
		(width 0.15)
		(layer "F.Cu")
		(net 191)
	)
	(arc
		(start 120.4 76.4)
		(mid 120.329289 76.370711)
		(end 120.3 76.3)
		(width 0.15)
		(layer "F.Cu")
		(net 191)
	)
	(arc
		(start 120.3 76.3)
		(mid 120.270711 76.229289)
		(end 120.2 76.2)
		(width 0.15)
		(layer "F.Cu")
		(net 191)
	)
	(segment
		(start 107.975 93.35)
		(end 107.975 92.75)
		(width 0.15)
		(layer "B.Cu")
		(net 191)
	)
	(segment
		(start 107.975 92.75)
		(end 108.025 92.7)
		(width 0.15)
		(layer "B.Cu")
		(net 191)
	)
	(segment
		(start 109.675 94.75)
		(end 108.025 93.1)
		(width 0.15)
		(layer "In3.Cu")
		(net 191)
	)
	(segment
		(start 112.275 96.334586)
		(end 110.690414 94.75)
		(width 0.15)
		(layer "In3.Cu")
		(net 191)
	)
	(segment
		(start 110.690414 94.75)
		(end 109.675 94.75)
		(width 0.15)
		(layer "In3.Cu")
		(net 191)
	)
	(segment
		(start 108.025 93.1)
		(end 108.025 92.7)
		(width 0.15)
		(layer "In3.Cu")
		(net 191)
	)
	(segment
		(start 112.275 96.45)
		(end 112.275 96.334586)
		(width 0.15)
		(layer "In3.Cu")
		(net 191)
	)
	(segment
		(start 113.867392 82.191185)
		(end 114.008814 82.332608)
		(width 0.15)
		(layer "F.Cu")
		(net 192)
	)
	(segment
		(start 127.35 76.375)
		(end 127.95 76.375)
		(width 0.09)
		(layer "F.Cu")
		(net 192)
	)
	(segment
		(start 116.130143 80.211282)
		(end 116.130142 80.211281)
		(width 0.15)
		(layer "F.Cu")
		(net 192)
	)
	(segment
		(start 115.281611 81.059812)
		(end 115.140188 80.91839)
		(width 0.15)
		(layer "F.Cu")
		(net 192)
	)
	(segment
		(start 116.130142 80.211281)
		(end 115.988719 80.069859)
		(width 0.15)
		(layer "F.Cu")
		(net 192)
	)
	(segment
		(start 118.675736 77.665689)
		(end 118.675735 77.665688)
		(width 0.15)
		(layer "F.Cu")
		(net 192)
	)
	(segment
		(start 112.736019 83.605406)
		(end 112.736018 83.605405)
		(width 0.15)
		(layer "F.Cu")
		(net 192)
	)
	(segment
		(start 114.433081 81.908344)
		(end 114.43308 81.908343)
		(width 0.15)
		(layer "F.Cu")
		(net 192)
	)
	(segment
		(start 115.847297 80.069859)
		(end 115.564454 80.352701)
		(width 0.15)
		(layer "F.Cu")
		(net 192)
	)
	(segment
		(start 129.975 77.2)
		(end 128.275 77.2)
		(width 0.09)
		(layer "F.Cu")
		(net 192)
	)
	(segment
		(start 117.827205 78.51422)
		(end 117.827204 78.514219)
		(width 0.15)
		(layer "F.Cu")
		(net 192)
	)
	(segment
		(start 114.857345 81.625499)
		(end 114.574502 81.908343)
		(width 0.15)
		(layer "F.Cu")
		(net 192)
	)
	(segment
		(start 115.705876 80.776968)
		(end 115.423033 81.059812)
		(width 0.15)
		(layer "F.Cu")
		(net 192)
	)
	(segment
		(start 113.160283 83.322561)
		(end 112.87744 83.605405)
		(width 0.15)
		(layer "F.Cu")
		(net 192)
	)
	(segment
		(start 113.301704 82.615452)
		(end 113.018861 82.898294)
		(width 0.15)
		(layer "F.Cu")
		(net 192)
	)
	(segment
		(start 130.575 78.4)
		(end 130.225 78.05)
		(width 0.09)
		(layer "F.Cu")
		(net 192)
	)
	(segment
		(start 117.544359 78.372797)
		(end 117.261516 78.655639)
		(width 0.15)
		(layer "F.Cu")
		(net 192)
	)
	(segment
		(start 117.261515 78.79706)
		(end 117.261516 78.797061)
		(width 0.15)
		(layer "F.Cu")
		(net 192)
	)
	(segment
		(start 113.867391 82.191184)
		(end 113.867392 82.191185)
		(width 0.15)
		(layer "F.Cu")
		(net 192)
	)
	(segment
		(start 114.150235 81.766921)
		(end 113.867392 82.049763)
		(width 0.15)
		(layer "F.Cu")
		(net 192)
	)
	(segment
		(start 111.887488 84.453937)
		(end 111.887487 84.453936)
		(width 0.15)
		(layer "F.Cu")
		(net 192)
	)
	(segment
		(start 116.978673 79.36275)
		(end 116.83725 79.221328)
		(width 0.15)
		(layer "F.Cu")
		(net 192)
	)
	(segment
		(start 113.58455 82.756875)
		(end 113.584549 82.756874)
		(width 0.15)
		(layer "F.Cu")
		(net 192)
	)
	(segment
		(start 115.281612 81.059813)
		(end 115.281611 81.059812)
		(width 0.15)
		(layer "F.Cu")
		(net 192)
	)
	(segment
		(start 127.35 76.375)
		(end 126.925 76.8)
		(width 0.15)
		(layer "F.Cu")
		(net 192)
	)
	(segment
		(start 115.564454 80.494123)
		(end 115.705876 80.635546)
		(width 0.15)
		(layer "F.Cu")
		(net 192)
	)
	(segment
		(start 118.675735 77.665688)
		(end 118.534312 77.524266)
		(width 0.15)
		(layer "F.Cu")
		(net 192)
	)
	(segment
		(start 112.170329 83.888246)
		(end 112.17033 83.888247)
		(width 0.15)
		(layer "F.Cu")
		(net 192)
	)
	(segment
		(start 117.402938 79.079906)
		(end 117.120095 79.36275)
		(width 0.15)
		(layer "F.Cu")
		(net 192)
	)
	(segment
		(start 116.554407 79.928437)
		(end 116.271564 80.211281)
		(width 0.15)
		(layer "F.Cu")
		(net 192)
	)
	(segment
		(start 114.715922 81.342653)
		(end 114.715923 81.342654)
		(width 0.15)
		(layer "F.Cu")
		(net 192)
	)
	(segment
		(start 111.746066 84.453937)
		(end 111.746067 84.453935)
		(width 0.15)
		(layer "F.Cu")
		(net 192)
	)
	(segment
		(start 116.412985 79.645592)
		(end 116.554407 79.787015)
		(width 0.15)
		(layer "F.Cu")
		(net 192)
	)
	(segment
		(start 111.746067 84.453935)
		(end 108.575 87.625)
		(width 0.15)
		(layer "F.Cu")
		(net 192)
	)
	(segment
		(start 130.225 78.05)
		(end 130.225 77.45)
		(width 0.09)
		(layer "F.Cu")
		(net 192)
	)
	(segment
		(start 114.008814 82.47403)
		(end 113.725971 82.756874)
		(width 0.15)
		(layer "F.Cu")
		(net 192)
	)
	(segment
		(start 112.311752 84.171092)
		(end 112.028909 84.453936)
		(width 0.15)
		(layer "F.Cu")
		(net 192)
	)
	(segment
		(start 113.584549 82.756874)
		(end 113.443126 82.615452)
		(width 0.15)
		(layer "F.Cu")
		(net 192)
	)
	(segment
		(start 118.110046 77.948529)
		(end 118.110047 77.94853)
		(width 0.15)
		(layer "F.Cu")
		(net 192)
	)
	(segment
		(start 112.17033 83.888247)
		(end 112.311752 84.02967)
		(width 0.15)
		(layer "F.Cu")
		(net 192)
	)
	(segment
		(start 108.575 87.625)
		(end 108.575 92.7)
		(width 0.15)
		(layer "F.Cu")
		(net 192)
	)
	(segment
		(start 119.100001 77.382843)
		(end 119.1 77.382844)
		(width 0.15)
		(layer "F.Cu")
		(net 192)
	)
	(segment
		(start 118.39289 77.524266)
		(end 118.110047 77.807108)
		(width 0.15)
		(layer "F.Cu")
		(net 192)
	)
	(segment
		(start 112.736018 83.605405)
		(end 112.594595 83.463983)
		(width 0.15)
		(layer "F.Cu")
		(net 192)
	)
	(segment
		(start 117.827204 78.514219)
		(end 117.685781 78.372797)
		(width 0.15)
		(layer "F.Cu")
		(net 192)
	)
	(segment
		(start 114.43308 81.908343)
		(end 114.291657 81.766921)
		(width 0.15)
		(layer "F.Cu")
		(net 192)
	)
	(segment
		(start 113.01886 83.039715)
		(end 113.018861 83.039716)
		(width 0.15)
		(layer "F.Cu")
		(net 192)
	)
	(segment
		(start 128.125 76.55)
		(end 128.125 77.05)
		(width 0.09)
		(layer "F.Cu")
		(net 192)
	)
	(segment
		(start 116.412984 79.645591)
		(end 116.412985 79.645592)
		(width 0.15)
		(layer "F.Cu")
		(net 192)
	)
	(segment
		(start 112.453173 83.463983)
		(end 112.17033 83.746825)
		(width 0.15)
		(layer "F.Cu")
		(net 192)
	)
	(segment
		(start 118.110047 77.94853)
		(end 118.251469 78.089953)
		(width 0.15)
		(layer "F.Cu")
		(net 192)
	)
	(segment
		(start 128.125 77.05)
		(end 128.275 77.2)
		(width 0.09)
		(layer "F.Cu")
		(net 192)
	)
	(segment
		(start 115.564453 80.494122)
		(end 115.564454 80.494123)
		(width 0.15)
		(layer "F.Cu")
		(net 192)
	)
	(segment
		(start 114.715923 81.342654)
		(end 114.857345 81.484077)
		(width 0.15)
		(layer "F.Cu")
		(net 192)
	)
	(segment
		(start 126.925 76.8)
		(end 119.4 76.8)
		(width 0.15)
		(layer "F.Cu")
		(net 192)
	)
	(segment
		(start 119.4 76.8)
		(end 119.1 77.1)
		(width 0.15)
		(layer "F.Cu")
		(net 192)
	)
	(segment
		(start 116.978674 79.362751)
		(end 116.978673 79.36275)
		(width 0.15)
		(layer "F.Cu")
		(net 192)
	)
	(segment
		(start 108.6125 92.7375)
		(end 108.6125 93.35)
		(width 0.15)
		(layer "F.Cu")
		(net 192)
	)
	(segment
		(start 114.998766 80.91839)
		(end 114.715923 81.201232)
		(width 0.15)
		(layer "F.Cu")
		(net 192)
	)
	(segment
		(start 117.261516 78.797061)
		(end 117.402938 78.938484)
		(width 0.15)
		(layer "F.Cu")
		(net 192)
	)
	(segment
		(start 116.695828 79.221328)
		(end 116.412985 79.50417)
		(width 0.15)
		(layer "F.Cu")
		(net 192)
	)
	(segment
		(start 118.251469 78.231375)
		(end 117.968626 78.514219)
		(width 0.15)
		(layer "F.Cu")
		(net 192)
	)
	(segment
		(start 108.575 92.7)
		(end 108.6125 92.7375)
		(width 0.15)
		(layer "F.Cu")
		(net 192)
	)
	(segment
		(start 130.225 77.45)
		(end 129.975 77.2)
		(width 0.09)
		(layer "F.Cu")
		(net 192)
	)
	(segment
		(start 119.1 77.382844)
		(end 118.817157 77.665688)
		(width 0.15)
		(layer "F.Cu")
		(net 192)
	)
	(segment
		(start 127.95 76.375)
		(end 128.125 76.55)
		(width 0.09)
		(layer "F.Cu")
		(net 192)
	)
	(segment
		(start 113.018861 83.039716)
		(end 113.160283 83.181139)
		(width 0.15)
		(layer "F.Cu")
		(net 192)
	)
	(via
		(at 108.575 92.7)
		(size 0.4)
		(drill 0.2)
		(layers "F.Cu" "B.Cu")
		(net 192)
	)
	(via
		(at 112.774503 96.45)
		(size 0.4)
		(drill 0.2)
		(layers "F.Cu" "B.Cu")
		(net 192)
	)
	(arc
		(start 114.291657 81.766921)
		(mid 114.220946 81.737632)
		(end 114.150235 81.766921)
		(width 0.15)
		(layer "F.Cu")
		(net 192)
	)
	(arc
		(start 115.564454 80.352701)
		(mid 115.535164 80.423411)
		(end 115.564453 80.494122)
		(width 0.15)
		(layer "F.Cu")
		(net 192)
	)
	(arc
		(start 115.140188 80.91839)
		(mid 115.069477 80.889101)
		(end 114.998766 80.91839)
		(width 0.15)
		(layer "F.Cu")
		(net 192)
	)
	(arc
		(start 115.423033 81.059812)
		(mid 115.352323 81.089102)
		(end 115.281612 81.059813)
		(width 0.15)
		(layer "F.Cu")
		(net 192)
	)
	(arc
		(start 119.1 77.1)
		(mid 119.070711 77.170711)
		(end 119.1 77.241422)
		(width 0.15)
		(layer "F.Cu")
		(net 192)
	)
	(arc
		(start 113.443126 82.615452)
		(mid 113.372415 82.586163)
		(end 113.301704 82.615452)
		(width 0.15)
		(layer "F.Cu")
		(net 192)
	)
	(arc
		(start 115.988719 80.069859)
		(mid 115.918008 80.04057)
		(end 115.847297 80.069859)
		(width 0.15)
		(layer "F.Cu")
		(net 192)
	)
	(arc
		(start 116.83725 79.221328)
		(mid 116.766539 79.192039)
		(end 116.695828 79.221328)
		(width 0.15)
		(layer "F.Cu")
		(net 192)
	)
	(arc
		(start 118.817157 77.665688)
		(mid 118.746447 77.694978)
		(end 118.675736 77.665689)
		(width 0.15)
		(layer "F.Cu")
		(net 192)
	)
	(arc
		(start 117.261516 78.655639)
		(mid 117.232226 78.726349)
		(end 117.261515 78.79706)
		(width 0.15)
		(layer "F.Cu")
		(net 192)
	)
	(arc
		(start 112.594595 83.463983)
		(mid 112.523884 83.434694)
		(end 112.453173 83.463983)
		(width 0.15)
		(layer "F.Cu")
		(net 192)
	)
	(arc
		(start 113.018861 82.898294)
		(mid 112.989571 82.969004)
		(end 113.01886 83.039715)
		(width 0.15)
		(layer "F.Cu")
		(net 192)
	)
	(arc
		(start 119.1 77.241422)
		(mid 119.12929 77.312132)
		(end 119.100001 77.382843)
		(width 0.15)
		(layer "F.Cu")
		(net 192)
	)
	(arc
		(start 113.160283 83.181139)
		(mid 113.189572 83.25185)
		(end 113.160283 83.322561)
		(width 0.15)
		(layer "F.Cu")
		(net 192)
	)
	(arc
		(start 112.311752 84.02967)
		(mid 112.341041 84.100381)
		(end 112.311752 84.171092)
		(width 0.15)
		(layer "F.Cu")
		(net 192)
	)
	(arc
		(start 113.867392 82.049763)
		(mid 113.838102 82.120473)
		(end 113.867391 82.191184)
		(width 0.15)
		(layer "F.Cu")
		(net 192)
	)
	(arc
		(start 112.17033 83.746825)
		(mid 112.14104 83.817535)
		(end 112.170329 83.888246)
		(width 0.15)
		(layer "F.Cu")
		(net 192)
	)
	(arc
		(start 118.251469 78.089953)
		(mid 118.280758 78.160664)
		(end 118.251469 78.231375)
		(width 0.15)
		(layer "F.Cu")
		(net 192)
	)
	(arc
		(start 117.968626 78.514219)
		(mid 117.897916 78.543509)
		(end 117.827205 78.51422)
		(width 0.15)
		(layer "F.Cu")
		(net 192)
	)
	(arc
		(start 115.705876 80.635546)
		(mid 115.735165 80.706257)
		(end 115.705876 80.776968)
		(width 0.15)
		(layer "F.Cu")
		(net 192)
	)
	(arc
		(start 112.87744 83.605405)
		(mid 112.80673 83.634695)
		(end 112.736019 83.605406)
		(width 0.15)
		(layer "F.Cu")
		(net 192)
	)
	(arc
		(start 116.412985 79.50417)
		(mid 116.383695 79.57488)
		(end 116.412984 79.645591)
		(width 0.15)
		(layer "F.Cu")
		(net 192)
	)
	(arc
		(start 111.887487 84.453936)
		(mid 111.816776 84.424647)
		(end 111.746066 84.453937)
		(width 0.15)
		(layer "F.Cu")
		(net 192)
	)
	(arc
		(start 117.402938 78.938484)
		(mid 117.432227 79.009195)
		(end 117.402938 79.079906)
		(width 0.15)
		(layer "F.Cu")
		(net 192)
	)
	(arc
		(start 113.725971 82.756874)
		(mid 113.655261 82.786164)
		(end 113.58455 82.756875)
		(width 0.15)
		(layer "F.Cu")
		(net 192)
	)
	(arc
		(start 114.574502 81.908343)
		(mid 114.503792 81.937633)
		(end 114.433081 81.908344)
		(width 0.15)
		(layer "F.Cu")
		(net 192)
	)
	(arc
		(start 117.120095 79.36275)
		(mid 117.049385 79.39204)
		(end 116.978674 79.362751)
		(width 0.15)
		(layer "F.Cu")
		(net 192)
	)
	(arc
		(start 118.534312 77.524266)
		(mid 118.463601 77.494977)
		(end 118.39289 77.524266)
		(width 0.15)
		(layer "F.Cu")
		(net 192)
	)
	(arc
		(start 116.554407 79.787015)
		(mid 116.583696 79.857726)
		(end 116.554407 79.928437)
		(width 0.15)
		(layer "F.Cu")
		(net 192)
	)
	(arc
		(start 118.110047 77.807108)
		(mid 118.080757 77.877818)
		(end 118.110046 77.948529)
		(width 0.15)
		(layer "F.Cu")
		(net 192)
	)
	(arc
		(start 112.028909 84.453936)
		(mid 111.958199 84.483226)
		(end 111.887488 84.453937)
		(width 0.15)
		(layer "F.Cu")
		(net 192)
	)
	(arc
		(start 114.857345 81.484077)
		(mid 114.886634 81.554788)
		(end 114.857345 81.625499)
		(width 0.15)
		(layer "F.Cu")
		(net 192)
	)
	(arc
		(start 114.715923 81.201232)
		(mid 114.686633 81.271942)
		(end 114.715922 81.342653)
		(width 0.15)
		(layer "F.Cu")
		(net 192)
	)
	(arc
		(start 114.008814 82.332608)
		(mid 114.038103 82.403319)
		(end 114.008814 82.47403)
		(width 0.15)
		(layer "F.Cu")
		(net 192)
	)
	(arc
		(start 116.271564 80.211281)
		(mid 116.200854 80.240571)
		(end 116.130143 80.211282)
		(width 0.15)
		(layer "F.Cu")
		(net 192)
	)
	(arc
		(start 117.685781 78.372797)
		(mid 117.61507 78.343508)
		(end 117.544359 78.372797)
		(width 0.15)
		(layer "F.Cu")
		(net 192)
	)
	(segment
		(start 108.6125 93.35)
		(end 108.6125 92.7375)
		(width 0.15)
		(layer "B.Cu")
		(net 192)
	)
	(segment
		(start 108.6125 92.7375)
		(end 108.575 92.7)
		(width 0.15)
		(layer "B.Cu")
		(net 192)
	)
	(segment
		(start 112.774503 96.45)
		(end 112.675 96.549503)
		(width 0.15)
		(layer "B.Cu")
		(net 192)
	)
	(segment
		(start 112.675 96.549503)
		(end 112.675 98.625)
		(width 0.15)
		(layer "B.Cu")
		(net 192)
	)
	(segment
		(start 109.925 94.4)
		(end 110.925 94.4)
		(width 0.15)
		(layer "In3.Cu")
		(net 192)
	)
	(segment
		(start 108.575 93.05)
		(end 109.925 94.4)
		(width 0.15)
		(layer "In3.Cu")
		(net 192)
	)
	(segment
		(start 108.575 92.7)
		(end 108.575 93.05)
		(width 0.15)
		(layer "In3.Cu")
		(net 192)
	)
	(segment
		(start 112.774503 96.249503)
		(end 112.774503 96.45)
		(width 0.15)
		(layer "In3.Cu")
		(net 192)
	)
	(segment
		(start 110.925 94.4)
		(end 112.774503 96.249503)
		(width 0.15)
		(layer "In3.Cu")
		(net 192)
	)
	(segment
		(start 119.8 77.4)
		(end 119.6 77.6)
		(width 0.15)
		(layer "F.Cu")
		(net 193)
	)
	(segment
		(start 122.95 77.65)
		(end 122.6 77.65)
		(width 0.15)
		(layer "F.Cu")
		(net 193)
	)
	(segment
		(start 114.491138 82.991706)
		(end 114.208295 83.27455)
		(width 0.15)
		(layer "F.Cu")
		(net 193)
	)
	(segment
		(start 117.97365 78.872796)
		(end 117.97365 78.872795)
		(width 0.15)
		(layer "F.Cu")
		(net 193)
	)
	(segment
		(start 118.574693 78.448527)
		(end 118.574693 78.448528)
		(width 0.15)
		(layer "F.Cu")
		(net 193)
	)
	(segment
		(start 122.35 77.15)
		(end 122 77.15)
		(width 0.15)
		(layer "F.Cu")
		(net 193)
	)
	(segment
		(start 126.075 77.4)
		(end 126.075 77.275)
		(width 0.15)
		(layer "F.Cu")
		(net 193)
	)
	(segment
		(start 116.0291 80.994121)
		(end 116.1882 81.153222)
		(width 0.15)
		(layer "F.Cu")
		(net 193)
	)
	(segment
		(start 125.95 77.15)
		(end 125.6 77.15)
		(width 0.15)
		(layer "F.Cu")
		(net 193)
	)
	(segment
		(start 122.475 77.525)
		(end 122.475 77.4)
		(width 0.15)
		(layer "F.Cu")
		(net 193)
	)
	(segment
		(start 123.675 77.525)
		(end 123.675 77.4)
		(width 0.15)
		(layer "F.Cu")
		(net 193)
	)
	(segment
		(start 112.882464 83.963981)
		(end 112.634976 84.211468)
		(width 0.15)
		(layer "F.Cu")
		(net 193)
	)
	(segment
		(start 121.275 77.525)
		(end 121.275 77.4)
		(width 0.15)
		(layer "F.Cu")
		(net 193)
	)
	(segment
		(start 114.915405 82.42602)
		(end 114.915404 82.426019)
		(width 0.15)
		(layer "F.Cu")
		(net 193)
	)
	(segment
		(start 118.309529 79.031896)
		(end 118.309528 79.031895)
		(width 0.15)
		(layer "F.Cu")
		(net 193)
	)
	(segment
		(start 117.125119 79.721327)
		(end 117.125119 79.721326)
		(width 0.15)
		(layer "F.Cu")
		(net 193)
	)
	(segment
		(start 114.579526 82.266919)
		(end 114.332038 82.514406)
		(width 0.15)
		(layer "F.Cu")
		(net 193)
	)
	(segment
		(start 115.763936 81.577489)
		(end 115.763935 81.577488)
		(width 0.15)
		(layer "F.Cu")
		(net 193)
	)
	(segment
		(start 127.15 77.2)
		(end 126.95 77.4)
		(width 0.15)
		(layer "F.Cu")
		(net 193)
	)
	(segment
		(start 124.275 77.275)
		(end 124.275 77.4)
		(width 0.15)
		(layer "F.Cu")
		(net 193)
	)
	(segment
		(start 123.075 77.4)
		(end 123.075 77.525)
		(width 0.15)
		(layer "F.Cu")
		(net 193)
	)
	(segment
		(start 123.55 77.15)
		(end 123.2 77.15)
		(width 0.15)
		(layer "F.Cu")
		(net 193)
	)
	(segment
		(start 112.634976 84.565021)
		(end 112.399999 84.799999)
		(width 0.15)
		(layer "F.Cu")
		(net 193)
	)
	(segment
		(start 117.460997 79.880426)
		(end 117.301896 79.721326)
		(width 0.15)
		(layer "F.Cu")
		(net 193)
	)
	(segment
		(start 127.35 77.2)
		(end 127.15 77.2)
		(width 0.15)
		(layer "F.Cu")
		(net 193)
	)
	(segment
		(start 115.428057 81.418388)
		(end 115.180569 81.665875)
		(width 0.15)
		(layer "F.Cu")
		(net 193)
	)
	(segment
		(start 116.0291 80.99412)
		(end 116.0291 80.994121)
		(width 0.15)
		(layer "F.Cu")
		(net 193)
	)
	(segment
		(start 117.460998 79.880427)
		(end 117.460997 79.880426)
		(width 0.15)
		(layer "F.Cu")
		(net 193)
	)
	(segment
		(start 124.275 77.4)
		(end 124.275 77.525)
		(width 0.15)
		(layer "F.Cu")
		(net 193)
	)
	(segment
		(start 111.834311 85.365684)
		(end 111.834312 85.365684)
		(width 0.15)
		(layer "F.Cu")
		(net 193)
	)
	(segment
		(start 124.75 77.15)
		(end 124.4 77.15)
		(width 0.15)
		(layer "F.Cu")
		(net 193)
	)
	(segment
		(start 115.763935 81.577488)
		(end 115.604834 81.418388)
		(width 0.15)
		(layer "F.Cu")
		(net 193)
	)
	(segment
		(start 113.730995 83.11545)
		(end 113.483507 83.362937)
		(width 0.15)
		(layer "F.Cu")
		(net 193)
	)
	(segment
		(start 117.125119 79.721326)
		(end 116.877631 79.968813)
		(width 0.15)
		(layer "F.Cu")
		(net 193)
	)
	(segment
		(start 113.483507 83.539713)
		(end 113.483507 83.539714)
		(width 0.15)
		(layer "F.Cu")
		(net 193)
	)
	(segment
		(start 126.95 77.4)
		(end 126.8 77.4)
		(width 0.15)
		(layer "F.Cu")
		(net 193)
	)
	(segment
		(start 114.915404 82.426019)
		(end 114.756303 82.266919)
		(width 0.15)
		(layer "F.Cu")
		(net 193)
	)
	(segment
		(start 116.276588 80.569857)
		(end 116.0291 80.817344)
		(width 0.15)
		(layer "F.Cu")
		(net 193)
	)
	(segment
		(start 119.6 77.953555)
		(end 119.6 77.953554)
		(width 0.15)
		(layer "F.Cu")
		(net 193)
	)
	(segment
		(start 116.877631 80.14559)
		(end 117.036731 80.304691)
		(width 0.15)
		(layer "F.Cu")
		(net 193)
	)
	(segment
		(start 127.975 77.2)
		(end 127.35 77.2)
		(width 0.09)
		(layer "F.Cu")
		(net 193)
	)
	(segment
		(start 119.175736 78.201043)
		(end 119.175736 78.201042)
		(width 0.15)
		(layer "F.Cu")
		(net 193)
	)
	(segment
		(start 125.475 77.275)
		(end 125.475 77.4)
		(width 0.15)
		(layer "F.Cu")
		(net 193)
	)
	(segment
		(start 123.075 77.275)
		(end 123.075 77.4)
		(width 0.15)
		(layer "F.Cu")
		(net 193)
	)
	(segment
		(start 126.075 77.525)
		(end 126.075 77.4)
		(width 0.15)
		(layer "F.Cu")
		(net 193)
	)
	(segment
		(start 125.35 77.65)
		(end 125 77.65)
		(width 0.15)
		(layer "F.Cu")
		(net 193)
	)
	(segment
		(start 119.6 77.776778)
		(end 119.599999 77.776778)
		(width 0.15)
		(layer "F.Cu")
		(net 193)
	)
	(segment
		(start 118.822181 78.024265)
		(end 118.822181 78.024264)
		(width 0.15)
		(layer "F.Cu")
		(net 193)
	)
	(segment
		(start 117.036731 80.446113)
		(end 116.753888 80.728957)
		(width 0.15)
		(layer "F.Cu")
		(net 193)
	)
	(segment
		(start 115.339669 82.143175)
		(end 115.056826 82.426019)
		(width 0.15)
		(layer "F.Cu")
		(net 193)
	)
	(segment
		(start 111.834312 85.365684)
		(end 109.125 88.075)
		(width 0.15)
		(layer "F.Cu")
		(net 193)
	)
	(segment
		(start 109.1125 92.7125)
		(end 109.125 92.7)
		(width 0.15)
		(layer "F.Cu")
		(net 193)
	)
	(segment
		(start 122.475 77.4)
		(end 122.475 77.275)
		(width 0.15)
		(layer "F.Cu")
		(net 193)
	)
	(segment
		(start 113.218343 84.123082)
		(end 113.218342 84.123081)
		(width 0.15)
		(layer "F.Cu")
		(net 193)
	)
	(segment
		(start 116.276588 80.569858)
		(end 116.276588 80.569857)
		(width 0.15)
		(layer "F.Cu")
		(net 193)
	)
	(segment
		(start 124.875 77.525)
		(end 124.875 77.4)
		(width 0.15)
		(layer "F.Cu")
		(net 193)
	)
	(segment
		(start 117.726162 79.297058)
		(end 117.726162 79.297059)
		(width 0.15)
		(layer "F.Cu")
		(net 193)
	)
	(segment
		(start 121.15 77.15)
		(end 120.8 77.15)
		(width 0.15)
		(layer "F.Cu")
		(net 193)
	)
	(segment
		(start 118.309528 79.031895)
		(end 118.150427 78.872795)
		(width 0.15)
		(layer "F.Cu")
		(net 193)
	)
	(segment
		(start 114.066873 83.27455)
		(end 113.907772 83.11545)
		(width 0.15)
		(layer "F.Cu")
		(net 193)
	)
	(segment
		(start 114.332038 82.691183)
		(end 114.491138 82.850284)
		(width 0.15)
		(layer "F.Cu")
		(net 193)
	)
	(segment
		(start 113.730995 83.115451)
		(end 113.730995 83.11545)
		(width 0.15)
		(layer "F.Cu")
		(net 193)
	)
	(segment
		(start 121.875 77.4)
		(end 121.875 77.525)
		(width 0.15)
		(layer "F.Cu")
		(net 193)
	)
	(segment
		(start 116.1882 81.294644)
		(end 115.905357 81.577488)
		(width 0.15)
		(layer "F.Cu")
		(net 193)
	)
	(segment
		(start 115.428057 81.418389)
		(end 115.428057 81.418388)
		(width 0.15)
		(layer "F.Cu")
		(net 193)
	)
	(segment
		(start 124.875 77.4)
		(end 124.875 77.275)
		(width 0.15)
		(layer "F.Cu")
		(net 193)
	)
	(segment
		(start 111.834311 85.224262)
		(end 111.834312 85.224263)
		(width 0.15)
		(layer "F.Cu")
		(net 193)
	)
	(segment
		(start 119.175736 78.201042)
		(end 118.998958 78.024264)
		(width 0.15)
		(layer "F.Cu")
		(net 193)
	)
	(segment
		(start 117.97365 78.872795)
		(end 117.726162 79.120282)
		(width 0.15)
		(layer "F.Cu")
		(net 193)
	)
	(segment
		(start 113.483507 83.539714)
		(end 113.642607 83.698815)
		(width 0.15)
		(layer "F.Cu")
		(net 193)
	)
	(segment
		(start 119.6 77.953554)
		(end 119.352512 78.201043)
		(width 0.15)
		(layer "F.Cu")
		(net 193)
	)
	(segment
		(start 113.274006 96.45)
		(end 113.425 96.600994)
		(width 0.15)
		(layer "F.Cu")
		(net 193)
	)
	(segment
		(start 113.425 96.600994)
		(end 113.425 98.625)
		(width 0.15)
		(layer "F.Cu")
		(net 193)
	)
	(segment
		(start 114.579526 82.26692)
		(end 114.579526 82.266919)
		(width 0.15)
		(layer "F.Cu")
		(net 193)
	)
	(segment
		(start 121.875 77.275)
		(end 121.875 77.4)
		(width 0.15)
		(layer "F.Cu")
		(net 193)
	)
	(segment
		(start 112.117156 84.799998)
		(end 112.117155 84.799999)
		(width 0.15)
		(layer "F.Cu")
		(net 193)
	)
	(segment
		(start 112.634976 84.388244)
		(end 112.634976 84.388245)
		(width 0.15)
		(layer "F.Cu")
		(net 193)
	)
	(segment
		(start 116.877631 80.145589)
		(end 116.877631 80.14559)
		(width 0.15)
		(layer "F.Cu")
		(net 193)
	)
	(segment
		(start 115.180569 81.842652)
		(end 115.339669 82.001753)
		(width 0.15)
		(layer "F.Cu")
		(net 193)
	)
	(segment
		(start 121.75 77.65)
		(end 121.4 77.65)
		(width 0.15)
		(layer "F.Cu")
		(net 193)
	)
	(segment
		(start 112.634975 84.565022)
		(end 112.634976 84.565021)
		(width 0.15)
		(layer "F.Cu")
		(net 193)
	)
	(segment
		(start 116.612467 80.728958)
		(end 116.612466 80.728957)
		(width 0.15)
		(layer "F.Cu")
		(net 193)
	)
	(segment
		(start 114.332038 82.691182)
		(end 114.332038 82.691183)
		(width 0.15)
		(layer "F.Cu")
		(net 193)
	)
	(segment
		(start 116.612466 80.728957)
		(end 116.453365 80.569857)
		(width 0.15)
		(layer "F.Cu")
		(net 193)
	)
	(segment
		(start 118.574693 78.448528)
		(end 118.733793 78.607629)
		(width 0.15)
		(layer "F.Cu")
		(net 193)
	)
	(segment
		(start 125.475 77.4)
		(end 125.475 77.525)
		(width 0.15)
		(layer "F.Cu")
		(net 193)
	)
	(segment
		(start 113.218342 84.123081)
		(end 113.059241 83.963981)
		(width 0.15)
		(layer "F.Cu")
		(net 193)
	)
	(segment
		(start 112.117155 84.799999)
		(end 111.834312 85.082841)
		(width 0.15)
		(layer "F.Cu")
		(net 193)
	)
	(segment
		(start 118.733793 78.749051)
		(end 118.45095 79.031895)
		(width 0.15)
		(layer "F.Cu")
		(net 193)
	)
	(segment
		(start 114.066874 83.274551)
		(end 114.066873 83.27455)
		(width 0.15)
		(layer "F.Cu")
		(net 193)
	)
	(segment
		(start 117.885262 79.597582)
		(end 117.602419 79.880426)
		(width 0.15)
		(layer "F.Cu")
		(net 193)
	)
	(segment
		(start 124.15 77.65)
		(end 123.8 77.65)
		(width 0.15)
		(layer "F.Cu")
		(net 193)
	)
	(segment
		(start 109.1125 93.35)
		(end 109.1125 92.7125)
		(width 0.15)
		(layer "F.Cu")
		(net 193)
	)
	(segment
		(start 120.55 77.4)
		(end 119.8 77.4)
		(width 0.15)
		(layer "F.Cu")
		(net 193)
	)
	(segment
		(start 115.180569 81.842651)
		(end 115.180569 81.842652)
		(width 0.15)
		(layer "F.Cu")
		(net 193)
	)
	(segment
		(start 113.642607 83.840237)
		(end 113.359764 84.123081)
		(width 0.15)
		(layer "F.Cu")
		(net 193)
	)
	(segment
		(start 121.275 77.4)
		(end 121.275 77.275)
		(width 0.15)
		(layer "F.Cu")
		(net 193)
	)
	(segment
		(start 128.475 77.6)
		(end 128.375 77.6)
		(width 0.09)
		(layer "F.Cu")
		(net 193)
	)
	(segment
		(start 128.375 77.6)
		(end 127.975 77.2)
		(width 0.09)
		(layer "F.Cu")
		(net 193)
	)
	(segment
		(start 118.822181 78.024264)
		(end 118.574693 78.271751)
		(width 0.15)
		(layer "F.Cu")
		(net 193)
	)
	(segment
		(start 112.882464 83.963982)
		(end 112.882464 83.963981)
		(width 0.15)
		(layer "F.Cu")
		(net 193)
	)
	(segment
		(start 109.125 88.075)
		(end 109.125 92.7)
		(width 0.15)
		(layer "F.Cu")
		(net 193)
	)
	(segment
		(start 117.726162 79.297059)
		(end 117.885262 79.45616)
		(width 0.15)
		(layer "F.Cu")
		(net 193)
	)
	(segment
		(start 123.675 77.4)
		(end 123.675 77.275)
		(width 0.15)
		(layer "F.Cu")
		(net 193)
	)
	(segment
		(start 126.55 77.65)
		(end 126.2 77.65)
		(width 0.15)
		(layer "F.Cu")
		(net 193)
	)
	(via
		(at 113.274006 96.45)
		(size 0.4)
		(drill 0.2)
		(layers "F.Cu" "B.Cu")
		(net 193)
	)
	(via
		(at 109.125 92.7)
		(size 0.4)
		(drill 0.2)
		(layers "F.Cu" "B.Cu")
		(net 193)
	)
	(arc
		(start 112.258577 84.799999)
		(mid 112.187867 84.770709)
		(end 112.117156 84.799998)
		(width 0.15)
		(layer "F.Cu")
		(net 193)
	)
	(arc
		(start 125.475 77.525)
		(mid 125.438388 77.613388)
		(end 125.35 77.65)
		(width 0.15)
		(layer "F.Cu")
		(net 193)
	)
	(arc
		(start 118.733793 78.607629)
		(mid 118.763082 78.67834)
		(end 118.733793 78.749051)
		(width 0.15)
		(layer "F.Cu")
		(net 193)
	)
	(arc
		(start 116.453365 80.569857)
		(mid 116.364976 80.533246)
		(end 116.276588 80.569858)
		(width 0.15)
		(layer "F.Cu")
		(net 193)
	)
	(arc
		(start 119.6 77.6)
		(mid 119.563387 77.68839)
		(end 119.6 77.776778)
		(width 0.15)
		(layer "F.Cu")
		(net 193)
	)
	(arc
		(start 113.059241 83.963981)
		(mid 112.970852 83.92737)
		(end 112.882464 83.963982)
		(width 0.15)
		(layer "F.Cu")
		(net 193)
	)
	(arc
		(start 114.332038 82.514406)
		(mid 114.295426 82.602794)
		(end 114.332038 82.691182)
		(width 0.15)
		(layer "F.Cu")
		(net 193)
	)
	(arc
		(start 124.275 77.525)
		(mid 124.238388 77.613388)
		(end 124.15 77.65)
		(width 0.15)
		(layer "F.Cu")
		(net 193)
	)
	(arc
		(start 113.642607 83.698815)
		(mid 113.671896 83.769526)
		(end 113.642607 83.840237)
		(width 0.15)
		(layer "F.Cu")
		(net 193)
	)
	(arc
		(start 117.602419 79.880426)
		(mid 117.531709 79.909716)
		(end 117.460998 79.880427)
		(width 0.15)
		(layer "F.Cu")
		(net 193)
	)
	(arc
		(start 118.150427 78.872795)
		(mid 118.062038 78.836184)
		(end 117.97365 78.872796)
		(width 0.15)
		(layer "F.Cu")
		(net 193)
	)
	(arc
		(start 126.8 77.4)
		(mid 126.711612 77.436612)
		(end 126.675 77.525)
		(width 0.15)
		(layer "F.Cu")
		(net 193)
	)
	(arc
		(start 120.675 77.275)
		(mid 120.638388 77.363388)
		(end 120.55 77.4)
		(width 0.15)
		(layer "F.Cu")
		(net 193)
	)
	(arc
		(start 124.875 77.275)
		(mid 124.838388 77.186612)
		(end 124.75 77.15)
		(width 0.15)
		(layer "F.Cu")
		(net 193)
	)
	(arc
		(start 112.634976 84.388245)
		(mid 112.671587 84.476634)
		(end 112.634975 84.565022)
		(width 0.15)
		(layer "F.Cu")
		(net 193)
	)
	(arc
		(start 111.834312 85.082841)
		(mid 111.805022 85.153551)
		(end 111.834311 85.224262)
		(width 0.15)
		(layer "F.Cu")
		(net 193)
	)
	(arc
		(start 125.6 77.15)
		(mid 125.511612 77.186612)
		(end 125.475 77.275)
		(width 0.15)
		(layer "F.Cu")
		(net 193)
	)
	(arc
		(start 115.604834 81.418388)
		(mid 115.516445 81.381777)
		(end 115.428057 81.418389)
		(width 0.15)
		(layer "F.Cu")
		(net 193)
	)
	(arc
		(start 116.877631 79.968813)
		(mid 116.841019 80.057201)
		(end 116.877631 80.145589)
		(width 0.15)
		(layer "F.Cu")
		(net 193)
	)
	(arc
		(start 113.907772 83.11545)
		(mid 113.819383 83.078839)
		(end 113.730995 83.115451)
		(width 0.15)
		(layer "F.Cu")
		(net 193)
	)
	(arc
		(start 116.1882 81.153222)
		(mid 116.217489 81.223933)
		(end 116.1882 81.294644)
		(width 0.15)
		(layer "F.Cu")
		(net 193)
	)
	(arc
		(start 117.726162 79.120282)
		(mid 117.68955 79.20867)
		(end 117.726162 79.297058)
		(width 0.15)
		(layer "F.Cu")
		(net 193)
	)
	(arc
		(start 123.8 77.65)
		(mid 123.711612 77.613388)
		(end 123.675 77.525)
		(width 0.15)
		(layer "F.Cu")
		(net 193)
	)
	(arc
		(start 122.6 77.65)
		(mid 122.511612 77.613388)
		(end 122.475 77.525)
		(width 0.15)
		(layer "F.Cu")
		(net 193)
	)
	(arc
		(start 114.208295 83.27455)
		(mid 114.137585 83.30384)
		(end 114.066874 83.274551)
		(width 0.15)
		(layer "F.Cu")
		(net 193)
	)
	(arc
		(start 117.036731 80.304691)
		(mid 117.06602 80.375402)
		(end 117.036731 80.446113)
		(width 0.15)
		(layer "F.Cu")
		(net 193)
	)
	(arc
		(start 119.352512 78.201043)
		(mid 119.264124 78.237655)
		(end 119.175736 78.201043)
		(width 0.15)
		(layer "F.Cu")
		(net 193)
	)
	(arc
		(start 126.675 77.525)
		(mid 126.638388 77.613388)
		(end 126.55 77.65)
		(width 0.15)
		(layer "F.Cu")
		(net 193)
	)
	(arc
		(start 113.483507 83.362937)
		(mid 113.446895 83.451325)
		(end 113.483507 83.539713)
		(width 0.15)
		(layer "F.Cu")
		(net 193)
	)
	(arc
		(start 113.359764 84.123081)
		(mid 113.289054 84.152371)
		(end 113.218343 84.123082)
		(width 0.15)
		(layer "F.Cu")
		(net 193)
	)
	(arc
		(start 112.634976 84.211468)
		(mid 112.598364 84.299856)
		(end 112.634976 84.388244)
		(width 0.15)
		(layer "F.Cu")
		(net 193)
	)
	(arc
		(start 118.998958 78.024264)
		(mid 118.910569 77.987653)
		(end 118.822181 78.024265)
		(width 0.15)
		(layer "F.Cu")
		(net 193)
	)
	(arc
		(start 114.756303 82.266919)
		(mid 114.667914 82.230308)
		(end 114.579526 82.26692)
		(width 0.15)
		(layer "F.Cu")
		(net 193)
	)
	(arc
		(start 118.45095 79.031895)
		(mid 118.38024 79.061185)
		(end 118.309529 79.031896)
		(width 0.15)
		(layer "F.Cu")
		(net 193)
	)
	(arc
		(start 122.475 77.275)
		(mid 122.438388 77.186612)
		(end 122.35 77.15)
		(width 0.15)
		(layer "F.Cu")
		(net 193)
	)
	(arc
		(start 112.399999 84.799999)
		(mid 112.329288 84.829288)
		(end 112.258577 84.799999)
		(width 0.15)
		(layer "F.Cu")
		(net 193)
	)
	(arc
		(start 117.885262 79.45616)
		(mid 117.914551 79.526871)
		(end 117.885262 79.597582)
		(width 0.15)
		(layer "F.Cu")
		(net 193)
	)
	(arc
		(start 115.339669 82.001753)
		(mid 115.368958 82.072464)
		(end 115.339669 82.143175)
		(width 0.15)
		(layer "F.Cu")
		(net 193)
	)
	(arc
		(start 114.491138 82.850284)
		(mid 114.520427 82.920995)
		(end 114.491138 82.991706)
		(width 0.15)
		(layer "F.Cu")
		(net 193)
	)
	(arc
		(start 123.2 77.15)
		(mid 123.111612 77.186612)
		(end 123.075 77.275)
		(width 0.15)
		(layer "F.Cu")
		(net 193)
	)
	(arc
		(start 121.875 77.525)
		(mid 121.838388 77.613388)
		(end 121.75 77.65)
		(width 0.15)
		(layer "F.Cu")
		(net 193)
	)
	(arc
		(start 115.056826 82.426019)
		(mid 114.986116 82.455309)
		(end 114.915405 82.42602)
		(width 0.15)
		(layer "F.Cu")
		(net 193)
	)
	(arc
		(start 111.834312 85.224263)
		(mid 111.863601 85.294974)
		(end 111.834311 85.365684)
		(width 0.15)
		(layer "F.Cu")
		(net 193)
	)
	(arc
		(start 126.2 77.65)
		(mid 126.111612 77.613388)
		(end 126.075 77.525)
		(width 0.15)
		(layer "F.Cu")
		(net 193)
	)
	(arc
		(start 123.075 77.525)
		(mid 123.038388 77.613388)
		(end 122.95 77.65)
		(width 0.15)
		(layer "F.Cu")
		(net 193)
	)
	(arc
		(start 117.301896 79.721326)
		(mid 117.213507 79.684715)
		(end 117.125119 79.721327)
		(width 0.15)
		(layer "F.Cu")
		(net 193)
	)
	(arc
		(start 120.8 77.15)
		(mid 120.711612 77.186612)
		(end 120.675 77.275)
		(width 0.15)
		(layer "F.Cu")
		(net 193)
	)
	(arc
		(start 124.4 77.15)
		(mid 124.311612 77.186612)
		(end 124.275 77.275)
		(width 0.15)
		(layer "F.Cu")
		(net 193)
	)
	(arc
		(start 123.675 77.275)
		(mid 123.638388 77.186612)
		(end 123.55 77.15)
		(width 0.15)
		(layer "F.Cu")
		(net 193)
	)
	(arc
		(start 119.599999 77.776778)
		(mid 119.636611 77.865166)
		(end 119.6 77.953555)
		(width 0.15)
		(layer "F.Cu")
		(net 193)
	)
	(arc
		(start 122 77.15)
		(mid 121.911612 77.186612)
		(end 121.875 77.275)
		(width 0.15)
		(layer "F.Cu")
		(net 193)
	)
	(arc
		(start 116.753888 80.728957)
		(mid 116.683178 80.758247)
		(end 116.612467 80.728958)
		(width 0.15)
		(layer "F.Cu")
		(net 193)
	)
	(arc
		(start 121.275 77.275)
		(mid 121.238388 77.186612)
		(end 121.15 77.15)
		(width 0.15)
		(layer "F.Cu")
		(net 193)
	)
	(arc
		(start 115.180569 81.665875)
		(mid 115.143957 81.754263)
		(end 115.180569 81.842651)
		(width 0.15)
		(layer "F.Cu")
		(net 193)
	)
	(arc
		(start 118.574693 78.271751)
		(mid 118.538081 78.360139)
		(end 118.574693 78.448527)
		(width 0.15)
		(layer "F.Cu")
		(net 193)
	)
	(arc
		(start 116.0291 80.817344)
		(mid 115.992488 80.905732)
		(end 116.0291 80.99412)
		(width 0.15)
		(layer "F.Cu")
		(net 193)
	)
	(arc
		(start 115.905357 81.577488)
		(mid 115.834647 81.606778)
		(end 115.763936 81.577489)
		(width 0.15)
		(layer "F.Cu")
		(net 193)
	)
	(arc
		(start 126.075 77.275)
		(mid 126.038388 77.186612)
		(end 125.95 77.15)
		(width 0.15)
		(layer "F.Cu")
		(net 193)
	)
	(arc
		(start 125 77.65)
		(mid 124.911612 77.613388)
		(end 124.875 77.525)
		(width 0.15)
		(layer "F.Cu")
		(net 193)
	)
	(arc
		(start 121.4 77.65)
		(mid 121.311612 77.613388)
		(end 121.275 77.525)
		(width 0.15)
		(layer "F.Cu")
		(net 193)
	)
	(segment
		(start 109.1125 92.7125)
		(end 109.125 92.7)
		(width 0.15)
		(layer "B.Cu")
		(net 193)
	)
	(segment
		(start 109.1125 93.35)
		(end 109.1125 92.7125)
		(width 0.15)
		(layer "B.Cu")
		(net 193)
	)
	(segment
		(start 113.274006 96.45)
		(end 113.274006 96.199006)
		(width 0.15)
		(layer "In3.Cu")
		(net 193)
	)
	(segment
		(start 109.125 93)
		(end 109.125 92.7)
		(width 0.15)
		(layer "In3.Cu")
		(net 193)
	)
	(segment
		(start 113.274006 96.199006)
		(end 111.125 94.05)
		(width 0.15)
		(layer "In3.Cu")
		(net 193)
	)
	(segment
		(start 110.175 94.05)
		(end 109.125 93)
		(width 0.15)
		(layer "In3.Cu")
		(net 193)
	)
	(segment
		(start 111.125 94.05)
		(end 110.175 94.05)
		(width 0.15)
		(layer "In3.Cu")
		(net 193)
	)
	(segment
		(start 119.039335 78.94853)
		(end 119.145401 79.054596)
		(width 0.15)
		(layer "F.Cu")
		(net 194)
	)
	(segment
		(start 117.554407 81.069859)
		(end 117.342274 81.281993)
		(width 0.15)
		(layer "F.Cu")
		(net 194)
	)
	(segment
		(start 114.160282 83.615452)
		(end 113.948149 83.827584)
		(width 0.15)
		(layer "F.Cu")
		(net 194)
	)
	(segment
		(start 115.008814 83.615452)
		(end 114.796681 83.827586)
		(width 0.15)
		(layer "F.Cu")
		(net 194)
	)
	(segment
		(start 113.311751 85.312515)
		(end 113.311752 85.312514)
		(width 0.15)
		(layer "F.Cu")
		(net 194)
	)
	(segment
		(start 110.341895 87.858108)
		(end 109.675 88.525)
		(width 0.15)
		(layer "F.Cu")
		(net 194)
	)
	(segment
		(start 113.736018 84.676117)
		(end 113.629952 84.570051)
		(width 0.15)
		(layer "F.Cu")
		(net 194)
	)
	(segment
		(start 114.478483 83.72152)
		(end 114.372414 83.615452)
		(width 0.15)
		(layer "F.Cu")
		(net 194)
	)
	(segment
		(start 118.402937 80.221329)
		(end 118.402938 80.221328)
		(width 0.15)
		(layer "F.Cu")
		(net 194)
	)
	(segment
		(start 111.402558 87.009577)
		(end 111.296492 86.903511)
		(width 0.15)
		(layer "F.Cu")
		(net 194)
	)
	(segment
		(start 116.705874 81.06986)
		(end 116.705875 81.069859)
		(width 0.15)
		(layer "F.Cu")
		(net 194)
	)
	(segment
		(start 114.79668 83.191185)
		(end 114.902746 83.297251)
		(width 0.15)
		(layer "F.Cu")
		(net 194)
	)
	(segment
		(start 117.554406 80.221328)
		(end 117.342273 80.43346)
		(width 0.15)
		(layer "F.Cu")
		(net 194)
	)
	(segment
		(start 120.1 78.524266)
		(end 119.887867 78.7364)
		(width 0.15)
		(layer "F.Cu")
		(net 194)
	)
	(segment
		(start 115.327014 82.872989)
		(end 115.220945 82.766921)
		(width 0.15)
		(layer "F.Cu")
		(net 194)
	)
	(segment
		(start 109.675 88.525)
		(end 109.675 92.7)
		(width 0.15)
		(layer "F.Cu")
		(net 194)
	)
	(segment
		(start 110.766158 87.221707)
		(end 110.872224 87.327773)
		(width 0.15)
		(layer "F.Cu")
		(net 194)
	)
	(segment
		(start 110.978291 86.797443)
		(end 110.766158 87.009575)
		(width 0.15)
		(layer "F.Cu")
		(net 194)
	)
	(segment
		(start 115.857345 82.766921)
		(end 115.645212 82.979055)
		(width 0.15)
		(layer "F.Cu")
		(net 194)
	)
	(segment
		(start 111.296492 86.903511)
		(end 111.190423 86.797443)
		(width 0.15)
		(layer "F.Cu")
		(net 194)
	)
	(segment
		(start 118.402936 79.372798)
		(end 118.402937 79.372797)
		(width 0.15)
		(layer "F.Cu")
		(net 194)
	)
	(segment
		(start 118.721138 79.478865)
		(end 118.615069 79.372797)
		(width 0.15)
		(layer "F.Cu")
		(net 194)
	)
	(segment
		(start 117.130142 81.281993)
		(end 117.024076 81.175927)
		(width 0.15)
		(layer "F.Cu")
		(net 194)
	)
	(segment
		(start 119.569669 78.630334)
		(end 119.4636 78.524266)
		(width 0.15)
		(layer "F.Cu")
		(net 194)
	)
	(segment
		(start 120.1 78.524267)
		(end 120.1 78.524266)
		(width 0.15)
		(layer "F.Cu")
		(net 194)
	)
	(segment
		(start 117.872607 80.327396)
		(end 117.766538 80.221328)
		(width 0.15)
		(layer "F.Cu")
		(net 194)
	)
	(segment
		(start 119.145401 79.054596)
		(end 119.251469 79.160665)
		(width 0.15)
		(layer "F.Cu")
		(net 194)
	)
	(segment
		(start 117.554406 81.06986)
		(end 117.554407 81.069859)
		(width 0.15)
		(layer "F.Cu")
		(net 194)
	)
	(segment
		(start 118.402937 79.372797)
		(end 118.190804 79.584929)
		(width 0.15)
		(layer "F.Cu")
		(net 194)
	)
	(segment
		(start 110.978291 87.645975)
		(end 110.978292 87.645974)
		(width 0.15)
		(layer "F.Cu")
		(net 194)
	)
	(segment
		(start 114.160281 83.615453)
		(end 114.160282 83.615452)
		(width 0.15)
		(layer "F.Cu")
		(net 194)
	)
	(segment
		(start 112.251087 85.94891)
		(end 112.251088 85.948912)
		(width 0.15)
		(layer "F.Cu")
		(net 194)
	)
	(segment
		(start 112.038954 85.948912)
		(end 112.038955 85.948912)
		(width 0.15)
		(layer "F.Cu")
		(net 194)
	)
	(segment
		(start 117.448339 80.751658)
		(end 117.554407 80.857727)
		(width 0.15)
		(layer "F.Cu")
		(net 194)
	)
	(segment
		(start 116.493742 81.494123)
		(end 116.599808 81.600189)
		(width 0.15)
		(layer "F.Cu")
		(net 194)
	)
	(segment
		(start 125.968916 77.996)
		(end 125.964916 78)
		(width 0.15)
		(layer "F.Cu")
		(net 194)
	)
	(segment
		(start 112.887487 85.524648)
		(end 112.781421 85.418582)
		(width 0.15)
		(layer "F.Cu")
		(net 194)
	)
	(segment
		(start 116.281611 82.130524)
		(end 116.175545 82.024458)
		(width 0.15)
		(layer "F.Cu")
		(net 194)
	)
	(segment
		(start 115.645211 82.342654)
		(end 115.751277 82.44872)
		(width 0.15)
		(layer "F.Cu")
		(net 194)
	)
	(segment
		(start 118.402938 80.221328)
		(end 118.190805 80.433462)
		(width 0.15)
		(layer "F.Cu")
		(net 194)
	)
	(segment
		(start 113.31175 84.463984)
		(end 113.311751 84.463983)
		(width 0.15)
		(layer "F.Cu")
		(net 194)
	)
	(segment
		(start 116.175545 82.024458)
		(end 116.069476 81.91839)
		(width 0.15)
		(layer "F.Cu")
		(net 194)
	)
	(segment
		(start 127.521 77.996)
		(end 125.968916 77.996)
		(width 0.15)
		(layer "F.Cu")
		(net 194)
	)
	(segment
		(start 114.584549 83.827586)
		(end 114.478483 83.72152)
		(width 0.15)
		(layer "F.Cu")
		(net 194)
	)
	(segment
		(start 127.55 78.025)
		(end 127.521 77.996)
		(width 0.15)
		(layer "F.Cu")
		(net 194)
	)
	(segment
		(start 113.311752 85.312514)
		(end 113.099619 85.524648)
		(width 0.15)
		(layer "F.Cu")
		(net 194)
	)
	(segment
		(start 113.099618 84.888247)
		(end 113.205684 84.994313)
		(width 0.15)
		(layer "F.Cu")
		(net 194)
	)
	(segment
		(start 114.054215 84.145782)
		(end 114.160283 84.251851)
		(width 0.15)
		(layer "F.Cu")
		(net 194)
	)
	(segment
		(start 112.463219 85.312515)
		(end 112.46322 85.312514)
		(width 0.15)
		(layer "F.Cu")
		(net 194)
	)
	(segment
		(start 114.160282 84.463984)
		(end 114.160283 84.463983)
		(width 0.15)
		(layer "F.Cu")
		(net 194)
	)
	(segment
		(start 110.872224 87.327773)
		(end 110.978292 87.433842)
		(width 0.15)
		(layer "F.Cu")
		(net 194)
	)
	(segment
		(start 115.857344 81.91839)
		(end 115.645211 82.130522)
		(width 0.15)
		(layer "F.Cu")
		(net 194)
	)
	(segment
		(start 112.781421 85.418582)
		(end 112.675352 85.312514)
		(width 0.15)
		(layer "F.Cu")
		(net 194)
	)
	(segment
		(start 125.964916 78)
		(end 120.2 78)
		(width 0.15)
		(layer "F.Cu")
		(net 194)
	)
	(segment
		(start 110.341894 87.858109)
		(end 110.341895 87.858108)
		(width 0.15)
		(layer "F.Cu")
		(net 194)
	)
	(segment
		(start 113.948149 84.039716)
		(end 114.054215 84.145782)
		(width 0.15)
		(layer "F.Cu")
		(net 194)
	)
	(segment
		(start 119.251467 78.524267)
		(end 119.251468 78.524266)
		(width 0.15)
		(layer "F.Cu")
		(net 194)
	)
	(segment
		(start 115.008813 83.615453)
		(end 115.008814 83.615452)
		(width 0.15)
		(layer "F.Cu")
		(net 194)
	)
	(segment
		(start 113.629952 84.570051)
		(end 113.523883 84.463983)
		(width 0.15)
		(layer "F.Cu")
		(net 194)
	)
	(segment
		(start 111.826823 86.797443)
		(end 111.61469 87.009577)
		(width 0.15)
		(layer "F.Cu")
		(net 194)
	)
	(segment
		(start 116.705876 81.91839)
		(end 116.493743 82.130524)
		(width 0.15)
		(layer "F.Cu")
		(net 194)
	)
	(segment
		(start 113.311751 84.463983)
		(end 113.099618 84.676115)
		(width 0.15)
		(layer "F.Cu")
		(net 194)
	)
	(segment
		(start 120.1 78.312134)
		(end 120.099999 78.312134)
		(width 0.15)
		(layer "F.Cu")
		(net 194)
	)
	(segment
		(start 116.599808 81.600189)
		(end 116.705876 81.706258)
		(width 0.15)
		(layer "F.Cu")
		(net 194)
	)
	(segment
		(start 110.97829 86.797444)
		(end 110.978291 86.797443)
		(width 0.15)
		(layer "F.Cu")
		(net 194)
	)
	(segment
		(start 119.251468 79.372798)
		(end 119.251469 79.372797)
		(width 0.15)
		(layer "F.Cu")
		(net 194)
	)
	(segment
		(start 115.751277 82.44872)
		(end 115.857345 82.554789)
		(width 0.15)
		(layer "F.Cu")
		(net 194)
	)
	(segment
		(start 112.251086 85.948911)
		(end 112.251087 85.94891)
		(width 0.15)
		(layer "F.Cu")
		(net 194)
	)
	(segment
		(start 116.705875 81.069859)
		(end 116.493742 81.281991)
		(width 0.15)
		(layer "F.Cu")
		(net 194)
	)
	(segment
		(start 117.978673 80.433462)
		(end 117.872607 80.327396)
		(width 0.15)
		(layer "F.Cu")
		(net 194)
	)
	(segment
		(start 119.251469 79.372797)
		(end 119.039336 79.584931)
		(width 0.15)
		(layer "F.Cu")
		(net 194)
	)
	(segment
		(start 111.826822 85.948911)
		(end 111.826822 85.948912)
		(width 0.15)
		(layer "F.Cu")
		(net 194)
	)
	(segment
		(start 115.008812 82.766922)
		(end 115.008813 82.766921)
		(width 0.15)
		(layer "F.Cu")
		(net 194)
	)
	(segment
		(start 127.55 78.025)
		(end 128.8 78.025)
		(width 0.09)
		(layer "F.Cu")
		(net 194)
	)
	(segment
		(start 109.75 92.775)
		(end 109.75 93.35)
		(width 0.15)
		(layer "F.Cu")
		(net 194)
	)
	(segment
		(start 117.554405 80.221329)
		(end 117.554406 80.221328)
		(width 0.15)
		(layer "F.Cu")
		(net 194)
	)
	(segment
		(start 118.827204 79.584931)
		(end 118.721138 79.478865)
		(width 0.15)
		(layer "F.Cu")
		(net 194)
	)
	(segment
		(start 117.342273 80.645592)
		(end 117.448339 80.751658)
		(width 0.15)
		(layer "F.Cu")
		(net 194)
	)
	(segment
		(start 120.2 78)
		(end 120.1 78.1)
		(width 0.15)
		(layer "F.Cu")
		(net 194)
	)
	(segment
		(start 118.190804 79.797061)
		(end 118.29687 79.903127)
		(width 0.15)
		(layer "F.Cu")
		(net 194)
	)
	(segment
		(start 118.29687 79.903127)
		(end 118.402938 80.009196)
		(width 0.15)
		(layer "F.Cu")
		(net 194)
	)
	(segment
		(start 119.675735 78.7364)
		(end 119.569669 78.630334)
		(width 0.15)
		(layer "F.Cu")
		(net 194)
	)
	(segment
		(start 116.705875 81.918391)
		(end 116.705876 81.91839)
		(width 0.15)
		(layer "F.Cu")
		(net 194)
	)
	(segment
		(start 111.720755 86.479242)
		(end 111.826823 86.585311)
		(width 0.15)
		(layer "F.Cu")
		(net 194)
	)
	(segment
		(start 111.614689 86.373176)
		(end 111.720755 86.479242)
		(width 0.15)
		(layer "F.Cu")
		(net 194)
	)
	(segment
		(start 114.902746 83.297251)
		(end 115.008814 83.40332)
		(width 0.15)
		(layer "F.Cu")
		(net 194)
	)
	(segment
		(start 115.43308 82.979055)
		(end 115.327014 82.872989)
		(width 0.15)
		(layer "F.Cu")
		(net 194)
	)
	(segment
		(start 111.826822 85.948912)
		(end 111.614689 86.161044)
		(width 0.15)
		(layer "F.Cu")
		(net 194)
	)
	(segment
		(start 119.251468 78.524266)
		(end 119.039335 78.736398)
		(width 0.15)
		(layer "F.Cu")
		(net 194)
	)
	(segment
		(start 128.8 78.025)
		(end 129.175 78.4)
		(width 0.09)
		(layer "F.Cu")
		(net 194)
	)
	(segment
		(start 115.008813 82.766921)
		(end 114.79668 82.979053)
		(width 0.15)
		(layer "F.Cu")
		(net 194)
	)
	(segment
		(start 114.160283 84.463983)
		(end 113.94815 84.676117)
		(width 0.15)
		(layer "F.Cu")
		(net 194)
	)
	(segment
		(start 117.024076 81.175927)
		(end 116.918007 81.069859)
		(width 0.15)
		(layer "F.Cu")
		(net 194)
	)
	(segment
		(start 110.978292 87.645974)
		(end 110.766159 87.858108)
		(width 0.15)
		(layer "F.Cu")
		(net 194)
	)
	(segment
		(start 111.826822 86.797444)
		(end 111.826823 86.797443)
		(width 0.15)
		(layer "F.Cu")
		(net 194)
	)
	(segment
		(start 113.205684 84.994313)
		(end 113.311752 85.100382)
		(width 0.15)
		(layer "F.Cu")
		(net 194)
	)
	(segment
		(start 112.46322 85.312514)
		(end 112.251087 85.524646)
		(width 0.15)
		(layer "F.Cu")
		(net 194)
	)
	(segment
		(start 115.857343 81.918391)
		(end 115.857344 81.91839)
		(width 0.15)
		(layer "F.Cu")
		(net 194)
	)
	(segment
		(start 109.675 92.7)
		(end 109.75 92.775)
		(width 0.15)
		(layer "F.Cu")
		(net 194)
	)
	(segment
		(start 115.857344 82.766922)
		(end 115.857345 82.766921)
		(width 0.15)
		(layer "F.Cu")
		(net 194)
	)
	(via
		(at 109.675 92.7)
		(size 0.4)
		(drill 0.2)
		(layers "F.Cu" "B.Cu")
		(net 194)
	)
	(via
		(at 113.773509 96.45)
		(size 0.4)
		(drill 0.2)
		(layers "F.Cu" "B.Cu")
		(net 194)
	)
	(arc
		(start 114.79668 82.979053)
		(mid 114.752746 83.085119)
		(end 114.79668 83.191185)
		(width 0.15)
		(layer "F.Cu")
		(net 194)
	)
	(arc
		(start 116.705876 81.706258)
		(mid 116.749809 81.812326)
		(end 116.705875 81.918391)
		(width 0.15)
		(layer "F.Cu")
		(net 194)
	)
	(arc
		(start 111.190423 86.797443)
		(mid 111.084356 86.753509)
		(end 110.97829 86.797444)
		(width 0.15)
		(layer "F.Cu")
		(net 194)
	)
	(arc
		(start 112.251087 85.736778)
		(mid 112.295021 85.842845)
		(end 112.251086 85.948911)
		(width 0.15)
		(layer "F.Cu")
		(net 194)
	)
	(arc
		(start 118.190804 79.584929)
		(mid 118.14687 79.690995)
		(end 118.190804 79.797061)
		(width 0.15)
		(layer "F.Cu")
		(net 194)
	)
	(arc
		(start 113.099619 85.524648)
		(mid 112.993553 85.568582)
		(end 112.887487 85.524648)
		(width 0.15)
		(layer "F.Cu")
		(net 194)
	)
	(arc
		(start 113.523883 84.463983)
		(mid 113.417816 84.420049)
		(end 113.31175 84.463984)
		(width 0.15)
		(layer "F.Cu")
		(net 194)
	)
	(arc
		(start 119.4636 78.524266)
		(mid 119.357533 78.480332)
		(end 119.251467 78.524267)
		(width 0.15)
		(layer "F.Cu")
		(net 194)
	)
	(arc
		(start 120.099999 78.312134)
		(mid 120.143935 78.418199)
		(end 120.1 78.524267)
		(width 0.15)
		(layer "F.Cu")
		(net 194)
	)
	(arc
		(start 111.61469 87.009577)
		(mid 111.508624 87.053511)
		(end 111.402558 87.009577)
		(width 0.15)
		(layer "F.Cu")
		(net 194)
	)
	(arc
		(start 118.190805 80.433462)
		(mid 118.084739 80.477396)
		(end 117.978673 80.433462)
		(width 0.15)
		(layer "F.Cu")
		(net 194)
	)
	(arc
		(start 116.069476 81.91839)
		(mid 115.963409 81.874456)
		(end 115.857343 81.918391)
		(width 0.15)
		(layer "F.Cu")
		(net 194)
	)
	(arc
		(start 115.645212 82.979055)
		(mid 115.539146 83.022989)
		(end 115.43308 82.979055)
		(width 0.15)
		(layer "F.Cu")
		(net 194)
	)
	(arc
		(start 113.099618 84.676115)
		(mid 113.055684 84.782181)
		(end 113.099618 84.888247)
		(width 0.15)
		(layer "F.Cu")
		(net 194)
	)
	(arc
		(start 112.251087 85.524646)
		(mid 112.207153 85.630712)
		(end 112.251087 85.736778)
		(width 0.15)
		(layer "F.Cu")
		(net 194)
	)
	(arc
		(start 114.372414 83.615452)
		(mid 114.266347 83.571518)
		(end 114.160281 83.615453)
		(width 0.15)
		(layer "F.Cu")
		(net 194)
	)
	(arc
		(start 115.645211 82.130522)
		(mid 115.601277 82.236588)
		(end 115.645211 82.342654)
		(width 0.15)
		(layer "F.Cu")
		(net 194)
	)
	(arc
		(start 117.342273 80.43346)
		(mid 117.298339 80.539526)
		(end 117.342273 80.645592)
		(width 0.15)
		(layer "F.Cu")
		(net 194)
	)
	(arc
		(start 117.342274 81.281993)
		(mid 117.236208 81.325927)
		(end 117.130142 81.281993)
		(width 0.15)
		(layer "F.Cu")
		(net 194)
	)
	(arc
		(start 111.614689 86.161044)
		(mid 111.570755 86.26711)
		(end 111.614689 86.373176)
		(width 0.15)
		(layer "F.Cu")
		(net 194)
	)
	(arc
		(start 110.766158 87.009575)
		(mid 110.722224 87.115641)
		(end 110.766158 87.221707)
		(width 0.15)
		(layer "F.Cu")
		(net 194)
	)
	(arc
		(start 119.039335 78.736398)
		(mid 118.995401 78.842464)
		(end 119.039335 78.94853)
		(width 0.15)
		(layer "F.Cu")
		(net 194)
	)
	(arc
		(start 118.402938 80.009196)
		(mid 118.446871 80.115264)
		(end 118.402937 80.221329)
		(width 0.15)
		(layer "F.Cu")
		(net 194)
	)
	(arc
		(start 110.978292 87.433842)
		(mid 111.022225 87.53991)
		(end 110.978291 87.645975)
		(width 0.15)
		(layer "F.Cu")
		(net 194)
	)
	(arc
		(start 120.1 78.1)
		(mid 120.056065 78.206068)
		(end 120.1 78.312134)
		(width 0.15)
		(layer "F.Cu")
		(net 194)
	)
	(arc
		(start 110.766159 87.858108)
		(mid 110.660093 87.902042)
		(end 110.554027 87.858108)
		(width 0.15)
		(layer "F.Cu")
		(net 194)
	)
	(arc
		(start 112.038955 85.948912)
		(mid 111.932889 85.904977)
		(end 111.826822 85.948911)
		(width 0.15)
		(layer "F.Cu")
		(net 194)
	)
	(arc
		(start 111.826823 86.585311)
		(mid 111.870756 86.691379)
		(end 111.826822 86.797444)
		(width 0.15)
		(layer "F.Cu")
		(net 194)
	)
	(arc
		(start 119.251469 79.160665)
		(mid 119.295402 79.266733)
		(end 119.251468 79.372798)
		(width 0.15)
		(layer "F.Cu")
		(net 194)
	)
	(arc
		(start 115.008814 83.40332)
		(mid 115.052747 83.509388)
		(end 115.008813 83.615453)
		(width 0.15)
		(layer "F.Cu")
		(net 194)
	)
	(arc
		(start 116.493743 82.130524)
		(mid 116.387677 82.174458)
		(end 116.281611 82.130524)
		(width 0.15)
		(layer "F.Cu")
		(net 194)
	)
	(arc
		(start 110.554027 87.858108)
		(mid 110.447961 87.814173)
		(end 110.341894 87.858109)
		(width 0.15)
		(layer "F.Cu")
		(net 194)
	)
	(arc
		(start 119.887867 78.7364)
		(mid 119.781801 78.780334)
		(end 119.675735 78.7364)
		(width 0.15)
		(layer "F.Cu")
		(net 194)
	)
	(arc
		(start 116.918007 81.069859)
		(mid 116.81194 81.025925)
		(end 116.705874 81.06986)
		(width 0.15)
		(layer "F.Cu")
		(net 194)
	)
	(arc
		(start 115.857345 82.554789)
		(mid 115.901278 82.660857)
		(end 115.857344 82.766922)
		(width 0.15)
		(layer "F.Cu")
		(net 194)
	)
	(arc
		(start 112.251088 85.948912)
		(mid 112.145021 85.992846)
		(end 112.038954 85.948912)
		(width 0.15)
		(layer "F.Cu")
		(net 194)
	)
	(arc
		(start 114.160283 84.251851)
		(mid 114.204216 84.357919)
		(end 114.160282 84.463984)
		(width 0.15)
		(layer "F.Cu")
		(net 194)
	)
	(arc
		(start 114.796681 83.827586)
		(mid 114.690615 83.87152)
		(end 114.584549 83.827586)
		(width 0.15)
		(layer "F.Cu")
		(net 194)
	)
	(arc
		(start 117.766538 80.221328)
		(mid 117.660471 80.177394)
		(end 117.554405 80.221329)
		(width 0.15)
		(layer "F.Cu")
		(net 194)
	)
	(arc
		(start 117.554407 80.857727)
		(mid 117.59834 80.963795)
		(end 117.554406 81.06986)
		(width 0.15)
		(layer "F.Cu")
		(net 194)
	)
	(arc
		(start 113.94815 84.676117)
		(mid 113.842084 84.720051)
		(end 113.736018 84.676117)
		(width 0.15)
		(layer "F.Cu")
		(net 194)
	)
	(arc
		(start 119.039336 79.584931)
		(mid 118.93327 79.628865)
		(end 118.827204 79.584931)
		(width 0.15)
		(layer "F.Cu")
		(net 194)
	)
	(arc
		(start 112.675352 85.312514)
		(mid 112.569285 85.26858)
		(end 112.463219 85.312515)
		(width 0.15)
		(layer "F.Cu")
		(net 194)
	)
	(arc
		(start 116.493742 81.281991)
		(mid 116.449808 81.388057)
		(end 116.493742 81.494123)
		(width 0.15)
		(layer "F.Cu")
		(net 194)
	)
	(arc
		(start 113.948149 83.827584)
		(mid 113.904215 83.93365)
		(end 113.948149 84.039716)
		(width 0.15)
		(layer "F.Cu")
		(net 194)
	)
	(arc
		(start 113.311752 85.100382)
		(mid 113.355685 85.20645)
		(end 113.311751 85.312515)
		(width 0.15)
		(layer "F.Cu")
		(net 194)
	)
	(arc
		(start 118.615069 79.372797)
		(mid 118.509002 79.328863)
		(end 118.402936 79.372798)
		(width 0.15)
		(layer "F.Cu")
		(net 194)
	)
	(arc
		(start 115.220945 82.766921)
		(mid 115.114878 82.722987)
		(end 115.008812 82.766922)
		(width 0.15)
		(layer "F.Cu")
		(net 194)
	)
	(segment
		(start 109.75 93.35)
		(end 109.75 92.775)
		(width 0.15)
		(layer "B.Cu")
		(net 194)
	)
	(segment
		(start 109.75 92.775)
		(end 109.675 92.7)
		(width 0.15)
		(layer "B.Cu")
		(net 194)
	)
	(segment
		(start 113.773509 96.45)
		(end 113.675 96.548509)
		(width 0.15)
		(layer "B.Cu")
		(net 194)
	)
	(segment
		(start 113.675 96.548509)
		(end 113.675 98.625)
		(width 0.15)
		(layer "B.Cu")
		(net 194)
	)
	(segment
		(start 111.325 93.7)
		(end 113.773509 96.148509)
		(width 0.15)
		(layer "In3.Cu")
		(net 194)
	)
	(segment
		(start 109.675 93)
		(end 110.375 93.7)
		(width 0.15)
		(layer "In3.Cu")
		(net 194)
	)
	(segment
		(start 109.675 92.7)
		(end 109.675 93)
		(width 0.15)
		(layer "In3.Cu")
		(net 194)
	)
	(segment
		(start 110.375 93.7)
		(end 111.325 93.7)
		(width 0.15)
		(layer "In3.Cu")
		(net 194)
	)
	(segment
		(start 113.773509 96.148509)
		(end 113.773509 96.45)
		(width 0.15)
		(layer "In3.Cu")
		(net 194)
	)
	(segment
		(start 119 84)
		(end 116.725 86.275)
		(width 0.15)
		(layer "F.Cu")
		(net 195)
	)
	(segment
		(start 127.975 84.4)
		(end 128.125 84.25)
		(width 0.09)
		(layer "F.Cu")
		(net 195)
	)
	(segment
		(start 116.725 92.7)
		(end 116.7625 92.7375)
		(width 0.15)
		(layer "F.Cu")
		(net 195)
	)
	(segment
		(start 130.225 82.2187)
		(end 130.42185 82.02185)
		(width 0.09)
		(layer "F.Cu")
		(net 195)
	)
	(segment
		(start 116.725 86.275)
		(end 116.725 92.7)
		(width 0.15)
		(layer "F.Cu")
		(net 195)
	)
	(segment
		(start 128.125 83.855025)
		(end 128.380025 83.6)
		(width 0.09)
		(layer "F.Cu")
		(net 195)
	)
	(segment
		(start 127.7 84.4)
		(end 127.975 84.4)
		(width 0.09)
		(layer "F.Cu")
		(net 195)
	)
	(segment
		(start 116.7625 92.7375)
		(end 116.7625 93.35)
		(width 0.15)
		(layer "F.Cu")
		(net 195)
	)
	(segment
		(start 130.42185 82.02185)
		(end 130.89685 82.02185)
		(width 0.09)
		(layer "F.Cu")
		(net 195)
	)
	(segment
		(start 130 83.6)
		(end 130.225 83.375)
		(width 0.09)
		(layer "F.Cu")
		(net 195)
	)
	(segment
		(start 128.125 84.25)
		(end 128.125 83.855025)
		(width 0.09)
		(layer "F.Cu")
		(net 195)
	)
	(segment
		(start 119 84)
		(end 127.237598 84)
		(width 0.15)
		(layer "F.Cu")
		(net 195)
	)
	(segment
		(start 130.225 83.375)
		(end 130.225 82.2187)
		(width 0.09)
		(layer "F.Cu")
		(net 195)
	)
	(segment
		(start 128.380025 83.6)
		(end 130 83.6)
		(width 0.09)
		(layer "F.Cu")
		(net 195)
	)
	(segment
		(start 130.89685 82.02185)
		(end 131.275 82.4)
		(width 0.09)
		(layer "F.Cu")
		(net 195)
	)
	(segment
		(start 127.637598 84.4)
		(end 127.7 84.4)
		(width 0.15)
		(layer "F.Cu")
		(net 195)
	)
	(segment
		(start 127.237598 84)
		(end 127.637598 84.4)
		(width 0.15)
		(layer "F.Cu")
		(net 195)
	)
	(via
		(at 116.725 92.7)
		(size 0.4)
		(drill 0.2)
		(layers "F.Cu" "B.Cu")
		(net 195)
	)
	(via
		(at 121.039499 96.536659)
		(size 0.4)
		(drill 0.2)
		(layers "F.Cu" "B.Cu")
		(net 195)
	)
	(segment
		(start 116.7625 93.35)
		(end 116.7625 92.7375)
		(width 0.15)
		(layer "B.Cu")
		(net 195)
	)
	(segment
		(start 121.175 98.625)
		(end 121.175 96.67216)
		(width 0.15)
		(layer "B.Cu")
		(net 195)
	)
	(segment
		(start 121.175 96.67216)
		(end 121.039499 96.536659)
		(width 0.15)
		(layer "B.Cu")
		(net 195)
	)
	(segment
		(start 116.7625 92.7375)
		(end 116.725 92.7)
		(width 0.15)
		(layer "B.Cu")
		(net 195)
	)
	(segment
		(start 121.039499 96.536659)
		(end 121.039499 96.483979)
		(width 0.15)
		(layer "In3.Cu")
		(net 195)
	)
	(segment
		(start 119.45552 94.9)
		(end 118.475 94.9)
		(width 0.15)
		(layer "In3.Cu")
		(net 195)
	)
	(segment
		(start 121.039499 96.483979)
		(end 119.45552 94.9)
		(width 0.15)
		(layer "In3.Cu")
		(net 195)
	)
	(segment
		(start 118.475 94.9)
		(end 116.725 93.15)
		(width 0.15)
		(layer "In3.Cu")
		(net 195)
	)
	(segment
		(start 116.725 93.15)
		(end 116.725 92.7)
		(width 0.15)
		(layer "In3.Cu")
		(net 195)
	)
	(segment
		(start 127.4 83.4)
		(end 121.6 83.4)
		(width 0.15)
		(layer "F.Cu")
		(net 196)
	)
	(segment
		(start 116.175 86.025)
		(end 116.175 92.7)
		(width 0.15)
		(layer "F.Cu")
		(net 196)
	)
	(segment
		(start 127.6 83.6)
		(end 127.4 83.4)
		(width 0.15)
		(layer "F.Cu")
		(net 196)
	)
	(segment
		(start 120.425 96.660025)
		(end 120.532867 96.552158)
		(width 0.15)
		(layer "F.Cu")
		(net 196)
	)
	(segment
		(start 129.75 81.95)
		(end 130.225 81.95)
		(width 0.09)
		(layer "F.Cu")
		(net 196)
	)
	(segment
		(start 121.4 83.2)
		(end 121.3 83.2)
		(width 0.15)
		(layer "F.Cu")
		(net 196)
	)
	(segment
		(start 129.525 82.175)
		(end 129.75 81.95)
		(width 0.09)
		(layer "F.Cu")
		(net 196)
	)
	(segment
		(start 120.425 98.625)
		(end 120.425 96.660025)
		(width 0.15)
		(layer "F.Cu")
		(net 196)
	)
	(segment
		(start 127.7 83.6)
		(end 127.975 83.6)
		(width 0.09)
		(layer "F.Cu")
		(net 196)
	)
	(segment
		(start 129.525 82.575)
		(end 129.525 82.175)
		(width 0.09)
		(layer "F.Cu")
		(net 196)
	)
	(segment
		(start 129.3 82.8)
		(end 129.525 82.575)
		(width 0.09)
		(layer "F.Cu")
		(net 196)
	)
	(segment
		(start 121.1 83.4)
		(end 121 83.4)
		(width 0.15)
		(layer "F.Cu")
		(net 196)
	)
	(segment
		(start 128.125 83.45)
		(end 128.125 82.95)
		(width 0.09)
		(layer "F.Cu")
		(net 196)
	)
	(segment
		(start 127.7 83.6)
		(end 127.6 83.6)
		(width 0.15)
		(layer "F.Cu")
		(net 196)
	)
	(segment
		(start 127.975 83.6)
		(end 128.125 83.45)
		(width 0.09)
		(layer "F.Cu")
		(net 196)
	)
	(segment
		(start 130.225 81.95)
		(end 130.575 81.6)
		(width 0.09)
		(layer "F.Cu")
		(net 196)
	)
	(segment
		(start 128.125 82.95)
		(end 128.275 82.8)
		(width 0.09)
		(layer "F.Cu")
		(net 196)
	)
	(segment
		(start 116.125 92.75)
		(end 116.125 93.35)
		(width 0.15)
		(layer "F.Cu")
		(net 196)
	)
	(segment
		(start 116.175 92.7)
		(end 116.125 92.75)
		(width 0.15)
		(layer "F.Cu")
		(net 196)
	)
	(segment
		(start 128.275 82.8)
		(end 129.3 82.8)
		(width 0.09)
		(layer "F.Cu")
		(net 196)
	)
	(segment
		(start 118.8 83.4)
		(end 116.175 86.025)
		(width 0.15)
		(layer "F.Cu")
		(net 196)
	)
	(segment
		(start 121 83.4)
		(end 118.8 83.4)
		(width 0.15)
		(layer "F.Cu")
		(net 196)
	)
	(via
		(at 116.175 92.7)
		(size 0.4)
		(drill 0.2)
		(layers "F.Cu" "B.Cu")
		(net 196)
	)
	(via
		(at 120.532867 96.552158)
		(size 0.4)
		(drill 0.2)
		(layers "F.Cu" "B.Cu")
		(net 196)
	)
	(arc
		(start 121.2 83.3)
		(mid 121.170711 83.370711)
		(end 121.1 83.4)
		(width 0.15)
		(layer "F.Cu")
		(net 196)
	)
	(arc
		(start 121.3 83.2)
		(mid 121.229289 83.229289)
		(end 121.2 83.3)
		(width 0.15)
		(layer "F.Cu")
		(net 196)
	)
	(arc
		(start 121.6 83.4)
		(mid 121.529289 83.370711)
		(end 121.5 83.3)
		(width 0.15)
		(layer "F.Cu")
		(net 196)
	)
	(arc
		(start 121.5 83.3)
		(mid 121.470711 83.229289)
		(end 121.4 83.2)
		(width 0.15)
		(layer "F.Cu")
		(net 196)
	)
	(segment
		(start 116.175 92.7)
		(end 116.125 92.75)
		(width 0.15)
		(layer "B.Cu")
		(net 196)
	)
	(segment
		(start 116.125 92.75)
		(end 116.125 93.35)
		(width 0.15)
		(layer "B.Cu")
		(net 196)
	)
	(segment
		(start 120.532867 96.457867)
		(end 120.532867 96.552158)
		(width 0.15)
		(layer "In3.Cu")
		(net 196)
	)
	(segment
		(start 118.175 95.2)
		(end 119.275 95.2)
		(width 0.15)
		(layer "In3.Cu")
		(net 196)
	)
	(segment
		(start 116.175 93.2)
		(end 118.175 95.2)
		(width 0.15)
		(layer "In3.Cu")
		(net 196)
	)
	(segment
		(start 119.275 95.2)
		(end 120.532867 96.457867)
		(width 0.15)
		(layer "In3.Cu")
		(net 196)
	)
	(segment
		(start 116.175 92.7)
		(end 116.175 93.2)
		(width 0.15)
		(layer "In3.Cu")
		(net 196)
	)
	(segment
		(start 119.425 96.645023)
		(end 119.425 98.625)
		(width 0.15)
		(layer "F.Cu")
		(net 197)
	)
	(segment
		(start 127.55 81.975)
		(end 128.8 81.975)
		(width 0.09)
		(layer "F.Cu")
		(net 197)
	)
	(segment
		(start 118.4 82.2)
		(end 120.5 82.2)
		(width 0.15)
		(layer "F.Cu")
		(net 197)
	)
	(segment
		(start 127.55 81.975)
		(end 127.325 82.2)
		(width 0.15)
		(layer "F.Cu")
		(net 197)
	)
	(segment
		(start 121.25 82.2)
		(end 121.25 82.35)
		(width 0.15)
		(layer "F.Cu")
		(net 197)
	)
	(segment
		(start 121.7 81.9)
		(end 121.4 81.9)
		(width 0.15)
		(layer "F.Cu")
		(net 197)
	)
	(segment
		(start 128.8 81.975)
		(end 129.175 81.6)
		(width 0.09)
		(layer "F.Cu")
		(net 197)
	)
	(segment
		(start 121.25 82.05)
		(end 121.25 82.2)
		(width 0.15)
		(layer "F.Cu")
		(net 197)
	)
	(segment
		(start 114.9875 92.7875)
		(end 114.9875 93.35)
		(width 0.15)
		(layer "F.Cu")
		(net 197)
	)
	(segment
		(start 115.075 85.525)
		(end 115.075 92.7)
		(width 0.15)
		(layer "F.Cu")
		(net 197)
	)
	(segment
		(start 115.075 92.7)
		(end 114.9875 92.7875)
		(width 0.15)
		(layer "F.Cu")
		(net 197)
	)
	(segment
		(start 118.4 82.2)
		(end 115.075 85.525)
		(width 0.15)
		(layer "F.Cu")
		(net 197)
	)
	(segment
		(start 127.325 82.2)
		(end 122 82.2)
		(width 0.15)
		(layer "F.Cu")
		(net 197)
	)
	(segment
		(start 121.1 82.5)
		(end 120.8 82.5)
		(width 0.15)
		(layer "F.Cu")
		(net 197)
	)
	(segment
		(start 119.525 96.545023)
		(end 119.425 96.645023)
		(width 0.15)
		(layer "F.Cu")
		(net 197)
	)
	(via
		(at 119.525 96.545023)
		(size 0.4)
		(drill 0.2)
		(layers "F.Cu" "B.Cu")
		(net 197)
	)
	(via
		(at 115.075 92.7)
		(size 0.4)
		(drill 0.2)
		(layers "F.Cu" "B.Cu")
		(net 197)
	)
	(arc
		(start 121.4 81.9)
		(mid 121.293934 81.943934)
		(end 121.25 82.05)
		(width 0.15)
		(layer "F.Cu")
		(net 197)
	)
	(arc
		(start 120.65 82.35)
		(mid 120.606066 82.243934)
		(end 120.5 82.2)
		(width 0.15)
		(layer "F.Cu")
		(net 197)
	)
	(arc
		(start 121.85 82.05)
		(mid 121.806066 81.943934)
		(end 121.7 81.9)
		(width 0.15)
		(layer "F.Cu")
		(net 197)
	)
	(arc
		(start 121.25 82.35)
		(mid 121.206066 82.456066)
		(end 121.1 82.5)
		(width 0.15)
		(layer "F.Cu")
		(net 197)
	)
	(arc
		(start 122 82.2)
		(mid 121.893934 82.156066)
		(end 121.85 82.05)
		(width 0.15)
		(layer "F.Cu")
		(net 197)
	)
	(arc
		(start 120.8 82.5)
		(mid 120.693934 82.456066)
		(end 120.65 82.35)
		(width 0.15)
		(layer "F.Cu")
		(net 197)
	)
	(segment
		(start 114.9875 92.7875)
		(end 115.075 92.7)
		(width 0.15)
		(layer "B.Cu")
		(net 197)
	)
	(segment
		(start 114.9875 93.35)
		(end 114.9875 92.7875)
		(width 0.15)
		(layer "B.Cu")
		(net 197)
	)
	(segment
		(start 115.075 93.3)
		(end 115.075 92.7)
		(width 0.15)
		(layer "In3.Cu")
		(net 197)
	)
	(segment
		(start 119.525 96.545023)
		(end 118.779977 95.8)
		(width 0.15)
		(layer "In3.Cu")
		(net 197)
	)
	(segment
		(start 117.575 95.8)
		(end 115.075 93.3)
		(width 0.15)
		(layer "In3.Cu")
		(net 197)
	)
	(segment
		(start 118.779977 95.8)
		(end 117.575 95.8)
		(width 0.15)
		(layer "In3.Cu")
		(net 197)
	)
	(segment
		(start 123.6 83)
		(end 123.2 83)
		(width 0.15)
		(layer "F.Cu")
		(net 198)
	)
	(segment
		(start 126.1 82.7)
		(end 126.1 82.8)
		(width 0.15)
		(layer "F.Cu")
		(net 198)
	)
	(segment
		(start 127.95 82.8)
		(end 128.35 82.4)
		(width 0.09)
		(layer "F.Cu")
		(net 198)
	)
	(segment
		(start 123 82.6)
		(end 122.6 82.6)
		(width 0.15)
		(layer "F.Cu")
		(net 198)
	)
	(segment
		(start 123.1 82.8)
		(end 123.1 82.7)
		(width 0.15)
		(layer "F.Cu")
		(net 198)
	)
	(segment
		(start 127.7 82.8)
		(end 127.4 82.8)
		(width 0.15)
		(layer "F.Cu")
		(net 198)
	)
	(segment
		(start 128.35 82.4)
		(end 128.475 82.4)
		(width 0.09)
		(layer "F.Cu")
		(net 198)
	)
	(segment
		(start 125.4 82.6)
		(end 125 82.6)
		(width 0.15)
		(layer "F.Cu")
		(net 198)
	)
	(segment
		(start 118.6 82.8)
		(end 121.8 82.8)
		(width 0.15)
		(layer "F.Cu")
		(net 198)
	)
	(segment
		(start 115.625 85.775)
		(end 115.625 92.7)
		(width 0.15)
		(layer "F.Cu")
		(net 198)
	)
	(segment
		(start 127.2 83)
		(end 126.8 83)
		(width 0.15)
		(layer "F.Cu")
		(net 198)
	)
	(segment
		(start 126 83)
		(end 125.6 83)
		(width 0.15)
		(layer "F.Cu")
		(net 198)
	)
	(segment
		(start 124.9 82.7)
		(end 124.9 82.8)
		(width 0.15)
		(layer "F.Cu")
		(net 198)
	)
	(segment
		(start 123.7 82.7)
		(end 123.7 82.8)
		(width 0.15)
		(layer "F.Cu")
		(net 198)
	)
	(segment
		(start 127.7 82.8)
		(end 127.95 82.8)
		(width 0.09)
		(layer "F.Cu")
		(net 198)
	)
	(segment
		(start 124.3 82.9)
		(end 124.3 82.8)
		(width 0.15)
		(layer "F.Cu")
		(net 198)
	)
	(segment
		(start 126.1 82.8)
		(end 126.1 82.9)
		(width 0.15)
		(layer "F.Cu")
		(net 198)
	)
	(segment
		(start 123.7 82.8)
		(end 123.7 82.9)
		(width 0.15)
		(layer "F.Cu")
		(net 198)
	)
	(segment
		(start 126.6 82.6)
		(end 126.2 82.6)
		(width 0.15)
		(layer "F.Cu")
		(net 198)
	)
	(segment
		(start 125.5 82.8)
		(end 125.5 82.7)
		(width 0.15)
		(layer "F.Cu")
		(net 198)
	)
	(segment
		(start 122.5 82.7)
		(end 122.5 82.8)
		(width 0.15)
		(layer "F.Cu")
		(net 198)
	)
	(segment
		(start 118.6 82.8)
		(end 115.625 85.775)
		(width 0.15)
		(layer "F.Cu")
		(net 198)
	)
	(segment
		(start 122.5 82.8)
		(end 122.5 82.9)
		(width 0.15)
		(layer "F.Cu")
		(net 198)
	)
	(segment
		(start 123.1 82.9)
		(end 123.1 82.8)
		(width 0.15)
		(layer "F.Cu")
		(net 198)
	)
	(segment
		(start 126.7 82.9)
		(end 126.7 82.8)
		(width 0.15)
		(layer "F.Cu")
		(net 198)
	)
	(segment
		(start 124.9 82.8)
		(end 124.9 82.9)
		(width 0.15)
		(layer "F.Cu")
		(net 198)
	)
	(segment
		(start 124.8 83)
		(end 124.4 83)
		(width 0.15)
		(layer "F.Cu")
		(net 198)
	)
	(segment
		(start 124.2 82.6)
		(end 123.8 82.6)
		(width 0.15)
		(layer "F.Cu")
		(net 198)
	)
	(segment
		(start 126.7 82.8)
		(end 126.7 82.7)
		(width 0.15)
		(layer "F.Cu")
		(net 198)
	)
	(segment
		(start 122.4 83)
		(end 122 83)
		(width 0.15)
		(layer "F.Cu")
		(net 198)
	)
	(segment
		(start 125.5 82.9)
		(end 125.5 82.8)
		(width 0.15)
		(layer "F.Cu")
		(net 198)
	)
	(segment
		(start 115.625 93.35)
		(end 115.625 92.7)
		(width 0.15)
		(layer "F.Cu")
		(net 198)
	)
	(segment
		(start 124.3 82.8)
		(end 124.3 82.7)
		(width 0.15)
		(layer "F.Cu")
		(net 198)
	)
	(via
		(at 120.033711 96.533546)
		(size 0.4)
		(drill 0.2)
		(layers "F.Cu" "B.Cu")
		(net 198)
	)
	(via
		(at 115.625 92.7)
		(size 0.4)
		(drill 0.2)
		(layers "F.Cu" "B.Cu")
		(net 198)
	)
	(arc
		(start 126.7 82.7)
		(mid 126.670711 82.629289)
		(end 126.6 82.6)
		(width 0.15)
		(layer "F.Cu")
		(net 198)
	)
	(arc
		(start 121.9 82.9)
		(mid 121.870711 82.829289)
		(end 121.8 82.8)
		(width 0.15)
		(layer "F.Cu")
		(net 198)
	)
	(arc
		(start 125 82.6)
		(mid 124.929289 82.629289)
		(end 124.9 82.7)
		(width 0.15)
		(layer "F.Cu")
		(net 198)
	)
	(arc
		(start 124.3 82.7)
		(mid 124.270711 82.629289)
		(end 124.2 82.6)
		(width 0.15)
		(layer "F.Cu")
		(net 198)
	)
	(arc
		(start 126.8 83)
		(mid 126.729289 82.970711)
		(end 126.7 82.9)
		(width 0.15)
		(layer "F.Cu")
		(net 198)
	)
	(arc
		(start 127.3 82.9)
		(mid 127.270711 82.970711)
		(end 127.2 83)
		(width 0.15)
		(layer "F.Cu")
		(net 198)
	)
	(arc
		(start 125.6 83)
		(mid 125.529289 82.970711)
		(end 125.5 82.9)
		(width 0.15)
		(layer "F.Cu")
		(net 198)
	)
	(arc
		(start 123.7 82.9)
		(mid 123.670711 82.970711)
		(end 123.6 83)
		(width 0.15)
		(layer "F.Cu")
		(net 198)
	)
	(arc
		(start 122 83)
		(mid 121.929289 82.970711)
		(end 121.9 82.9)
		(width 0.15)
		(layer "F.Cu")
		(net 198)
	)
	(arc
		(start 124.9 82.9)
		(mid 124.870711 82.970711)
		(end 124.8 83)
		(width 0.15)
		(layer "F.Cu")
		(net 198)
	)
	(arc
		(start 122.5 82.9)
		(mid 122.470711 82.970711)
		(end 122.4 83)
		(width 0.15)
		(layer "F.Cu")
		(net 198)
	)
	(arc
		(start 127.4 82.8)
		(mid 127.329289 82.829289)
		(end 127.3 82.9)
		(width 0.15)
		(layer "F.Cu")
		(net 198)
	)
	(arc
		(start 123.2 83)
		(mid 123.129289 82.970711)
		(end 123.1 82.9)
		(width 0.15)
		(layer "F.Cu")
		(net 198)
	)
	(arc
		(start 125.5 82.7)
		(mid 125.470711 82.629289)
		(end 125.4 82.6)
		(width 0.15)
		(layer "F.Cu")
		(net 198)
	)
	(arc
		(start 123.8 82.6)
		(mid 123.729289 82.629289)
		(end 123.7 82.7)
		(width 0.15)
		(layer "F.Cu")
		(net 198)
	)
	(arc
		(start 126.1 82.9)
		(mid 126.070711 82.970711)
		(end 126 83)
		(width 0.15)
		(layer "F.Cu")
		(net 198)
	)
	(arc
		(start 124.4 83)
		(mid 124.329289 82.970711)
		(end 124.3 82.9)
		(width 0.15)
		(layer "F.Cu")
		(net 198)
	)
	(arc
		(start 123.1 82.7)
		(mid 123.070711 82.629289)
		(end 123 82.6)
		(width 0.15)
		(layer "F.Cu")
		(net 198)
	)
	(arc
		(start 122.6 82.6)
		(mid 122.529289 82.629289)
		(end 122.5 82.7)
		(width 0.15)
		(layer "F.Cu")
		(net 198)
	)
	(arc
		(start 126.2 82.6)
		(mid 126.129289 82.629289)
		(end 126.1 82.7)
		(width 0.15)
		(layer "F.Cu")
		(net 198)
	)
	(segment
		(start 120.175 98.625)
		(end 120.175 96.674835)
		(width 0.15)
		(layer "B.Cu")
		(net 198)
	)
	(segment
		(start 115.625 93.35)
		(end 115.625 92.7)
		(width 0.15)
		(layer "B.Cu")
		(net 198)
	)
	(segment
		(start 120.175 96.674835)
		(end 120.033711 96.533546)
		(width 0.15)
		(layer "B.Cu")
		(net 198)
	)
	(segment
		(start 120.033711 96.523403)
		(end 119.010308 95.5)
		(width 0.15)
		(layer "In3.Cu")
		(net 198)
	)
	(segment
		(start 120.033711 96.533546)
		(end 120.033711 96.523403)
		(width 0.15)
		(layer "In3.Cu")
		(net 198)
	)
	(segment
		(start 117.875 95.5)
		(end 115.625 93.25)
		(width 0.15)
		(layer "In3.Cu")
		(net 198)
	)
	(segment
		(start 119.010308 95.5)
		(end 117.875 95.5)
		(width 0.15)
		(layer "In3.Cu")
		(net 198)
	)
	(segment
		(start 115.625 93.25)
		(end 115.625 92.7)
		(width 0.15)
		(layer "In3.Cu")
		(net 198)
	)
	(segment
		(start 121.5734 96.548153)
		(end 121.573399 93.323899)
		(width 0.1016)
		(layer "F.Cu")
		(net 199)
	)
	(segment
		(start 121.573399 93.323899)
		(end 121.4242 93.1747)
		(width 0.1016)
		(layer "F.Cu")
		(net 199)
	)
	(segment
		(start 121.325 97.144975)
		(end 121.325 96.798897)
		(width 0.1)
		(layer "F.Cu")
		(net 199)
	)
	(segment
		(start 121.325 96.798897)
		(end 121.325 96.796553)
		(width 0.1016)
		(layer "F.Cu")
		(net 199)
	)
	(segment
		(start 121.425 98.625)
		(end 121.425 97.244975)
		(width 0.1)
		(layer "F.Cu")
		(net 199)
	)
	(segment
		(start 121.325 96.796553)
		(end 121.5734 96.548153)
		(width 0.1016)
		(layer "F.Cu")
		(net 199)
	)
	(segment
		(start 121.425 97.244975)
		(end 121.325 97.144975)
		(width 0.1)
		(layer "F.Cu")
		(net 199)
	)
	(via
		(at 121.4242 93.1747)
		(size 0.4)
		(drill 0.2)
		(layers "F.Cu" "B.Cu")
		(net 199)
	)
	(via
		(at 129.175 83.2)
		(size 0.4)
		(drill 0.15)
		(layers "F.Cu" "B.Cu")
		(net 199)
	)
	(segment
		(start 126.781754 84.3592)
		(end 126.461754 84.0392)
		(width 0.1)
		(layer "B.Cu")
		(net 199)
	)
	(segment
		(start 129.175 83.2)
		(end 128.775 83.6)
		(width 0.1)
		(layer "B.Cu")
		(net 199)
	)
	(segment
		(start 121.575 85.113578)
		(end 121.575 85.425)
		(width 0.1)
		(layer "B.Cu")
		(net 199)
	)
	(segment
		(start 120.775 88.525)
		(end 120.775 88.625)
		(width 0.1)
		(layer "B.Cu")
		(net 199)
	)
	(segment
		(start 121.225 92.275)
		(end 121.325 92.275)
		(width 0.1)
		(layer "B.Cu")
		(net 199)
	)
	(segment
		(start 121.575 87.475)
		(end 122.125 87.475)
		(width 0.1)
		(layer "B.Cu")
		(net 199)
	)
	(segment
		(start 122.125 86.475)
		(end 122.025 86.475)
		(width 0.1)
		(layer "B.Cu")
		(net 199)
	)
	(segment
		(start 121.775 91.275)
		(end 121.225 91.275)
		(width 0.1)
		(layer "B.Cu")
		(net 199)
	)
	(segment
		(start 120.775 86.925)
		(end 120.775 87.025)
		(width 0.1)
		(layer "B.Cu")
		(net 199)
	)
	(segment
		(start 121.775 88.075)
		(end 121.225 88.075)
		(width 0.1)
		(layer "B.Cu")
		(net 199)
	)
	(segment
		(start 122.375 89.325)
		(end 122.375 89.425)
		(width 0.1)
		(layer "B.Cu")
		(net 199)
	)
	(segment
		(start 121.575 93.0239)
		(end 121.4242 93.1747)
		(width 0.1)
		(layer "B.Cu")
		(net 199)
	)
	(segment
		(start 122.649378 84.0392)
		(end 121.575 85.113578)
		(width 0.1)
		(layer "B.Cu")
		(net 199)
	)
	(segment
		(start 128.125 83.85)
		(end 128.125 84.163676)
		(width 0.1)
		(layer "B.Cu")
		(net 199)
	)
	(segment
		(start 126.461754 84.0392)
		(end 122.649378 84.0392)
		(width 0.1)
		(layer "B.Cu")
		(net 199)
	)
	(segment
		(start 120.775 91.725)
		(end 120.775 91.825)
		(width 0.1)
		(layer "B.Cu")
		(net 199)
	)
	(segment
		(start 122.025 85.875)
		(end 122.125 85.875)
		(width 0.1)
		(layer "B.Cu")
		(net 199)
	)
	(segment
		(start 121.775 89.675)
		(end 121.225 89.675)
		(width 0.1)
		(layer "B.Cu")
		(net 199)
	)
	(segment
		(start 122.125 88.075)
		(end 121.775 88.075)
		(width 0.1)
		(layer "B.Cu")
		(net 199)
	)
	(segment
		(start 121.225 90.675)
		(end 121.575 90.675)
		(width 0.1)
		(layer "B.Cu")
		(net 199)
	)
	(segment
		(start 120.775 90.125)
		(end 120.775 90.225)
		(width 0.1)
		(layer "B.Cu")
		(net 199)
	)
	(segment
		(start 121.4242 93.1747)
		(end 121.573399 93.025501)
		(width 0.1016)
		(layer "B.Cu")
		(net 199)
	)
	(segment
		(start 128.125 84.163676)
		(end 127.929476 84.3592)
		(width 0.1)
		(layer "B.Cu")
		(net 199)
	)
	(segment
		(start 121.575 92.525)
		(end 121.575 93.0239)
		(width 0.1)
		(layer "B.Cu")
		(net 199)
	)
	(segment
		(start 122.375 86.125)
		(end 122.375 86.225)
		(width 0.1)
		(layer "B.Cu")
		(net 199)
	)
	(segment
		(start 122.375 90.925)
		(end 122.375 91.025)
		(width 0.1)
		(layer "B.Cu")
		(net 199)
	)
	(segment
		(start 127.929476 84.3592)
		(end 126.781754 84.3592)
		(width 0.1)
		(layer "B.Cu")
		(net 199)
	)
	(segment
		(start 128.375 83.6)
		(end 128.125 83.85)
		(width 0.1)
		(layer "B.Cu")
		(net 199)
	)
	(segment
		(start 122.125 91.275)
		(end 121.775 91.275)
		(width 0.1)
		(layer "B.Cu")
		(net 199)
	)
	(segment
		(start 128.775 83.6)
		(end 128.375 83.6)
		(width 0.1)
		(layer "B.Cu")
		(net 199)
	)
	(segment
		(start 121.575 90.675)
		(end 122.125 90.675)
		(width 0.1)
		(layer "B.Cu")
		(net 199)
	)
	(segment
		(start 122.025 86.475)
		(end 121.225 86.475)
		(width 0.1)
		(layer "B.Cu")
		(net 199)
	)
	(segment
		(start 121.575 89.075)
		(end 122.125 89.075)
		(width 0.1)
		(layer "B.Cu")
		(net 199)
	)
	(segment
		(start 122.375 87.725)
		(end 122.375 87.825)
		(width 0.1)
		(layer "B.Cu")
		(net 199)
	)
	(segment
		(start 121.225 89.075)
		(end 121.575 89.075)
		(width 0.1)
		(layer "B.Cu")
		(net 199)
	)
	(segment
		(start 122.125 89.675)
		(end 121.775 89.675)
		(width 0.1)
		(layer "B.Cu")
		(net 199)
	)
	(segment
		(start 121.225 87.475)
		(end 121.575 87.475)
		(width 0.1)
		(layer "B.Cu")
		(net 199)
	)
	(arc
		(start 121.225 88.075)
		(mid 120.906802 88.206802)
		(end 120.775 88.525)
		(width 0.1)
		(layer "B.Cu")
		(net 199)
	)
	(arc
		(start 122.375 89.425)
		(mid 122.301777 89.601777)
		(end 122.125 89.675)
		(width 0.1)
		(layer "B.Cu")
		(net 199)
	)
	(arc
		(start 120.775 90.225)
		(mid 120.906802 90.543198)
		(end 121.225 90.675)
		(width 0.1)
		(layer "B.Cu")
		(net 199)
	)
	(arc
		(start 121.225 86.475)
		(mid 120.906802 86.606802)
		(end 120.775 86.925)
		(width 0.1)
		(layer "B.Cu")
		(net 199)
	)
	(arc
		(start 121.575 85.425)
		(mid 121.706802 85.743198)
		(end 122.025 85.875)
		(width 0.1)
		(layer "B.Cu")
		(net 199)
	)
	(arc
		(start 120.775 91.825)
		(mid 120.906802 92.143198)
		(end 121.225 92.275)
		(width 0.1)
		(layer "B.Cu")
		(net 199)
	)
	(arc
		(start 120.775 87.025)
		(mid 120.906802 87.343198)
		(end 121.225 87.475)
		(width 0.1)
		(layer "B.Cu")
		(net 199)
	)
	(arc
		(start 121.225 89.675)
		(mid 120.906802 89.806802)
		(end 120.775 90.125)
		(width 0.1)
		(layer "B.Cu")
		(net 199)
	)
	(arc
		(start 122.125 89.075)
		(mid 122.301777 89.148223)
		(end 122.375 89.325)
		(width 0.1)
		(layer "B.Cu")
		(net 199)
	)
	(arc
		(start 122.125 87.475)
		(mid 122.301777 87.548223)
		(end 122.375 87.725)
		(width 0.1)
		(layer "B.Cu")
		(net 199)
	)
	(arc
		(start 121.325 92.275)
		(mid 121.501777 92.348223)
		(end 121.575 92.525)
		(width 0.1)
		(layer "B.Cu")
		(net 199)
	)
	(arc
		(start 122.375 86.225)
		(mid 122.301777 86.401777)
		(end 122.125 86.475)
		(width 0.1)
		(layer "B.Cu")
		(net 199)
	)
	(arc
		(start 122.375 87.825)
		(mid 122.301777 88.001777)
		(end 122.125 88.075)
		(width 0.1)
		(layer "B.Cu")
		(net 199)
	)
	(arc
		(start 121.225 91.275)
		(mid 120.906802 91.406802)
		(end 120.775 91.725)
		(width 0.1)
		(layer "B.Cu")
		(net 199)
	)
	(arc
		(start 120.775 88.625)
		(mid 120.906802 88.943198)
		(end 121.225 89.075)
		(width 0.1)
		(layer "B.Cu")
		(net 199)
	)
	(arc
		(start 122.125 90.675)
		(mid 122.301777 90.748223)
		(end 122.375 90.925)
		(width 0.1)
		(layer "B.Cu")
		(net 199)
	)
	(arc
		(start 122.375 91.025)
		(mid 122.301777 91.201777)
		(end 122.125 91.275)
		(width 0.1)
		(layer "B.Cu")
		(net 199)
	)
	(arc
		(start 122.125 85.875)
		(mid 122.301777 85.948223)
		(end 122.375 86.125)
		(width 0.1)
		(layer "B.Cu")
		(net 199)
	)
	(segment
		(start 122.025 97.144975)
		(end 122.025 96.798897)
		(width 0.1)
		(layer "F.Cu")
		(net 200)
	)
	(segment
		(start 121.7766 96.548153)
		(end 121.776601 93.323899)
		(width 0.1016)
		(layer "F.Cu")
		(net 200)
	)
	(segment
		(start 121.776601 93.323899)
		(end 121.9258 93.1747)
		(width 0.1016)
		(layer "F.Cu")
		(net 200)
	)
	(segment
		(start 121.925 98.625)
		(end 121.925 97.244975)
		(width 0.1)
		(layer "F.Cu")
		(net 200)
	)
	(segment
		(start 121.925 97.244975)
		(end 122.025 97.144975)
		(width 0.1)
		(layer "F.Cu")
		(net 200)
	)
	(segment
		(start 122.025 96.798897)
		(end 122.025 96.796553)
		(width 0.1016)
		(layer "F.Cu")
		(net 200)
	)
	(segment
		(start 122.025 96.796553)
		(end 121.7766 96.548153)
		(width 0.1016)
		(layer "F.Cu")
		(net 200)
	)
	(via
		(at 121.9258 93.1747)
		(size 0.4)
		(drill 0.2)
		(layers "F.Cu" "B.Cu")
		(net 200)
	)
	(via
		(at 128.475 84)
		(size 0.4)
		(drill 0.15)
		(layers "F.Cu" "B.Cu")
		(net 200)
	)
	(segment
		(start 122.575 89.325)
		(end 122.575 89.425)
		(width 0.1)
		(layer "B.Cu")
		(net 200)
	)
	(segment
		(start 122.575 87.725)
		(end 122.575 87.825)
		(width 0.1)
		(layer "B.Cu")
		(net 200)
	)
	(segment
		(start 122.125 86.675)
		(end 122.025 86.675)
		(width 0.1)
		(layer "B.Cu")
		(net 200)
	)
	(segment
		(start 122.125 89.875)
		(end 121.775 89.875)
		(width 0.1)
		(layer "B.Cu")
		(net 200)
	)
	(segment
		(start 120.975 90.125)
		(end 120.975 90.225)
		(width 0.1)
		(layer "B.Cu")
		(net 200)
	)
	(segment
		(start 122.575 90.925)
		(end 122.575 91.025)
		(width 0.1)
		(layer "B.Cu")
		(net 200)
	)
	(segment
		(start 128.475 84)
		(end 128.475 84.077114)
		(width 0.1)
		(layer "B.Cu")
		(net 200)
	)
	(segment
		(start 126.812984 84.5608)
		(end 126.762984 84.5608)
		(width 0.1)
		(layer "B.Cu")
		(net 200)
	)
	(segment
		(start 121.9258 93.1747)
		(end 121.776601 93.025501)
		(width 0.1016)
		(layer "B.Cu")
		(net 200)
	)
	(segment
		(start 126.698246 84.5608)
		(end 126.378246 84.2408)
		(width 0.1)
		(layer "B.Cu")
		(net 200)
	)
	(segment
		(start 122.730622 84.2408)
		(end 121.775 85.196422)
		(width 0.1)
		(layer "B.Cu")
		(net 200)
	)
	(segment
		(start 121.225 87.275)
		(end 121.575 87.275)
		(width 0.1)
		(layer "B.Cu")
		(net 200)
	)
	(segment
		(start 122.125 91.475)
		(end 121.775 91.475)
		(width 0.1)
		(layer "B.Cu")
		(net 200)
	)
	(segment
		(start 121.775 91.475)
		(end 121.225 91.475)
		(width 0.1)
		(layer "B.Cu")
		(net 200)
	)
	(segment
		(start 121.775 89.875)
		(end 121.225 89.875)
		(width 0.1)
		(layer "B.Cu")
		(net 200)
	)
	(segment
		(start 121.575 90.475)
		(end 122.125 90.475)
		(width 0.1)
		(layer "B.Cu")
		(net 200)
	)
	(segment
		(start 122.575 86.125)
		(end 122.575 86.225)
		(width 0.1)
		(layer "B.Cu")
		(net 200)
	)
	(segment
		(start 128.475 84)
		(end 128.475 84.095)
		(width 0.1)
		(layer "B.Cu")
		(net 200)
	)
	(segment
		(start 126.762984 84.5608)
		(end 126.698246 84.5608)
		(width 0.1)
		(layer "B.Cu")
		(net 200)
	)
	(segment
		(start 121.225 90.475)
		(end 121.575 90.475)
		(width 0.1)
		(layer "B.Cu")
		(net 200)
	)
	(segment
		(start 128.475 84.095)
		(end 128.34 84.23)
		(width 0.1)
		(layer "B.Cu")
		(net 200)
	)
	(segment
		(start 120.975 86.925)
		(end 120.975 87.025)
		(width 0.1)
		(layer "B.Cu")
		(net 200)
	)
	(segment
		(start 121.775 85.196422)
		(end 121.775 85.425)
		(width 0.1)
		(layer "B.Cu")
		(net 200)
	)
	(segment
		(start 121.225 92.075)
		(end 121.325 92.075)
		(width 0.1)
		(layer "B.Cu")
		(net 200)
	)
	(segment
		(start 127.562984 84.8108)
		(end 127.562984 84.7108)
		(width 0.1)
		(layer "B.Cu")
		(net 200)
	)
	(segment
		(start 127.862984 84.7108)
		(end 127.862984 84.8108)
		(width 0.1)
		(layer "B.Cu")
		(net 200)
	)
	(segment
		(start 120.975 91.725)
		(end 120.975 91.825)
		(width 0.1)
		(layer "B.Cu")
		(net 200)
	)
	(segment
		(start 121.775 88.275)
		(end 121.225 88.275)
		(width 0.1)
		(layer "B.Cu")
		(net 200)
	)
	(segment
		(start 120.975 88.525)
		(end 120.975 88.625)
		(width 0.1)
		(layer "B.Cu")
		(net 200)
	)
	(segment
		(start 121.575 88.875)
		(end 122.125 88.875)
		(width 0.1)
		(layer "B.Cu")
		(net 200)
	)
	(segment
		(start 128.34 84.23)
		(end 128.34 84.233784)
		(width 0.1)
		(layer "B.Cu")
		(net 200)
	)
	(segment
		(start 122.125 88.275)
		(end 121.775 88.275)
		(width 0.1)
		(layer "B.Cu")
		(net 200)
	)
	(segment
		(start 121.225 88.875)
		(end 121.575 88.875)
		(width 0.1)
		(layer "B.Cu")
		(net 200)
	)
	(segment
		(start 128.34 84.233784)
		(end 128.012984 84.5608)
		(width 0.1)
		(layer "B.Cu")
		(net 200)
	)
	(segment
		(start 122.025 85.675)
		(end 122.125 85.675)
		(width 0.1)
		(layer "B.Cu")
		(net 200)
	)
	(segment
		(start 126.378246 84.2408)
		(end 122.730622 84.2408)
		(width 0.1)
		(layer "B.Cu")
		(net 200)
	)
	(segment
		(start 121.775 92.525)
		(end 121.775 93.0239)
		(width 0.1)
		(layer "B.Cu")
		(net 200)
	)
	(segment
		(start 122.025 86.675)
		(end 121.225 86.675)
		(width 0.1)
		(layer "B.Cu")
		(net 200)
	)
	(segment
		(start 121.775 93.0239)
		(end 121.9258 93.1747)
		(width 0.1)
		(layer "B.Cu")
		(net 200)
	)
	(segment
		(start 121.575 87.275)
		(end 122.125 87.275)
		(width 0.1)
		(layer "B.Cu")
		(net 200)
	)
	(segment
		(start 126.962984 84.8108)
		(end 126.962984 84.7108)
		(width 0.1)
		(layer "B.Cu")
		(net 200)
	)
	(segment
		(start 127.262984 84.7108)
		(end 127.262984 84.8108)
		(width 0.1)
		(layer "B.Cu")
		(net 200)
	)
	(arc
		(start 121.775 85.425)
		(mid 121.848223 85.601777)
		(end 122.025 85.675)
		(width 0.1)
		(layer "B.Cu")
		(net 200)
	)
	(arc
		(start 120.975 88.625)
		(mid 121.048223 88.801777)
		(end 121.225 88.875)
		(width 0.1)
		(layer "B.Cu")
		(net 200)
	)
	(arc
		(start 121.325 92.075)
		(mid 121.643198 92.206802)
		(end 121.775 92.525)
		(width 0.1)
		(layer "B.Cu")
		(net 200)
	)
	(arc
		(start 127.262984 84.8108)
		(mid 127.21905 84.916866)
		(end 127.112984 84.9608)
		(width 0.1)
		(layer "B.Cu")
		(net 200)
	)
	(arc
		(start 121.225 88.275)
		(mid 121.048223 88.348223)
		(end 120.975 88.525)
		(width 0.1)
		(layer "B.Cu")
		(net 200)
	)
	(arc
		(start 121.225 91.475)
		(mid 121.048223 91.548223)
		(end 120.975 91.725)
		(width 0.1)
		(layer "B.Cu")
		(net 200)
	)
	(arc
		(start 120.975 90.225)
		(mid 121.048223 90.401777)
		(end 121.225 90.475)
		(width 0.1)
		(layer "B.Cu")
		(net 200)
	)
	(arc
		(start 121.225 89.875)
		(mid 121.048223 89.948223)
		(end 120.975 90.125)
		(width 0.1)
		(layer "B.Cu")
		(net 200)
	)
	(arc
		(start 127.412984 84.5608)
		(mid 127.306918 84.604734)
		(end 127.262984 84.7108)
		(width 0.1)
		(layer "B.Cu")
		(net 200)
	)
	(arc
		(start 122.125 90.475)
		(mid 122.443198 90.606802)
		(end 122.575 90.925)
		(width 0.1)
		(layer "B.Cu")
		(net 200)
	)
	(arc
		(start 122.125 88.875)
		(mid 122.443198 89.006802)
		(end 122.575 89.325)
		(width 0.1)
		(layer "B.Cu")
		(net 200)
	)
	(arc
		(start 127.112984 84.9608)
		(mid 127.006918 84.916866)
		(end 126.962984 84.8108)
		(width 0.1)
		(layer "B.Cu")
		(net 200)
	)
	(arc
		(start 128.012984 84.5608)
		(mid 127.906918 84.604734)
		(end 127.862984 84.7108)
		(width 0.1)
		(layer "B.Cu")
		(net 200)
	)
	(arc
		(start 122.125 87.275)
		(mid 122.443198 87.406802)
		(end 122.575 87.725)
		(width 0.1)
		(layer "B.Cu")
		(net 200)
	)
	(arc
		(start 127.562984 84.7108)
		(mid 127.51905 84.604734)
		(end 127.412984 84.5608)
		(width 0.1)
		(layer "B.Cu")
		(net 200)
	)
	(arc
		(start 127.712984 84.9608)
		(mid 127.606918 84.916866)
		(end 127.562984 84.8108)
		(width 0.1)
		(layer "B.Cu")
		(net 200)
	)
	(arc
		(start 122.575 86.225)
		(mid 122.443198 86.543198)
		(end 122.125 86.675)
		(width 0.1)
		(layer "B.Cu")
		(net 200)
	)
	(arc
		(start 127.862984 84.8108)
		(mid 127.81905 84.916866)
		(end 127.712984 84.9608)
		(width 0.1)
		(layer "B.Cu")
		(net 200)
	)
	(arc
		(start 122.575 89.425)
		(mid 122.443198 89.743198)
		(end 122.125 89.875)
		(width 0.1)
		(layer "B.Cu")
		(net 200)
	)
	(arc
		(start 122.125 85.675)
		(mid 122.443198 85.806802)
		(end 122.575 86.125)
		(width 0.1)
		(layer "B.Cu")
		(net 200)
	)
	(arc
		(start 120.975 87.025)
		(mid 121.048223 87.201777)
		(end 121.225 87.275)
		(width 0.1)
		(layer "B.Cu")
		(net 200)
	)
	(arc
		(start 122.575 87.825)
		(mid 122.443198 88.143198)
		(end 122.125 88.275)
		(width 0.1)
		(layer "B.Cu")
		(net 200)
	)
	(arc
		(start 122.575 91.025)
		(mid 122.443198 91.343198)
		(end 122.125 91.475)
		(width 0.1)
		(layer "B.Cu")
		(net 200)
	)
	(arc
		(start 120.975 91.825)
		(mid 121.048223 92.001777)
		(end 121.225 92.075)
		(width 0.1)
		(layer "B.Cu")
		(net 200)
	)
	(arc
		(start 121.225 86.675)
		(mid 121.048223 86.748223)
		(end 120.975 86.925)
		(width 0.1)
		(layer "B.Cu")
		(net 200)
	)
	(arc
		(start 126.962984 84.7108)
		(mid 126.91905 84.604734)
		(end 126.812984 84.5608)
		(width 0.1)
		(layer "B.Cu")
		(net 200)
	)
	(segment
		(start 124.35 84.85)
		(end 124 84.85)
		(width 0.15)
		(layer "F.Cu")
		(net 201)
	)
	(segment
		(start 124.95 84.35)
		(end 124.6 84.35)
		(width 0.15)
		(layer "F.Cu")
		(net 201)
	)
	(segment
		(start 125.075 84.6)
		(end 125.075 84.475)
		(width 0.15)
		(layer "F.Cu")
		(net 201)
	)
	(segment
		(start 123.15 84.85)
		(end 122.8 84.85)
		(width 0.15)
		(layer "F.Cu")
		(net 201)
	)
	(segment
		(start 123.875 84.6)
		(end 123.875 84.475)
		(width 0.15)
		(layer "F.Cu")
		(net 201)
	)
	(segment
		(start 119.2 84.6)
		(end 117.625 86.175)
		(width 0.15)
		(layer "F.Cu")
		(net 201)
	)
	(segment
		(start 119.2 84.6)
		(end 121.35 84.6)
		(width 0.15)
		(layer "F.Cu")
		(net 201)
	)
	(segment
		(start 117.625 91.5245)
		(end 117.0995 92.05)
		(width 0.15)
		(layer "F.Cu")
		(net 201)
	)
	(segment
		(start 124.475 84.475)
		(end 124.475 84.6)
		(width 0.15)
		(layer "F.Cu")
		(net 201)
	)
	(segment
		(start 125.075 84.725)
		(end 125.075 84.6)
		(width 0.15)
		(layer "F.Cu")
		(net 201)
	)
	(segment
		(start 117.585 93.315)
		(end 117.0995 92.8295)
		(width 0.15)
		(layer "F.Cu")
		(net 201)
	)
	(segment
		(start 127.775 83.2)
		(end 127.7805 83.2)
		(width 0.09)
		(layer "F.Cu")
		(net 201)
	)
	(segment
		(start 122.675 84.6)
		(end 122.675 84.475)
		(width 0.15)
		(layer "F.Cu")
		(net 201)
	)
	(segment
		(start 117.0995 92.8295)
		(end 117.0995 92.05)
		(width 0.15)
		(layer "F.Cu")
		(net 201)
	)
	(segment
		(start 122.075 84.475)
		(end 122.075 84.6)
		(width 0.15)
		(layer "F.Cu")
		(net 201)
	)
	(segment
		(start 123.275 84.6)
		(end 123.275 84.725)
		(width 0.15)
		(layer "F.Cu")
		(net 201)
	)
	(segment
		(start 121.95 84.85)
		(end 121.6 84.85)
		(width 0.15)
		(layer "F.Cu")
		(net 201)
	)
	(segment
		(start 126.1005 84.6)
		(end 125.8 84.6)
		(width 0.15)
		(layer "F.Cu")
		(net 201)
	)
	(segment
		(start 122.675 84.725)
		(end 122.675 84.6)
		(width 0.15)
		(layer "F.Cu")
		(net 201)
	)
	(segment
		(start 124.475 84.6)
		(end 124.475 84.725)
		(width 0.15)
		(layer "F.Cu")
		(net 201)
	)
	(segment
		(start 117.625 86.175)
		(end 117.625 91.5245)
		(width 0.15)
		(layer "F.Cu")
		(net 201)
	)
	(segment
		(start 122.075 84.6)
		(end 122.075 84.725)
		(width 0.15)
		(layer "F.Cu")
		(net 201)
	)
	(segment
		(start 123.75 84.35)
		(end 123.4 84.35)
		(width 0.15)
		(layer "F.Cu")
		(net 201)
	)
	(segment
		(start 123.875 84.725)
		(end 123.875 84.6)
		(width 0.15)
		(layer "F.Cu")
		(net 201)
	)
	(segment
		(start 125.55 84.85)
		(end 125.2 84.85)
		(width 0.15)
		(layer "F.Cu")
		(net 201)
	)
	(segment
		(start 123.275 84.475)
		(end 123.275 84.6)
		(width 0.15)
		(layer "F.Cu")
		(net 201)
	)
	(segment
		(start 117.625 93.315)
		(end 117.585 93.315)
		(width 0.15)
		(layer "F.Cu")
		(net 201)
	)
	(segment
		(start 122.55 84.35)
		(end 122.2 84.35)
		(width 0.15)
		(layer "F.Cu")
		(net 201)
	)
	(via
		(at 126.1005 84.6)
		(size 0.4)
		(drill 0.2)
		(layers "F.Cu" "B.Cu")
		(net 201)
	)
	(via
		(at 127.7805 83.2)
		(size 0.4)
		(drill 0.2)
		(layers "F.Cu" "B.Cu")
		(net 201)
	)
	(via
		(at 117.0995 92.05)
		(size 0.4)
		(drill 0.2)
		(layers "F.Cu" "B.Cu")
		(net 201)
	)
	(via
		(at 122.275497 96.45)
		(size 0.4)
		(drill 0.2)
		(layers "F.Cu" "B.Cu")
		(net 201)
	)
	(arc
		(start 122.075 84.725)
		(mid 122.038388 84.813388)
		(end 121.95 84.85)
		(width 0.15)
		(layer "F.Cu")
		(net 201)
	)
	(arc
		(start 122.2 84.35)
		(mid 122.111612 84.386612)
		(end 122.075 84.475)
		(width 0.15)
		(layer "F.Cu")
		(net 201)
	)
	(arc
		(start 123.4 84.35)
		(mid 123.311612 84.386612)
		(end 123.275 84.475)
		(width 0.15)
		(layer "F.Cu")
		(net 201)
	)
	(arc
		(start 122.8 84.85)
		(mid 122.711612 84.813388)
		(end 122.675 84.725)
		(width 0.15)
		(layer "F.Cu")
		(net 201)
	)
	(arc
		(start 125.8 84.6)
		(mid 125.711612 84.636612)
		(end 125.675 84.725)
		(width 0.15)
		(layer "F.Cu")
		(net 201)
	)
	(arc
		(start 125.075 84.475)
		(mid 125.038388 84.386612)
		(end 124.95 84.35)
		(width 0.15)
		(layer "F.Cu")
		(net 201)
	)
	(arc
		(start 125.675 84.725)
		(mid 125.638388 84.813388)
		(end 125.55 84.85)
		(width 0.15)
		(layer "F.Cu")
		(net 201)
	)
	(arc
		(start 124.6 84.35)
		(mid 124.511612 84.386612)
		(end 124.475 84.475)
		(width 0.15)
		(layer "F.Cu")
		(net 201)
	)
	(arc
		(start 122.675 84.475)
		(mid 122.638388 84.386612)
		(end 122.55 84.35)
		(width 0.15)
		(layer "F.Cu")
		(net 201)
	)
	(arc
		(start 124 84.85)
		(mid 123.911612 84.813388)
		(end 123.875 84.725)
		(width 0.15)
		(layer "F.Cu")
		(net 201)
	)
	(arc
		(start 123.275 84.725)
		(mid 123.238388 84.813388)
		(end 123.15 84.85)
		(width 0.15)
		(layer "F.Cu")
		(net 201)
	)
	(arc
		(start 124.475 84.725)
		(mid 124.438388 84.813388)
		(end 124.35 84.85)
		(width 0.15)
		(layer "F.Cu")
		(net 201)
	)
	(arc
		(start 123.875 84.475)
		(mid 123.838388 84.386612)
		(end 123.75 84.35)
		(width 0.15)
		(layer "F.Cu")
		(net 201)
	)
	(arc
		(start 121.6 84.85)
		(mid 121.511612 84.813388)
		(end 121.475 84.725)
		(width 0.15)
		(layer "F.Cu")
		(net 201)
	)
	(arc
		(start 121.475 84.725)
		(mid 121.438388 84.636612)
		(end 121.35 84.6)
		(width 0.15)
		(layer "F.Cu")
		(net 201)
	)
	(arc
		(start 125.2 84.85)
		(mid 125.111612 84.813388)
		(end 125.075 84.725)
		(width 0.15)
		(layer "F.Cu")
		(net 201)
	)
	(segment
		(start 116.195 92.05)
		(end 116.165 92.02)
		(width 0.15)
		(layer "B.Cu")
		(net 201)
	)
	(segment
		(start 122.175 96.550497)
		(end 122.175 98.625)
		(width 0.15)
		(layer "B.Cu")
		(net 201)
	)
	(segment
		(start 117.0995 92.05)
		(end 116.195 92.05)
		(width 0.15)
		(layer "B.Cu")
		(net 201)
	)
	(segment
		(start 122.275497 96.45)
		(end 122.175 96.550497)
		(width 0.15)
		(layer "B.Cu")
		(net 201)
	)
	(segment
		(start 121.325497 95.5)
		(end 122.275497 96.45)
		(width 0.15)
		(layer "In3.Cu")
		(net 201)
	)
	(segment
		(start 120.525 95.5)
		(end 121.325497 95.5)
		(width 0.15)
		(layer "In3.Cu")
		(net 201)
	)
	(segment
		(start 119.625 94.6)
		(end 120.525 95.5)
		(width 0.15)
		(layer "In3.Cu")
		(net 201)
	)
	(segment
		(start 117.0995 92.8245)
		(end 118.875 94.6)
		(width 0.15)
		(layer "In3.Cu")
		(net 201)
	)
	(segment
		(start 117.0995 92.05)
		(end 117.0995 92.8245)
		(width 0.15)
		(layer "In3.Cu")
		(net 201)
	)
	(segment
		(start 126.1005 84.6)
		(end 127.5005 83.2)
		(width 0.15)
		(layer "In3.Cu")
		(net 201)
	)
	(segment
		(start 127.5005 83.2)
		(end 127.7805 83.2)
		(width 0.15)
		(layer "In3.Cu")
		(net 201)
	)
	(segment
		(start 118.875 94.6)
		(end 119.625 94.6)
		(width 0.15)
		(layer "In3.Cu")
		(net 201)
	)
	(segment
		(start 126.365688 87.692893)
		(end 126.365686 87.692894)
		(width 0.15)
		(layer "F.Cu")
		(net 202)
	)
	(segment
		(start 118.525 86.275)
		(end 119.6 85.2)
		(width 0.15)
		(layer "F.Cu")
		(net 202)
	)
	(segment
		(start 126.224263 88.117157)
		(end 126.082843 87.975737)
		(width 0.15)
		(layer "F.Cu")
		(net 202)
	)
	(segment
		(start 128 86.2)
		(end 128 86)
		(width 0.15)
		(layer "F.Cu")
		(net 202)
	)
	(segment
		(start 127.214215 86.702943)
		(end 127.355638 86.561521)
		(width 0.15)
		(layer "F.Cu")
		(net 202)
	)
	(segment
		(start 126.789949 87.55147)
		(end 126.789949 87.551471)
		(width 0.15)
		(layer "F.Cu")
		(net 202)
	)
	(segment
		(start 128.125 84.655025)
		(end 128.330025 84.45)
		(width 0.09)
		(layer "F.Cu")
		(net 202)
	)
	(segment
		(start 127.214214 86.702944)
		(end 127.214215 86.702943)
		(width 0.15)
		(layer "F.Cu")
		(net 202)
	)
	(segment
		(start 122.775 96.45)
		(end 122.925 96.6)
		(width 0.15)
		(layer "F.Cu")
		(net 202)
	)
	(segment
		(start 127.214214 87.268628)
		(end 127.355635 87.127206)
		(width 0.15)
		(layer "F.Cu")
		(net 202)
	)
	(segment
		(start 126.648527 87.834315)
		(end 126.648528 87.834314)
		(width 0.15)
		(layer "F.Cu")
		(net 202)
	)
	(segment
		(start 126.082842 87.834316)
		(end 126.082843 87.834315)
		(width 0.15)
		(layer "F.Cu")
		(net 202)
	)
	(segment
		(start 128 86)
		(end 128.125 85.875)
		(width 0.09)
		(layer "F.Cu")
		(net 202)
	)
	(segment
		(start 127.638479 86.561523)
		(end 127.63848 86.561522)
		(width 0.15)
		(layer "F.Cu")
		(net 202)
	)
	(segment
		(start 126.082842 88.4)
		(end 126.224263 88.258578)
		(width 0.15)
		(layer "F.Cu")
		(net 202)
	)
	(segment
		(start 126.648528 87.834314)
		(end 126.789949 87.692892)
		(width 0.15)
		(layer "F.Cu")
		(net 202)
	)
	(segment
		(start 126.224263 88.117156)
		(end 126.224263 88.117157)
		(width 0.15)
		(layer "F.Cu")
		(net 202)
	)
	(segment
		(start 125.94142 88.4)
		(end 125.941421 88.4)
		(width 0.15)
		(layer "F.Cu")
		(net 202)
	)
	(segment
		(start 126.648529 87.268629)
		(end 126.789952 87.127207)
		(width 0.15)
		(layer "F.Cu")
		(net 202)
	)
	(segment
		(start 127.49706 86.561521)
		(end 127.497058 86.561522)
		(width 0.15)
		(layer "F.Cu")
		(net 202)
	)
	(segment
		(start 125.6 88.4)
		(end 125.8 88.4)
		(width 0.15)
		(layer "F.Cu")
		(net 202)
	)
	(segment
		(start 127.355635 86.985785)
		(end 127.214215 86.844365)
		(width 0.15)
		(layer "F.Cu")
		(net 202)
	)
	(segment
		(start 126.931372 87.127208)
		(end 127.072792 87.268628)
		(width 0.15)
		(layer "F.Cu")
		(net 202)
	)
	(segment
		(start 122.925 96.6)
		(end 122.925 98.625)
		(width 0.15)
		(layer "F.Cu")
		(net 202)
	)
	(segment
		(start 126.931374 87.127207)
		(end 126.931372 87.127208)
		(width 0.15)
		(layer "F.Cu")
		(net 202)
	)
	(segment
		(start 128.330025 84.45)
		(end 129.425 84.45)
		(width 0.09)
		(layer "F.Cu")
		(net 202)
	)
	(segment
		(start 126.365686 87.692894)
		(end 126.507106 87.834314)
		(width 0.15)
		(layer "F.Cu")
		(net 202)
	)
	(segment
		(start 118.475 93.35)
		(end 118.475 92.75)
		(width 0.15)
		(layer "F.Cu")
		(net 202)
	)
	(segment
		(start 127.355635 86.985784)
		(end 127.355635 86.985785)
		(width 0.15)
		(layer "F.Cu")
		(net 202)
	)
	(segment
		(start 126.789949 87.551471)
		(end 126.648529 87.410051)
		(width 0.15)
		(layer "F.Cu")
		(net 202)
	)
	(segment
		(start 127.214213 87.268629)
		(end 127.214214 87.268628)
		(width 0.15)
		(layer "F.Cu")
		(net 202)
	)
	(segment
		(start 128.125 85.875)
		(end 128.125 84.655025)
		(width 0.09)
		(layer "F.Cu")
		(net 202)
	)
	(segment
		(start 129.425 84.45)
		(end 129.875 84)
		(width 0.09)
		(layer "F.Cu")
		(net 202)
	)
	(segment
		(start 126.648528 87.26863)
		(end 126.648529 87.268629)
		(width 0.15)
		(layer "F.Cu")
		(net 202)
	)
	(segment
		(start 127.63848 86.561522)
		(end 128 86.2)
		(width 0.15)
		(layer "F.Cu")
		(net 202)
	)
	(segment
		(start 119.6 85.2)
		(end 122.4 85.2)
		(width 0.15)
		(layer "F.Cu")
		(net 202)
	)
	(segment
		(start 126.082842 88.399999)
		(end 126.082842 88.4)
		(width 0.15)
		(layer "F.Cu")
		(net 202)
	)
	(segment
		(start 118.475 92.75)
		(end 118.525 92.7)
		(width 0.15)
		(layer "F.Cu")
		(net 202)
	)
	(segment
		(start 126.082843 87.834315)
		(end 126.224266 87.692893)
		(width 0.15)
		(layer "F.Cu")
		(net 202)
	)
	(segment
		(start 118.525 92.7)
		(end 118.525 86.275)
		(width 0.15)
		(layer "F.Cu")
		(net 202)
	)
	(segment
		(start 122.4 85.2)
		(end 125.6 88.4)
		(width 0.15)
		(layer "F.Cu")
		(net 202)
	)
	(via
		(at 122.775 96.45)
		(size 0.4)
		(drill 0.2)
		(layers "F.Cu" "B.Cu")
		(net 202)
	)
	(via
		(at 118.525 92.7)
		(size 0.4)
		(drill 0.2)
		(layers "F.Cu" "B.Cu")
		(net 202)
	)
	(arc
		(start 126.224263 88.258578)
		(mid 126.253552 88.187867)
		(end 126.224263 88.117156)
		(width 0.15)
		(layer "F.Cu")
		(net 202)
	)
	(arc
		(start 126.789949 87.692892)
		(mid 126.819238 87.622181)
		(end 126.789949 87.55147)
		(width 0.15)
		(layer "F.Cu")
		(net 202)
	)
	(arc
		(start 127.072792 87.268628)
		(mid 127.143502 87.297918)
		(end 127.214213 87.268629)
		(width 0.15)
		(layer "F.Cu")
		(net 202)
	)
	(arc
		(start 125.941421 88.4)
		(mid 126.012132 88.429289)
		(end 126.082842 88.399999)
		(width 0.15)
		(layer "F.Cu")
		(net 202)
	)
	(arc
		(start 127.214215 86.844365)
		(mid 127.184925 86.773655)
		(end 127.214214 86.702944)
		(width 0.15)
		(layer "F.Cu")
		(net 202)
	)
	(arc
		(start 127.355638 86.561521)
		(mid 127.426349 86.532232)
		(end 127.49706 86.561521)
		(width 0.15)
		(layer "F.Cu")
		(net 202)
	)
	(arc
		(start 127.355635 87.127206)
		(mid 127.384924 87.056495)
		(end 127.355635 86.985784)
		(width 0.15)
		(layer "F.Cu")
		(net 202)
	)
	(arc
		(start 126.789952 87.127207)
		(mid 126.860663 87.097918)
		(end 126.931374 87.127207)
		(width 0.15)
		(layer "F.Cu")
		(net 202)
	)
	(arc
		(start 126.224266 87.692893)
		(mid 126.294977 87.663604)
		(end 126.365688 87.692893)
		(width 0.15)
		(layer "F.Cu")
		(net 202)
	)
	(arc
		(start 126.507106 87.834314)
		(mid 126.577816 87.863604)
		(end 126.648527 87.834315)
		(width 0.15)
		(layer "F.Cu")
		(net 202)
	)
	(arc
		(start 127.497058 86.561522)
		(mid 127.567768 86.590812)
		(end 127.638479 86.561523)
		(width 0.15)
		(layer "F.Cu")
		(net 202)
	)
	(arc
		(start 125.8 88.4)
		(mid 125.87071 88.370711)
		(end 125.94142 88.4)
		(width 0.15)
		(layer "F.Cu")
		(net 202)
	)
	(arc
		(start 126.648529 87.410051)
		(mid 126.619239 87.339341)
		(end 126.648528 87.26863)
		(width 0.15)
		(layer "F.Cu")
		(net 202)
	)
	(arc
		(start 126.082843 87.975737)
		(mid 126.053553 87.905027)
		(end 126.082842 87.834316)
		(width 0.15)
		(layer "F.Cu")
		(net 202)
	)
	(segment
		(start 118.4875 92.7375)
		(end 118.525 92.7)
		(width 0.15)
		(layer "B.Cu")
		(net 202)
	)
	(segment
		(start 118.4875 93.35)
		(end 118.4875 92.7375)
		(width 0.15)
		(layer "B.Cu")
		(net 202)
	)
	(segment
		(start 120.175 94.75)
		(end 118.525 93.1)
		(width 0.15)
		(layer "In3.Cu")
		(net 202)
	)
	(segment
		(start 118.525 93.1)
		(end 118.525 92.7)
		(width 0.15)
		(layer "In3.Cu")
		(net 202)
	)
	(segment
		(start 122.775 96.334586)
		(end 121.190414 94.75)
		(width 0.15)
		(layer "In3.Cu")
		(net 202)
	)
	(segment
		(start 121.190414 94.75)
		(end 120.175 94.75)
		(width 0.15)
		(layer "In3.Cu")
		(net 202)
	)
	(segment
		(start 122.775 96.45)
		(end 122.775 96.334586)
		(width 0.15)
		(layer "In3.Cu")
		(net 202)
	)
	(segment
		(start 127.969365 88.407415)
		(end 127.792586 88.230636)
		(width 0.15)
		(layer "F.Cu")
		(net 203)
	)
	(segment
		(start 123.925 96.600994)
		(end 123.925 98.625)
		(width 0.15)
		(layer "F.Cu")
		(net 203)
	)
	(segment
		(start 123.774006 96.45)
		(end 123.925 96.600994)
		(width 0.15)
		(layer "F.Cu")
		(net 203)
	)
	(segment
		(start 129.171446 86.674999)
		(end 129.171446 86.675)
		(width 0.15)
		(layer "F.Cu")
		(net 203)
	)
	(segment
		(start 127.615809 88.230637)
		(end 127.615809 88.230636)
		(width 0.15)
		(layer "F.Cu")
		(net 203)
	)
	(segment
		(start 126.2 90)
		(end 125 90)
		(width 0.15)
		(layer "F.Cu")
		(net 203)
	)
	(segment
		(start 120.2 86.4)
		(end 119.625 86.975)
		(width 0.15)
		(layer "F.Cu")
		(net 203)
	)
	(segment
		(start 129.171446 86.675)
		(end 128.959313 86.887132)
		(width 0.15)
		(layer "F.Cu")
		(net 203)
	)
	(segment
		(start 126.625857 89.574139)
		(end 126.625858 89.574138)
		(width 0.15)
		(layer "F.Cu")
		(net 203)
	)
	(segment
		(start 129.525 85.85)
		(end 129.525 86.675)
		(width 0.15)
		(layer "F.Cu")
		(net 203)
	)
	(segment
		(start 127.403677 88.619545)
		(end 127.403676 88.619544)
		(width 0.15)
		(layer "F.Cu")
		(net 203)
	)
	(segment
		(start 127.580454 88.9731)
		(end 127.580454 88.973101)
		(width 0.15)
		(layer "F.Cu")
		(net 203)
	)
	(segment
		(start 128.181494 87.841726)
		(end 128.358273 88.018505)
		(width 0.15)
		(layer "F.Cu")
		(net 203)
	)
	(segment
		(start 127.191547 89.185233)
		(end 127.014768 89.008454)
		(width 0.15)
		(layer "F.Cu")
		(net 203)
	)
	(segment
		(start 128.393627 87.452819)
		(end 128.393627 87.452818)
		(width 0.15)
		(layer "F.Cu")
		(net 203)
	)
	(segment
		(start 128.959313 87.063908)
		(end 129.136091 87.240687)
		(width 0.15)
		(layer "F.Cu")
		(net 203)
	)
	(segment
		(start 119.6125 93.35)
		(end 119.6125 92.7125)
		(width 0.15)
		(layer "F.Cu")
		(net 203)
	)
	(segment
		(start 129.13609 87.417464)
		(end 129.13609 87.417465)
		(width 0.15)
		(layer "F.Cu")
		(net 203)
	)
	(segment
		(start 126.625858 89.574138)
		(end 126.2 90)
		(width 0.15)
		(layer "F.Cu")
		(net 203)
	)
	(segment
		(start 127.615809 88.230636)
		(end 127.403676 88.442768)
		(width 0.15)
		(layer "F.Cu")
		(net 203)
	)
	(segment
		(start 129.13609 87.417465)
		(end 128.923959 87.629597)
		(width 0.15)
		(layer "F.Cu")
		(net 203)
	)
	(segment
		(start 126.837991 89.008454)
		(end 126.625858 89.220586)
		(width 0.15)
		(layer "F.Cu")
		(net 203)
	)
	(segment
		(start 127.191546 89.185232)
		(end 127.191547 89.185233)
		(width 0.15)
		(layer "F.Cu")
		(net 203)
	)
	(segment
		(start 129.525 85.85)
		(end 129.525 85.455025)
		(width 0.09)
		(layer "F.Cu")
		(net 203)
	)
	(segment
		(start 129.525 85.455025)
		(end 129.730025 85.25)
		(width 0.09)
		(layer "F.Cu")
		(net 203)
	)
	(segment
		(start 119.625 86.975)
		(end 119.625 92.7)
		(width 0.15)
		(layer "F.Cu")
		(net 203)
	)
	(segment
		(start 129.348222 86.675)
		(end 129.348223 86.675)
		(width 0.15)
		(layer "F.Cu")
		(net 203)
	)
	(segment
		(start 119.6125 92.7125)
		(end 119.625 92.7)
		(width 0.15)
		(layer "F.Cu")
		(net 203)
	)
	(segment
		(start 127.403676 88.619544)
		(end 127.580455 88.796323)
		(width 0.15)
		(layer "F.Cu")
		(net 203)
	)
	(segment
		(start 128.358272 88.195282)
		(end 128.358272 88.195283)
		(width 0.15)
		(layer "F.Cu")
		(net 203)
	)
	(segment
		(start 125 90)
		(end 121.4 86.4)
		(width 0.15)
		(layer "F.Cu")
		(net 203)
	)
	(segment
		(start 128.747183 87.629597)
		(end 128.570404 87.452818)
		(width 0.15)
		(layer "F.Cu")
		(net 203)
	)
	(segment
		(start 128.959314 87.063909)
		(end 128.959313 87.063908)
		(width 0.15)
		(layer "F.Cu")
		(net 203)
	)
	(segment
		(start 126.837991 89.008455)
		(end 126.837991 89.008454)
		(width 0.15)
		(layer "F.Cu")
		(net 203)
	)
	(segment
		(start 128.358272 88.195283)
		(end 128.146141 88.407415)
		(width 0.15)
		(layer "F.Cu")
		(net 203)
	)
	(segment
		(start 130.125 85.25)
		(end 130.575 84.8)
		(width 0.09)
		(layer "F.Cu")
		(net 203)
	)
	(segment
		(start 121.4 86.4)
		(end 120.2 86.4)
		(width 0.15)
		(layer "F.Cu")
		(net 203)
	)
	(segment
		(start 127.580454 88.973101)
		(end 127.368323 89.185233)
		(width 0.15)
		(layer "F.Cu")
		(net 203)
	)
	(segment
		(start 128.181495 87.841727)
		(end 128.181494 87.841726)
		(width 0.15)
		(layer "F.Cu")
		(net 203)
	)
	(segment
		(start 129.730025 85.25)
		(end 130.125 85.25)
		(width 0.09)
		(layer "F.Cu")
		(net 203)
	)
	(segment
		(start 128.747182 87.629596)
		(end 128.747183 87.629597)
		(width 0.15)
		(layer "F.Cu")
		(net 203)
	)
	(segment
		(start 126.625859 89.397363)
		(end 126.625858 89.397362)
		(width 0.15)
		(layer "F.Cu")
		(net 203)
	)
	(segment
		(start 127.969364 88.407414)
		(end 127.969365 88.407415)
		(width 0.15)
		(layer "F.Cu")
		(net 203)
	)
	(segment
		(start 128.393627 87.452818)
		(end 128.181494 87.66495)
		(width 0.15)
		(layer "F.Cu")
		(net 203)
	)
	(via
		(at 119.625 92.7)
		(size 0.4)
		(drill 0.2)
		(layers "F.Cu" "B.Cu")
		(net 203)
	)
	(via
		(at 123.774006 96.45)
		(size 0.4)
		(drill 0.2)
		(layers "F.Cu" "B.Cu")
		(net 203)
	)
	(arc
		(start 128.923959 87.629597)
		(mid 128.83557 87.666208)
		(end 128.747182 87.629596)
		(width 0.15)
		(layer "F.Cu")
		(net 203)
	)
	(arc
		(start 127.580455 88.796323)
		(mid 127.617066 88.884712)
		(end 127.580454 88.9731)
		(width 0.15)
		(layer "F.Cu")
		(net 203)
	)
	(arc
		(start 127.403676 88.442768)
		(mid 127.367065 88.531157)
		(end 127.403677 88.619545)
		(width 0.15)
		(layer "F.Cu")
		(net 203)
	)
	(arc
		(start 128.570404 87.452818)
		(mid 128.482015 87.416207)
		(end 128.393627 87.452819)
		(width 0.15)
		(layer "F.Cu")
		(net 203)
	)
	(arc
		(start 127.792586 88.230636)
		(mid 127.704197 88.194025)
		(end 127.615809 88.230637)
		(width 0.15)
		(layer "F.Cu")
		(net 203)
	)
	(arc
		(start 129.348223 86.675)
		(mid 129.259835 86.638388)
		(end 129.171446 86.674999)
		(width 0.15)
		(layer "F.Cu")
		(net 203)
	)
	(arc
		(start 128.146141 88.407415)
		(mid 128.057752 88.444026)
		(end 127.969364 88.407414)
		(width 0.15)
		(layer "F.Cu")
		(net 203)
	)
	(arc
		(start 128.358273 88.018505)
		(mid 128.394884 88.106894)
		(end 128.358272 88.195282)
		(width 0.15)
		(layer "F.Cu")
		(net 203)
	)
	(arc
		(start 128.181494 87.66495)
		(mid 128.144883 87.753339)
		(end 128.181495 87.841727)
		(width 0.15)
		(layer "F.Cu")
		(net 203)
	)
	(arc
		(start 128.959313 86.887132)
		(mid 128.922702 86.975521)
		(end 128.959314 87.063909)
		(width 0.15)
		(layer "F.Cu")
		(net 203)
	)
	(arc
		(start 126.625858 89.220586)
		(mid 126.589247 89.308975)
		(end 126.625859 89.397363)
		(width 0.15)
		(layer "F.Cu")
		(net 203)
	)
	(arc
		(start 127.014768 89.008454)
		(mid 126.926379 88.971843)
		(end 126.837991 89.008455)
		(width 0.15)
		(layer "F.Cu")
		(net 203)
	)
	(arc
		(start 129.525 86.675)
		(mid 129.436611 86.711612)
		(end 129.348222 86.675)
		(width 0.15)
		(layer "F.Cu")
		(net 203)
	)
	(arc
		(start 126.625858 89.397362)
		(mid 126.662469 89.485751)
		(end 126.625857 89.574139)
		(width 0.15)
		(layer "F.Cu")
		(net 203)
	)
	(arc
		(start 129.136091 87.240687)
		(mid 129.172702 87.329076)
		(end 129.13609 87.417464)
		(width 0.15)
		(layer "F.Cu")
		(net 203)
	)
	(arc
		(start 127.368323 89.185233)
		(mid 127.279934 89.221844)
		(end 127.191546 89.185232)
		(width 0.15)
		(layer "F.Cu")
		(net 203)
	)
	(segment
		(start 119.625 93.35)
		(end 119.625 92.7)
		(width 0.15)
		(layer "B.Cu")
		(net 203)
	)
	(segment
		(start 120.675 94.05)
		(end 119.625 93)
		(width 0.15)
		(layer "In3.Cu")
		(net 203)
	)
	(segment
		(start 121.625 94.05)
		(end 120.675 94.05)
		(width 0.15)
		(layer "In3.Cu")
		(net 203)
	)
	(segment
		(start 119.625 93)
		(end 119.625 92.7)
		(width 0.15)
		(layer "In3.Cu")
		(net 203)
	)
	(segment
		(start 123.774006 96.199006)
		(end 121.625 94.05)
		(width 0.15)
		(layer "In3.Cu")
		(net 203)
	)
	(segment
		(start 123.774006 96.45)
		(end 123.774006 96.199006)
		(width 0.15)
		(layer "In3.Cu")
		(net 203)
	)
	(segment
		(start 121.226777 85.95)
		(end 121.226777 85.65)
		(width 0.15)
		(layer "F.Cu")
		(net 204)
	)
	(segment
		(start 124.740376 88.139334)
		(end 124.952509 88.351467)
		(width 0.15)
		(layer "F.Cu")
		(net 204)
	)
	(segment
		(start 125.13516 89.226579)
		(end 125.161739 89.2)
		(width 0.15)
		(layer "F.Cu")
		(net 204)
	)
	(segment
		(start 123.467577 87.502933)
		(end 123.679712 87.290802)
		(width 0.15)
		(layer "F.Cu")
		(net 204)
	)
	(segment
		(start 126 89.2)
		(end 128.825 86.375)
		(width 0.15)
		(layer "F.Cu")
		(net 204)
	)
	(segment
		(start 120 85.8)
		(end 120.476777 85.8)
		(width 0.15)
		(layer "F.Cu")
		(net 204)
	)
	(segment
		(start 124.740378 88.987867)
		(end 124.952511 89.2)
		(width 0.15)
		(layer "F.Cu")
		(net 204)
	)
	(segment
		(start 123.891844 87.290802)
		(end 124.103977 87.502935)
		(width 0.15)
		(layer "F.Cu")
		(net 204)
	)
	(segment
		(start 124.740378 88.775735)
		(end 124.952509 88.563599)
		(width 0.15)
		(layer "F.Cu")
		(net 204)
	)
	(segment
		(start 123.043312 87.078668)
		(end 123.255445 86.866535)
		(width 0.15)
		(layer "F.Cu")
		(net 204)
	)
	(segment
		(start 120.776777 86.1)
		(end 121.076777 86.1)
		(width 0.15)
		(layer "F.Cu")
		(net 204)
	)
	(segment
		(start 123.891844 87.9272)
		(end 124.103977 87.715067)
		(width 0.15)
		(layer "F.Cu")
		(net 204)
	)
	(segment
		(start 125.361739 89.4)
		(end 125.561739 89.4)
		(width 0.15)
		(layer "F.Cu")
		(net 204)
	)
	(segment
		(start 124.316109 88.351465)
		(end 124.528244 88.139334)
		(width 0.15)
		(layer "F.Cu")
		(net 204)
	)
	(segment
		(start 119.1125 92.7375)
		(end 119.075 92.7)
		(width 0.15)
		(layer "F.Cu")
		(net 204)
	)
	(segment
		(start 122.619047 86.44227)
		(end 122.619046 86.44227)
		(width 0.15)
		(layer "F.Cu")
		(net 204)
	)
	(segment
		(start 123.043312 87.2908)
		(end 123.255445 87.502933)
		(width 0.15)
		(layer "F.Cu")
		(net 204)
	)
	(segment
		(start 128.825 86.375)
		(end 128.825 85.8)
		(width 0.15)
		(layer "F.Cu")
		(net 204)
	)
	(segment
		(start 125.761739 89.2)
		(end 125.961739 89.2)
		(width 0.15)
		(layer "F.Cu")
		(net 204)
	)
	(segment
		(start 128.825 85.15)
		(end 129.175 84.8)
		(width 0.09)
		(layer "F.Cu")
		(net 204)
	)
	(segment
		(start 121.976777 85.8)
		(end 122.619047 86.44227)
		(width 0.15)
		(layer "F.Cu")
		(net 204)
	)
	(segment
		(start 119.075 92.7)
		(end 119.075 86.725)
		(width 0.15)
		(layer "F.Cu")
		(net 204)
	)
	(segment
		(start 124.952511 89.2)
		(end 124.952509 89.199999)
		(width 0.15)
		(layer "F.Cu")
		(net 204)
	)
	(segment
		(start 119.1125 93.35)
		(end 119.1125 92.7375)
		(width 0.15)
		(layer "F.Cu")
		(net 204)
	)
	(segment
		(start 128.825 85.8)
		(end 128.825 85.15)
		(width 0.09)
		(layer "F.Cu")
		(net 204)
	)
	(segment
		(start 125.961739 89.2)
		(end 126 89.2)
		(width 0.15)
		(layer "F.Cu")
		(net 204)
	)
	(segment
		(start 119.075 86.725)
		(end 120 85.8)
		(width 0.15)
		(layer "F.Cu")
		(net 204)
	)
	(segment
		(start 123.891844 88.139332)
		(end 124.103977 88.351465)
		(width 0.15)
		(layer "F.Cu")
		(net 204)
	)
	(segment
		(start 123.043312 86.44227)
		(end 123.255445 86.654403)
		(width 0.15)
		(layer "F.Cu")
		(net 204)
	)
	(segment
		(start 121.376777 85.5)
		(end 121.676777 85.5)
		(width 0.15)
		(layer "F.Cu")
		(net 204)
	)
	(via
		(at 123.274503 96.45)
		(size 0.4)
		(drill 0.2)
		(layers "F.Cu" "B.Cu")
		(net 204)
	)
	(via
		(at 119.075 92.7)
		(size 0.4)
		(drill 0.2)
		(layers "F.Cu" "B.Cu")
		(net 204)
	)
	(arc
		(start 121.676777 85.5)
		(mid 121.782843 85.543934)
		(end 121.826777 85.65)
		(width 0.15)
		(layer "F.Cu")
		(net 204)
	)
	(arc
		(start 121.226777 85.65)
		(mid 121.270711 85.543934)
		(end 121.376777 85.5)
		(width 0.15)
		(layer "F.Cu")
		(net 204)
	)
	(arc
		(start 121.076777 86.1)
		(mid 121.182843 86.056066)
		(end 121.226777 85.95)
		(width 0.15)
		(layer "F.Cu")
		(net 204)
	)
	(arc
		(start 123.043312 87.078668)
		(mid 122.999378 87.184734)
		(end 123.043312 87.2908)
		(width 0.15)
		(layer "F.Cu")
		(net 204)
	)
	(arc
		(start 123.255445 86.654403)
		(mid 123.299379 86.760469)
		(end 123.255445 86.866535)
		(width 0.15)
		(layer "F.Cu")
		(net 204)
	)
	(arc
		(start 123.255445 87.502933)
		(mid 123.361511 87.546867)
		(end 123.467577 87.502933)
		(width 0.15)
		(layer "F.Cu")
		(net 204)
	)
	(arc
		(start 125.161739 89.2)
		(mid 125.23245 89.229289)
		(end 125.261739 89.3)
		(width 0.15)
		(layer "F.Cu")
		(net 204)
	)
	(arc
		(start 125.261739 89.3)
		(mid 125.291028 89.370711)
		(end 125.361739 89.4)
		(width 0.15)
		(layer "F.Cu")
		(net 204)
	)
	(arc
		(start 120.626777 85.95)
		(mid 120.670711 86.056066)
		(end 120.776777 86.1)
		(width 0.15)
		(layer "F.Cu")
		(net 204)
	)
	(arc
		(start 122.83118 86.44227)
		(mid 122.937246 86.398336)
		(end 123.043312 86.44227)
		(width 0.15)
		(layer "F.Cu")
		(net 204)
	)
	(arc
		(start 124.103977 87.502935)
		(mid 124.147911 87.609001)
		(end 124.103977 87.715067)
		(width 0.15)
		(layer "F.Cu")
		(net 204)
	)
	(arc
		(start 124.952509 88.351467)
		(mid 124.996443 88.457533)
		(end 124.952509 88.563599)
		(width 0.15)
		(layer "F.Cu")
		(net 204)
	)
	(arc
		(start 124.740378 88.775735)
		(mid 124.696444 88.881801)
		(end 124.740378 88.987867)
		(width 0.15)
		(layer "F.Cu")
		(net 204)
	)
	(arc
		(start 125.661739 89.3)
		(mid 125.691028 89.229289)
		(end 125.761739 89.2)
		(width 0.15)
		(layer "F.Cu")
		(net 204)
	)
	(arc
		(start 123.891844 87.9272)
		(mid 123.84791 88.033266)
		(end 123.891844 88.139332)
		(width 0.15)
		(layer "F.Cu")
		(net 204)
	)
	(arc
		(start 123.679712 87.290802)
		(mid 123.785778 87.246868)
		(end 123.891844 87.290802)
		(width 0.15)
		(layer "F.Cu")
		(net 204)
	)
	(arc
		(start 125.561739 89.4)
		(mid 125.63245 89.370711)
		(end 125.661739 89.3)
		(width 0.15)
		(layer "F.Cu")
		(net 204)
	)
	(arc
		(start 121.826777 85.65)
		(mid 121.870711 85.756066)
		(end 121.976777 85.8)
		(width 0.15)
		(layer "F.Cu")
		(net 204)
	)
	(arc
		(start 122.619046 86.44227)
		(mid 122.725113 86.486204)
		(end 122.83118 86.44227)
		(width 0.15)
		(layer "F.Cu")
		(net 204)
	)
	(arc
		(start 124.528244 88.139334)
		(mid 124.63431 88.0954)
		(end 124.740376 88.139334)
		(width 0.15)
		(layer "F.Cu")
		(net 204)
	)
	(arc
		(start 124.103977 88.351465)
		(mid 124.210043 88.395399)
		(end 124.316109 88.351465)
		(width 0.15)
		(layer "F.Cu")
		(net 204)
	)
	(arc
		(start 124.952509 89.199999)
		(mid 125.038997 89.242651)
		(end 125.13516 89.226579)
		(width 0.15)
		(layer "F.Cu")
		(net 204)
	)
	(arc
		(start 120.476777 85.8)
		(mid 120.582843 85.843934)
		(end 120.626777 85.95)
		(width 0.15)
		(layer "F.Cu")
		(net 204)
	)
	(segment
		(start 119.125 93.35)
		(end 119.125 92.75)
		(width 0.15)
		(layer "B.Cu")
		(net 204)
	)
	(segment
		(start 119.125 92.75)
		(end 119.075 92.7)
		(width 0.15)
		(layer "B.Cu")
		(net 204)
	)
	(segment
		(start 123.274503 96.45)
		(end 123.175 96.549503)
		(width 0.15)
		(layer "B.Cu")
		(net 204)
	)
	(segment
		(start 123.175 96.549503)
		(end 123.175 98.625)
		(width 0.15)
		(layer "B.Cu")
		(net 204)
	)
	(segment
		(start 120.425 94.4)
		(end 121.425 94.4)
		(width 0.15)
		(layer "In3.Cu")
		(net 204)
	)
	(segment
		(start 123.274503 96.249503)
		(end 123.274503 96.45)
		(width 0.15)
		(layer "In3.Cu")
		(net 204)
	)
	(segment
		(start 119.075 92.7)
		(end 119.075 93.05)
		(width 0.15)
		(layer "In3.Cu")
		(net 204)
	)
	(segment
		(start 119.075 93.05)
		(end 120.425 94.4)
		(width 0.15)
		(layer "In3.Cu")
		(net 204)
	)
	(segment
		(start 121.425 94.4)
		(end 123.274503 96.249503)
		(width 0.15)
		(layer "In3.Cu")
		(net 204)
	)
	(segment
		(start 123.633267 89.138292)
		(end 123.633266 89.138291)
		(width 0.15)
		(layer "F.Cu")
		(net 205)
	)
	(segment
		(start 122.74938 89.244355)
		(end 122.749379 89.244354)
		(width 0.15)
		(layer "F.Cu")
		(net 205)
	)
	(segment
		(start 123.38578 89.633267)
		(end 123.385781 89.633269)
		(width 0.15)
		(layer "F.Cu")
		(net 205)
	)
	(segment
		(start 121 87)
		(end 120.4 87)
		(width 0.15)
		(layer "F.Cu")
		(net 205)
	)
	(segment
		(start 121.68871 87.441223)
		(end 121.688711 87.441223)
		(width 0.15)
		(layer "F.Cu")
		(net 205)
	)
	(segment
		(start 122.07762 87.582645)
		(end 121.936198 87.441223)
		(width 0.15)
		(layer "F.Cu")
		(net 205)
	)
	(segment
		(start 124.163602 90.41109)
		(end 124.163601 90.41109)
		(width 0.15)
		(layer "F.Cu")
		(net 205)
	)
	(segment
		(start 123.385781 89.633269)
		(end 123.633266 89.385779)
		(width 0.15)
		(layer "F.Cu")
		(net 205)
	)
	(segment
		(start 122.607957 88.855444)
		(end 122.607958 88.855446)
		(width 0.15)
		(layer "F.Cu")
		(net 205)
	)
	(segment
		(start 121.971556 88.466531)
		(end 121.830134 88.325109)
		(width 0.15)
		(layer "F.Cu")
		(net 205)
	)
	(segment
		(start 120.25 92.775)
		(end 120.25 93.35)
		(width 0.15)
		(layer "F.Cu")
		(net 205)
	)
	(segment
		(start 120.175 87.225)
		(end 120.175 92.7)
		(width 0.15)
		(layer "F.Cu")
		(net 205)
	)
	(segment
		(start 129.875 87.325)
		(end 126.4 90.8)
		(width 0.15)
		(layer "F.Cu")
		(net 205)
	)
	(segment
		(start 122.607958 88.855446)
		(end 122.855443 88.607956)
		(width 0.15)
		(layer "F.Cu")
		(net 205)
	)
	(segment
		(start 123.244356 88.996869)
		(end 123.244357 88.996869)
		(width 0.15)
		(layer "F.Cu")
		(net 205)
	)
	(segment
		(start 123.244357 88.996869)
		(end 122.996867 89.244354)
		(width 0.15)
		(layer "F.Cu")
		(net 205)
	)
	(segment
		(start 123.527203 90.022178)
		(end 123.527202 90.022177)
		(width 0.15)
		(layer "F.Cu")
		(net 205)
	)
	(segment
		(start 123.633266 89.138291)
		(end 123.491844 88.996869)
		(width 0.15)
		(layer "F.Cu")
		(net 205)
	)
	(segment
		(start 124.022179 89.774692)
		(end 124.02218 89.774692)
		(width 0.15)
		(layer "F.Cu")
		(net 205)
	)
	(segment
		(start 126.4 90.8)
		(end 124.8 90.8)
		(width 0.15)
		(layer "F.Cu")
		(net 205)
	)
	(segment
		(start 124.552513 90.799999)
		(end 124.552512 90.8)
		(width 0.15)
		(layer "F.Cu")
		(net 205)
	)
	(segment
		(start 124.02218 89.774692)
		(end 123.77469 90.022177)
		(width 0.15)
		(layer "F.Cu")
		(net 205)
	)
	(segment
		(start 124.411089 89.916114)
		(end 124.269667 89.774692)
		(width 0.15)
		(layer "F.Cu")
		(net 205)
	)
	(segment
		(start 121.830135 88.077623)
		(end 122.07762 87.830133)
		(width 0.15)
		(layer "F.Cu")
		(net 205)
	)
	(segment
		(start 124.163601 90.41109)
		(end 124.411089 90.163602)
		(width 0.15)
		(layer "F.Cu")
		(net 205)
	)
	(segment
		(start 122.077621 87.582646)
		(end 122.07762 87.582645)
		(width 0.15)
		(layer "F.Cu")
		(net 205)
	)
	(segment
		(start 122.855444 88.360469)
		(end 122.855443 88.360468)
		(width 0.15)
		(layer "F.Cu")
		(net 205)
	)
	(segment
		(start 122.466534 88.219046)
		(end 122.219044 88.466531)
		(width 0.15)
		(layer "F.Cu")
		(net 205)
	)
	(segment
		(start 129.875 85.6)
		(end 129.875 87.325)
		(width 0.15)
		(layer "F.Cu")
		(net 205)
	)
	(segment
		(start 123.527202 90.022177)
		(end 123.38578 89.880755)
		(width 0.15)
		(layer "F.Cu")
		(net 205)
	)
	(segment
		(start 120.175 92.7)
		(end 120.25 92.775)
		(width 0.15)
		(layer "F.Cu")
		(net 205)
	)
	(segment
		(start 124.41109 89.916115)
		(end 124.411089 89.916114)
		(width 0.15)
		(layer "F.Cu")
		(net 205)
	)
	(segment
		(start 124.305024 90.8)
		(end 124.163602 90.658578)
		(width 0.15)
		(layer "F.Cu")
		(net 205)
	)
	(segment
		(start 121.830134 88.077621)
		(end 121.830135 88.077623)
		(width 0.15)
		(layer "F.Cu")
		(net 205)
	)
	(segment
		(start 122.749379 89.244354)
		(end 122.607957 89.102932)
		(width 0.15)
		(layer "F.Cu")
		(net 205)
	)
	(segment
		(start 121.441223 87.441223)
		(end 121 87)
		(width 0.15)
		(layer "F.Cu")
		(net 205)
	)
	(segment
		(start 121.971557 88.466532)
		(end 121.971556 88.466531)
		(width 0.15)
		(layer "F.Cu")
		(net 205)
	)
	(segment
		(start 122.466533 88.219046)
		(end 122.466534 88.219046)
		(width 0.15)
		(layer "F.Cu")
		(net 205)
	)
	(segment
		(start 122.855443 88.360468)
		(end 122.714021 88.219046)
		(width 0.15)
		(layer "F.Cu")
		(net 205)
	)
	(segment
		(start 120.4 87)
		(end 120.175 87.225)
		(width 0.15)
		(layer "F.Cu")
		(net 205)
	)
	(via
		(at 124.273509 96.45)
		(size 0.4)
		(drill 0.2)
		(layers "F.Cu" "B.Cu")
		(net 205)
	)
	(via
		(at 120.175 92.7)
		(size 0.4)
		(drill 0.2)
		(layers "F.Cu" "B.Cu")
		(net 205)
	)
	(arc
		(start 122.219044 88.466531)
		(mid 122.095301 88.517788)
		(end 121.971557 88.466532)
		(width 0.15)
		(layer "F.Cu")
		(net 205)
	)
	(arc
		(start 121.936198 87.441223)
		(mid 121.812454 87.389967)
		(end 121.68871 87.441223)
		(width 0.15)
		(layer "F.Cu")
		(net 205)
	)
	(arc
		(start 122.714021 88.219046)
		(mid 122.590277 88.16779)
		(end 122.466533 88.219046)
		(width 0.15)
		(layer "F.Cu")
		(net 205)
	)
	(arc
		(start 121.830134 88.325109)
		(mid 121.778878 88.201365)
		(end 121.830134 88.077621)
		(width 0.15)
		(layer "F.Cu")
		(net 205)
	)
	(arc
		(start 124.269667 89.774692)
		(mid 124.145923 89.723436)
		(end 124.022179 89.774692)
		(width 0.15)
		(layer "F.Cu")
		(net 205)
	)
	(arc
		(start 122.855443 88.607956)
		(mid 122.9067 88.484213)
		(end 122.855444 88.360469)
		(width 0.15)
		(layer "F.Cu")
		(net 205)
	)
	(arc
		(start 123.38578 89.880755)
		(mid 123.334524 89.757011)
		(end 123.38578 89.633267)
		(width 0.15)
		(layer "F.Cu")
		(net 205)
	)
	(arc
		(start 122.996867 89.244354)
		(mid 122.873124 89.295611)
		(end 122.74938 89.244355)
		(width 0.15)
		(layer "F.Cu")
		(net 205)
	)
	(arc
		(start 123.77469 90.022177)
		(mid 123.650947 90.073434)
		(end 123.527203 90.022178)
		(width 0.15)
		(layer "F.Cu")
		(net 205)
	)
	(arc
		(start 124.411089 90.163602)
		(mid 124.462346 90.039859)
		(end 124.41109 89.916115)
		(width 0.15)
		(layer "F.Cu")
		(net 205)
	)
	(arc
		(start 121.688711 87.441223)
		(mid 121.564967 87.492479)
		(end 121.441223 87.441223)
		(width 0.15)
		(layer "F.Cu")
		(net 205)
	)
	(arc
		(start 123.491844 88.996869)
		(mid 123.3681 88.945613)
		(end 123.244356 88.996869)
		(width 0.15)
		(layer "F.Cu")
		(net 205)
	)
	(arc
		(start 123.633266 89.385779)
		(mid 123.684523 89.262036)
		(end 123.633267 89.138292)
		(width 0.15)
		(layer "F.Cu")
		(net 205)
	)
	(arc
		(start 122.07762 87.830133)
		(mid 122.128877 87.70639)
		(end 122.077621 87.582646)
		(width 0.15)
		(layer "F.Cu")
		(net 205)
	)
	(arc
		(start 124.552512 90.8)
		(mid 124.428768 90.851256)
		(end 124.305024 90.8)
		(width 0.15)
		(layer "F.Cu")
		(net 205)
	)
	(arc
		(start 124.163602 90.658578)
		(mid 124.112346 90.534834)
		(end 124.163602 90.41109)
		(width 0.15)
		(layer "F.Cu")
		(net 205)
	)
	(arc
		(start 124.8 90.8)
		(mid 124.676257 90.748743)
		(end 124.552513 90.799999)
		(width 0.15)
		(layer "F.Cu")
		(net 205)
	)
	(arc
		(start 122.607957 89.102932)
		(mid 122.556701 88.979188)
		(end 122.607957 88.855444)
		(width 0.15)
		(layer "F.Cu")
		(net 205)
	)
	(segment
		(start 120.2625 92.7875)
		(end 120.175 92.7)
		(width 0.15)
		(layer "B.Cu")
		(net 205)
	)
	(segment
		(start 124.175 96.548509)
		(end 124.175 98.625)
		(width 0.15)
		(layer "B.Cu")
		(net 205)
	)
	(segment
		(start 124.273509 96.45)
		(end 124.175 96.548509)
		(width 0.15)
		(layer "B.Cu")
		(net 205)
	)
	(segment
		(start 120.2625 93.35)
		(end 120.2625 92.7875)
		(width 0.15)
		(layer "B.Cu")
		(net 205)
	)
	(segment
		(start 124.273509 96.148509)
		(end 124.273509 96.45)
		(width 0.15)
		(layer "In3.Cu")
		(net 205)
	)
	(segment
		(start 120.875 93.7)
		(end 121.825 93.7)
		(width 0.15)
		(layer "In3.Cu")
		(net 205)
	)
	(segment
		(start 120.175 92.7)
		(end 120.175 93)
		(width 0.15)
		(layer "In3.Cu")
		(net 205)
	)
	(segment
		(start 120.175 93)
		(end 120.875 93.7)
		(width 0.15)
		(layer "In3.Cu")
		(net 205)
	)
	(segment
		(start 121.825 93.7)
		(end 124.273509 96.148509)
		(width 0.15)
		(layer "In3.Cu")
		(net 205)
	)
	(segment
		(start 149.4 87.482844)
		(end 149.117157 87.765688)
		(width 0.15)
		(layer "F.Cu")
		(net 206)
	)
	(segment
		(start 148.975735 87.765688)
		(end 148.834312 87.624266)
		(width 0.15)
		(layer "F.Cu")
		(net 206)
	)
	(segment
		(start 143.4 91.6)
		(end 139.675 87.875)
		(width 0.15)
		(layer "F.Cu")
		(net 206)
	)
	(segment
		(start 145.864454 90.594123)
		(end 146.005876 90.735546)
		(width 0.15)
		(layer "F.Cu")
		(net 206)
	)
	(segment
		(start 148.69289 87.624266)
		(end 148.410047 87.907108)
		(width 0.15)
		(layer "F.Cu")
		(net 206)
	)
	(segment
		(start 145.440191 91.159811)
		(end 145 91.6)
		(width 0.15)
		(layer "F.Cu")
		(net 206)
	)
	(segment
		(start 148.975736 87.765689)
		(end 148.975735 87.765688)
		(width 0.15)
		(layer "F.Cu")
		(net 206)
	)
	(segment
		(start 151.4 87.6)
		(end 150.8 87)
		(width 0.15)
		(layer "F.Cu")
		(net 206)
	)
	(segment
		(start 151.4 92.7)
		(end 151.325 92.775)
		(width 0.15)
		(layer "F.Cu")
		(net 206)
	)
	(segment
		(start 149.6 87)
		(end 149.4 87.2)
		(width 0.15)
		(layer "F.Cu")
		(net 206)
	)
	(segment
		(start 148.551469 88.331375)
		(end 148.268626 88.614219)
		(width 0.15)
		(layer "F.Cu")
		(net 206)
	)
	(segment
		(start 146.430142 90.311281)
		(end 146.288719 90.169859)
		(width 0.15)
		(layer "F.Cu")
		(net 206)
	)
	(segment
		(start 147.561515 88.89706)
		(end 147.561516 88.897061)
		(width 0.15)
		(layer "F.Cu")
		(net 206)
	)
	(segment
		(start 151.4 92.7)
		(end 151.4 87.6)
		(width 0.15)
		(layer "F.Cu")
		(net 206)
	)
	(segment
		(start 148.410046 88.048529)
		(end 148.410047 88.04853)
		(width 0.15)
		(layer "F.Cu")
		(net 206)
	)
	(segment
		(start 145.581612 91.159813)
		(end 145.581611 91.159812)
		(width 0.15)
		(layer "F.Cu")
		(net 206)
	)
	(segment
		(start 146.995828 89.321328)
		(end 146.712985 89.60417)
		(width 0.15)
		(layer "F.Cu")
		(net 206)
	)
	(segment
		(start 145 91.6)
		(end 143.4 91.6)
		(width 0.15)
		(layer "F.Cu")
		(net 206)
	)
	(segment
		(start 146.712985 89.745592)
		(end 146.854407 89.887015)
		(width 0.15)
		(layer "F.Cu")
		(net 206)
	)
	(segment
		(start 146.854407 90.028437)
		(end 146.571564 90.311281)
		(width 0.15)
		(layer "F.Cu")
		(net 206)
	)
	(segment
		(start 148.127204 88.614219)
		(end 147.985781 88.472797)
		(width 0.15)
		(layer "F.Cu")
		(net 206)
	)
	(segment
		(start 146.712984 89.745591)
		(end 146.712985 89.745592)
		(width 0.15)
		(layer "F.Cu")
		(net 206)
	)
	(segment
		(start 146.430143 90.311282)
		(end 146.430142 90.311281)
		(width 0.15)
		(layer "F.Cu")
		(net 206)
	)
	(segment
		(start 147.561516 88.897061)
		(end 147.702938 89.038484)
		(width 0.15)
		(layer "F.Cu")
		(net 206)
	)
	(segment
		(start 149.400001 87.482843)
		(end 149.4 87.482844)
		(width 0.15)
		(layer "F.Cu")
		(net 206)
	)
	(segment
		(start 147.278674 89.462751)
		(end 147.278673 89.46275)
		(width 0.15)
		(layer "F.Cu")
		(net 206)
	)
	(segment
		(start 147.844359 88.472797)
		(end 147.561516 88.755639)
		(width 0.15)
		(layer "F.Cu")
		(net 206)
	)
	(segment
		(start 150.8 87)
		(end 149.6 87)
		(width 0.15)
		(layer "F.Cu")
		(net 206)
	)
	(segment
		(start 139.675 87.875)
		(end 139.675 85.6)
		(width 0.15)
		(layer "F.Cu")
		(net 206)
	)
	(segment
		(start 145.44019 91.159813)
		(end 145.440191 91.159811)
		(width 0.15)
		(layer "F.Cu")
		(net 206)
	)
	(segment
		(start 146.005876 90.876968)
		(end 145.723033 91.159812)
		(width 0.15)
		(layer "F.Cu")
		(net 206)
	)
	(segment
		(start 146.147297 90.169859)
		(end 145.864454 90.452701)
		(width 0.15)
		(layer "F.Cu")
		(net 206)
	)
	(segment
		(start 148.410047 88.04853)
		(end 148.551469 88.189953)
		(width 0.15)
		(layer "F.Cu")
		(net 206)
	)
	(segment
		(start 148.127205 88.61422)
		(end 148.127204 88.614219)
		(width 0.15)
		(layer "F.Cu")
		(net 206)
	)
	(segment
		(start 147.702938 89.179906)
		(end 147.420095 89.46275)
		(width 0.15)
		(layer "F.Cu")
		(net 206)
	)
	(segment
		(start 147.301491 96.45)
		(end 147.4 96.548509)
		(width 0.15)
		(layer "F.Cu")
		(net 206)
	)
	(segment
		(start 151.325 92.775)
		(end 151.325 93.35)
		(width 0.15)
		(layer "F.Cu")
		(net 206)
	)
	(segment
		(start 145.864453 90.594122)
		(end 145.864454 90.594123)
		(width 0.15)
		(layer "F.Cu")
		(net 206)
	)
	(segment
		(start 147.278673 89.46275)
		(end 147.13725 89.321328)
		(width 0.15)
		(layer "F.Cu")
		(net 206)
	)
	(segment
		(start 147.4 96.548509)
		(end 147.4 98.625)
		(width 0.15)
		(layer "F.Cu")
		(net 206)
	)
	(via
		(at 151.4 92.7)
		(size 0.4)
		(drill 0.2)
		(layers "F.Cu" "B.Cu")
		(net 206)
	)
	(via
		(at 147.301491 96.45)
		(size 0.4)
		(drill 0.2)
		(layers "F.Cu" "B.Cu")
		(net 206)
	)
	(arc
		(start 148.834312 87.624266)
		(mid 148.763601 87.594977)
		(end 148.69289 87.624266)
		(width 0.15)
		(layer "F.Cu")
		(net 206)
	)
	(arc
		(start 146.005876 90.735546)
		(mid 146.035165 90.806257)
		(end 146.005876 90.876968)
		(width 0.15)
		(layer "F.Cu")
		(net 206)
	)
	(arc
		(start 147.702938 89.038484)
		(mid 147.732227 89.109195)
		(end 147.702938 89.179906)
		(width 0.15)
		(layer "F.Cu")
		(net 206)
	)
	(arc
		(start 147.420095 89.46275)
		(mid 147.349385 89.49204)
		(end 147.278674 89.462751)
		(width 0.15)
		(layer "F.Cu")
		(net 206)
	)
	(arc
		(start 149.4 87.2)
		(mid 149.370711 87.270711)
		(end 149.4 87.341422)
		(width 0.15)
		(layer "F.Cu")
		(net 206)
	)
	(arc
		(start 149.4 87.341422)
		(mid 149.42929 87.412132)
		(end 149.400001 87.482843)
		(width 0.15)
		(layer "F.Cu")
		(net 206)
	)
	(arc
		(start 149.117157 87.765688)
		(mid 149.046447 87.794978)
		(end 148.975736 87.765689)
		(width 0.15)
		(layer "F.Cu")
		(net 206)
	)
	(arc
		(start 147.561516 88.755639)
		(mid 147.532226 88.826349)
		(end 147.561515 88.89706)
		(width 0.15)
		(layer "F.Cu")
		(net 206)
	)
	(arc
		(start 146.571564 90.311281)
		(mid 146.500854 90.340571)
		(end 146.430143 90.311282)
		(width 0.15)
		(layer "F.Cu")
		(net 206)
	)
	(arc
		(start 148.410047 87.907108)
		(mid 148.380757 87.977818)
		(end 148.410046 88.048529)
		(width 0.15)
		(layer "F.Cu")
		(net 206)
	)
	(arc
		(start 146.854407 89.887015)
		(mid 146.883696 89.957726)
		(end 146.854407 90.028437)
		(width 0.15)
		(layer "F.Cu")
		(net 206)
	)
	(arc
		(start 146.712985 89.60417)
		(mid 146.683695 89.67488)
		(end 146.712984 89.745591)
		(width 0.15)
		(layer "F.Cu")
		(net 206)
	)
	(arc
		(start 148.551469 88.189953)
		(mid 148.580758 88.260664)
		(end 148.551469 88.331375)
		(width 0.15)
		(layer "F.Cu")
		(net 206)
	)
	(arc
		(start 145.723033 91.159812)
		(mid 145.652323 91.189102)
		(end 145.581612 91.159813)
		(width 0.15)
		(layer "F.Cu")
		(net 206)
	)
	(arc
		(start 148.268626 88.614219)
		(mid 148.197916 88.643509)
		(end 148.127205 88.61422)
		(width 0.15)
		(layer "F.Cu")
		(net 206)
	)
	(arc
		(start 145.581611 91.159812)
		(mid 145.5109 91.130523)
		(end 145.44019 91.159813)
		(width 0.15)
		(layer "F.Cu")
		(net 206)
	)
	(arc
		(start 146.288719 90.169859)
		(mid 146.218008 90.14057)
		(end 146.147297 90.169859)
		(width 0.15)
		(layer "F.Cu")
		(net 206)
	)
	(arc
		(start 145.864454 90.452701)
		(mid 145.835164 90.523411)
		(end 145.864453 90.594122)
		(width 0.15)
		(layer "F.Cu")
		(net 206)
	)
	(arc
		(start 147.985781 88.472797)
		(mid 147.91507 88.443508)
		(end 147.844359 88.472797)
		(width 0.15)
		(layer "F.Cu")
		(net 206)
	)
	(arc
		(start 147.13725 89.321328)
		(mid 147.066539 89.292039)
		(end 146.995828 89.321328)
		(width 0.15)
		(layer "F.Cu")
		(net 206)
	)
	(segment
		(start 151.3125 93.35)
		(end 151.3125 92.7875)
		(width 0.15)
		(layer "B.Cu")
		(net 206)
	)
	(segment
		(start 151.3125 92.7875)
		(end 151.4 92.7)
		(width 0.15)
		(layer "B.Cu")
		(net 206)
	)
	(segment
		(start 149.75 93.7)
		(end 147.301491 96.148509)
		(width 0.15)
		(layer "In3.Cu")
		(net 206)
	)
	(segment
		(start 151.4 92.7)
		(end 151.4 93)
		(width 0.15)
		(layer "In3.Cu")
		(net 206)
	)
	(segment
		(start 151.4 93)
		(end 150.7 93.7)
		(width 0.15)
		(layer "In3.Cu")
		(net 206)
	)
	(segment
		(start 147.301491 96.148509)
		(end 147.301491 96.45)
		(width 0.15)
		(layer "In3.Cu")
		(net 206)
	)
	(segment
		(start 150.7 93.7)
		(end 149.75 93.7)
		(width 0.15)
		(layer "In3.Cu")
		(net 206)
	)
	(segment
		(start 146.054411 88.722369)
		(end 146.054409 88.72237)
		(width 0.15)
		(layer "F.Cu")
		(net 207)
	)
	(segment
		(start 143.8 90)
		(end 140.725 86.925)
		(width 0.15)
		(layer "F.Cu")
		(net 207)
	)
	(segment
		(start 147.998958 86.424263)
		(end 147.998958 86.424264)
		(width 0.15)
		(layer "F.Cu")
		(net 207)
	)
	(segment
		(start 146.549384 87.697062)
		(end 146.549384 87.697061)
		(width 0.15)
		(layer "F.Cu")
		(net 207)
	)
	(segment
		(start 148.8 85.8)
		(end 148.6 86)
		(width 0.15)
		(layer "F.Cu")
		(net 207)
	)
	(segment
		(start 147.150427 87.272793)
		(end 147.150427 87.272794)
		(width 0.15)
		(layer "F.Cu")
		(net 207)
	)
	(segment
		(start 148.175735 86.77782)
		(end 147.928249 87.025307)
		(width 0.15)
		(layer "F.Cu")
		(net 207)
	)
	(segment
		(start 148.246446 86)
		(end 147.998958 86.247487)
		(width 0.15)
		(layer "F.Cu")
		(net 207)
	)
	(segment
		(start 148.423222 86)
		(end 148.423223 86)
		(width 0.15)
		(layer "F.Cu")
		(net 207)
	)
	(segment
		(start 144.6 90)
		(end 143.8 90)
		(width 0.15)
		(layer "F.Cu")
		(net 207)
	)
	(segment
		(start 147.327204 87.626351)
		(end 147.079718 87.873838)
		(width 0.15)
		(layer "F.Cu")
		(net 207)
	)
	(segment
		(start 145.877632 88.722371)
		(end 145.877633 88.72237)
		(width 0.15)
		(layer "F.Cu")
		(net 207)
	)
	(segment
		(start 140.725 85.15)
		(end 140.375 84.8)
		(width 0.09)
		(layer "F.Cu")
		(net 207)
	)
	(segment
		(start 146.478673 88.474882)
		(end 146.231187 88.722369)
		(width 0.15)
		(layer "F.Cu")
		(net 207)
	)
	(segment
		(start 147.397915 86.848531)
		(end 147.397915 86.84853)
		(width 0.15)
		(layer "F.Cu")
		(net 207)
	)
	(segment
		(start 148.4 96.549503)
		(end 148.4 98.625)
		(width 0.15)
		(layer "F.Cu")
		(net 207)
	)
	(segment
		(start 146.90294 87.873839)
		(end 146.726161 87.697061)
		(width 0.15)
		(layer "F.Cu")
		(net 207)
	)
	(segment
		(start 148.175735 86.777819)
		(end 148.175735 86.77782)
		(width 0.15)
		(layer "F.Cu")
		(net 207)
	)
	(segment
		(start 146.301896 88.121325)
		(end 146.478674 88.298104)
		(width 0.15)
		(layer "F.Cu")
		(net 207)
	)
	(segment
		(start 146.301896 88.121324)
		(end 146.301896 88.121325)
		(width 0.15)
		(layer "F.Cu")
		(net 207)
	)
	(segment
		(start 145.877633 88.72237)
		(end 144.6 90)
		(width 0.15)
		(layer "F.Cu")
		(net 207)
	)
	(segment
		(start 152.5 86.9)
		(end 151.4 85.8)
		(width 0.15)
		(layer "F.Cu")
		(net 207)
	)
	(segment
		(start 147.751471 87.025308)
		(end 147.574692 86.84853)
		(width 0.15)
		(layer "F.Cu")
		(net 207)
	)
	(segment
		(start 151.4 85.8)
		(end 148.8 85.8)
		(width 0.15)
		(layer "F.Cu")
		(net 207)
	)
	(segment
		(start 147.998958 86.424264)
		(end 148.175736 86.601042)
		(width 0.15)
		(layer "F.Cu")
		(net 207)
	)
	(segment
		(start 146.902942 87.873838)
		(end 146.90294 87.873839)
		(width 0.15)
		(layer "F.Cu")
		(net 207)
	)
	(segment
		(start 152.4625 92.7375)
		(end 152.5 92.7)
		(width 0.15)
		(layer "F.Cu")
		(net 207)
	)
	(segment
		(start 140.725 86.925)
		(end 140.725 85.9)
		(width 0.15)
		(layer "F.Cu")
		(net 207)
	)
	(segment
		(start 146.478673 88.474881)
		(end 146.478673 88.474882)
		(width 0.15)
		(layer "F.Cu")
		(net 207)
	)
	(segment
		(start 152.5 92.7)
		(end 152.5 86.9)
		(width 0.15)
		(layer "F.Cu")
		(net 207)
	)
	(segment
		(start 140.725 85.9)
		(end 140.725 85.15)
		(width 0.09)
		(layer "F.Cu")
		(net 207)
	)
	(segment
		(start 148.246446 85.999999)
		(end 148.246446 86)
		(width 0.15)
		(layer "F.Cu")
		(net 207)
	)
	(segment
		(start 147.751473 87.025307)
		(end 147.751471 87.025308)
		(width 0.15)
		(layer "F.Cu")
		(net 207)
	)
	(segment
		(start 147.327204 87.62635)
		(end 147.327204 87.626351)
		(width 0.15)
		(layer "F.Cu")
		(net 207)
	)
	(segment
		(start 146.549384 87.697061)
		(end 146.301896 87.944548)
		(width 0.15)
		(layer "F.Cu")
		(net 207)
	)
	(segment
		(start 152.4625 93.35)
		(end 152.4625 92.7375)
		(width 0.15)
		(layer "F.Cu")
		(net 207)
	)
	(segment
		(start 147.397915 86.84853)
		(end 147.150427 87.096017)
		(width 0.15)
		(layer "F.Cu")
		(net 207)
	)
	(segment
		(start 147.150427 87.272794)
		(end 147.327205 87.449573)
		(width 0.15)
		(layer "F.Cu")
		(net 207)
	)
	(segment
		(start 148.300497 96.45)
		(end 148.4 96.549503)
		(width 0.15)
		(layer "F.Cu")
		(net 207)
	)
	(via
		(at 148.300497 96.45)
		(size 0.4)
		(drill 0.2)
		(layers "F.Cu" "B.Cu")
		(net 207)
	)
	(via
		(at 152.5 92.7)
		(size 0.4)
		(drill 0.2)
		(layers "F.Cu" "B.Cu")
		(net 207)
	)
	(arc
		(start 147.327205 87.449573)
		(mid 147.363816 87.537962)
		(end 147.327204 87.62635)
		(width 0.15)
		(layer "F.Cu")
		(net 207)
	)
	(arc
		(start 148.6 86)
		(mid 148.511611 86.036612)
		(end 148.423222 86)
		(width 0.15)
		(layer "F.Cu")
		(net 207)
	)
	(arc
		(start 147.928249 87.025307)
		(mid 147.839861 87.061919)
		(end 147.751473 87.025307)
		(width 0.15)
		(layer "F.Cu")
		(net 207)
	)
	(arc
		(start 146.231187 88.722369)
		(mid 146.142799 88.758981)
		(end 146.054411 88.722369)
		(width 0.15)
		(layer "F.Cu")
		(net 207)
	)
	(arc
		(start 147.574692 86.84853)
		(mid 147.486303 86.811919)
		(end 147.397915 86.848531)
		(width 0.15)
		(layer "F.Cu")
		(net 207)
	)
	(arc
		(start 147.150427 87.096017)
		(mid 147.113815 87.184405)
		(end 147.150427 87.272793)
		(width 0.15)
		(layer "F.Cu")
		(net 207)
	)
	(arc
		(start 146.478674 88.298104)
		(mid 146.515285 88.386493)
		(end 146.478673 88.474881)
		(width 0.15)
		(layer "F.Cu")
		(net 207)
	)
	(arc
		(start 147.998958 86.247487)
		(mid 147.962346 86.335875)
		(end 147.998958 86.424263)
		(width 0.15)
		(layer "F.Cu")
		(net 207)
	)
	(arc
		(start 146.726161 87.697061)
		(mid 146.637772 87.66045)
		(end 146.549384 87.697062)
		(width 0.15)
		(layer "F.Cu")
		(net 207)
	)
	(arc
		(start 146.054409 88.72237)
		(mid 145.96602 88.685759)
		(end 145.877632 88.722371)
		(width 0.15)
		(layer "F.Cu")
		(net 207)
	)
	(arc
		(start 146.301896 87.944548)
		(mid 146.265284 88.032936)
		(end 146.301896 88.121324)
		(width 0.15)
		(layer "F.Cu")
		(net 207)
	)
	(arc
		(start 148.423223 86)
		(mid 148.334835 85.963388)
		(end 148.246446 85.999999)
		(width 0.15)
		(layer "F.Cu")
		(net 207)
	)
	(arc
		(start 147.079718 87.873838)
		(mid 146.99133 87.91045)
		(end 146.902942 87.873838)
		(width 0.15)
		(layer "F.Cu")
		(net 207)
	)
	(arc
		(start 148.175736 86.601042)
		(mid 148.212347 86.689431)
		(end 148.175735 86.777819)
		(width 0.15)
		(layer "F.Cu")
		(net 207)
	)
	(segment
		(start 152.45 93.35)
		(end 152.45 92.75)
		(width 0.15)
		(layer "B.Cu")
		(net 207)
	)
	(segment
		(start 152.45 92.75)
		(end 152.5 92.7)
		(width 0.15)
		(layer "B.Cu")
		(net 207)
	)
	(segment
		(start 150.15 94.4)
		(end 148.300497 96.249503)
		(width 0.15)
		(layer "In3.Cu")
		(net 207)
	)
	(segment
		(start 152.5 93.05)
		(end 151.15 94.4)
		(width 0.15)
		(layer "In3.Cu")
		(net 207)
	)
	(segment
		(start 148.300497 96.249503)
		(end 148.300497 96.45)
		(width 0.15)
		(layer "In3.Cu")
		(net 207)
	)
	(segment
		(start 151.15 94.4)
		(end 150.15 94.4)
		(width 0.15)
		(layer "In3.Cu")
		(net 207)
	)
	(segment
		(start 152.5 92.7)
		(end 152.5 93.05)
		(width 0.15)
		(layer "In3.Cu")
		(net 207)
	)
	(segment
		(start 140 85.8)
		(end 140.025 85.775)
		(width 0.09)
		(layer "F.Cu")
		(net 208)
	)
	(segment
		(start 142.421315 89.762738)
		(end 142.421316 89.762737)
		(width 0.15)
		(layer "F.Cu")
		(net 208)
	)
	(segment
		(start 141.572789 88.914212)
		(end 141.57279 88.914211)
		(width 0.15)
		(layer "F.Cu")
		(net 208)
	)
	(segment
		(start 144.8 90.8)
		(end 149.2 86.4)
		(width 0.15)
		(layer "F.Cu")
		(net 208)
	)
	(segment
		(start 139.425 85.25)
		(end 138.975 84.8)
		(width 0.09)
		(layer "F.Cu")
		(net 208)
	)
	(segment
		(start 151.9625 93.35)
		(end 151.9625 92.7125)
		(width 0.15)
		(layer "F.Cu")
		(net 208)
	)
	(segment
		(start 140.299999 87.641421)
		(end 140.3 87.641421)
		(width 0.15)
		(layer "F.Cu")
		(net 208)
	)
	(segment
		(start 141.855633 88.77279)
		(end 142.138475 89.055632)
		(width 0.15)
		(layer "F.Cu")
		(net 208)
	)
	(segment
		(start 141.289949 88.348528)
		(end 141.148526 88.489947)
		(width 0.15)
		(layer "F.Cu")
		(net 208)
	)
	(segment
		(start 140.025 85.455025)
		(end 139.819975 85.25)
		(width 0.09)
		(layer "F.Cu")
		(net 208)
	)
	(segment
		(start 149.2 86.4)
		(end 151.2 86.4)
		(width 0.15)
		(layer "F.Cu")
		(net 208)
	)
	(segment
		(start 151.2 86.4)
		(end 151.95 87.15)
		(width 0.15)
		(layer "F.Cu")
		(net 208)
	)
	(segment
		(start 141.148526 88.631369)
		(end 141.431368 88.914211)
		(width 0.15)
		(layer "F.Cu")
		(net 208)
	)
	(segment
		(start 140.025 85.775)
		(end 140.025 85.455025)
		(width 0.09)
		(layer "F.Cu")
		(net 208)
	)
	(segment
		(start 142.138476 89.197053)
		(end 142.138475 89.197054)
		(width 0.15)
		(layer "F.Cu")
		(net 208)
	)
	(segment
		(start 142.562737 89.762737)
		(end 143.6 90.8)
		(width 0.15)
		(layer "F.Cu")
		(net 208)
	)
	(segment
		(start 141.997052 89.479895)
		(end 142.279894 89.762737)
		(width 0.15)
		(layer "F.Cu")
		(net 208)
	)
	(segment
		(start 140.724264 88.065684)
		(end 140.865683 87.924262)
		(width 0.15)
		(layer "F.Cu")
		(net 208)
	)
	(segment
		(start 141.57279 88.914211)
		(end 141.714209 88.772788)
		(width 0.15)
		(layer "F.Cu")
		(net 208)
	)
	(segment
		(start 140.3 87.782841)
		(end 140.3 87.782842)
		(width 0.15)
		(layer "F.Cu")
		(net 208)
	)
	(segment
		(start 139.819975 85.25)
		(end 139.425 85.25)
		(width 0.09)
		(layer "F.Cu")
		(net 208)
	)
	(segment
		(start 141.28995 88.348527)
		(end 141.289949 88.348528)
		(width 0.15)
		(layer "F.Cu")
		(net 208)
	)
	(segment
		(start 140.724263 88.065685)
		(end 140.724264 88.065684)
		(width 0.15)
		(layer "F.Cu")
		(net 208)
	)
	(segment
		(start 143.6 90.8)
		(end 144.8 90.8)
		(width 0.15)
		(layer "F.Cu")
		(net 208)
	)
	(segment
		(start 142.562736 89.762737)
		(end 142.562737 89.762737)
		(width 0.15)
		(layer "F.Cu")
		(net 208)
	)
	(segment
		(start 140 87.2)
		(end 140.3 87.5)
		(width 0.15)
		(layer "F.Cu")
		(net 208)
	)
	(segment
		(start 141.007107 87.924264)
		(end 141.289949 88.207106)
		(width 0.15)
		(layer "F.Cu")
		(net 208)
	)
	(segment
		(start 151.95 87.15)
		(end 151.95 92.7)
		(width 0.15)
		(layer "F.Cu")
		(net 208)
	)
	(segment
		(start 140.3 87.782842)
		(end 140.582842 88.065684)
		(width 0.15)
		(layer "F.Cu")
		(net 208)
	)
	(segment
		(start 140 85.8)
		(end 140 87.2)
		(width 0.15)
		(layer "F.Cu")
		(net 208)
	)
	(segment
		(start 142.138475 89.197054)
		(end 141.997052 89.338473)
		(width 0.15)
		(layer "F.Cu")
		(net 208)
	)
	(segment
		(start 151.9625 92.7125)
		(end 151.95 92.7)
		(width 0.15)
		(layer "F.Cu")
		(net 208)
	)
	(via
		(at 151.95 92.7)
		(size 0.4)
		(drill 0.2)
		(layers "F.Cu" "B.Cu")
		(net 208)
	)
	(via
		(at 147.800994 96.45)
		(size 0.4)
		(drill 0.2)
		(layers "F.Cu" "B.Cu")
		(net 208)
	)
	(arc
		(start 141.148526 88.489947)
		(mid 141.119237 88.560658)
		(end 141.148526 88.631369)
		(width 0.15)
		(layer "F.Cu")
		(net 208)
	)
	(arc
		(start 140.3 87.641421)
		(mid 140.270711 87.712131)
		(end 140.3 87.782841)
		(width 0.15)
		(layer "F.Cu")
		(net 208)
	)
	(arc
		(start 140.582842 88.065684)
		(mid 140.653552 88.094974)
		(end 140.724263 88.065685)
		(width 0.15)
		(layer "F.Cu")
		(net 208)
	)
	(arc
		(start 142.279894 89.762737)
		(mid 142.350604 89.792027)
		(end 142.421315 89.762738)
		(width 0.15)
		(layer "F.Cu")
		(net 208)
	)
	(arc
		(start 141.431368 88.914211)
		(mid 141.502078 88.943501)
		(end 141.572789 88.914212)
		(width 0.15)
		(layer "F.Cu")
		(net 208)
	)
	(arc
		(start 141.997052 89.338473)
		(mid 141.967763 89.409184)
		(end 141.997052 89.479895)
		(width 0.15)
		(layer "F.Cu")
		(net 208)
	)
	(arc
		(start 142.138475 89.055632)
		(mid 142.167765 89.126342)
		(end 142.138476 89.197053)
		(width 0.15)
		(layer "F.Cu")
		(net 208)
	)
	(arc
		(start 140.865683 87.924262)
		(mid 140.936396 87.894975)
		(end 141.007107 87.924264)
		(width 0.15)
		(layer "F.Cu")
		(net 208)
	)
	(arc
		(start 141.714209 88.772788)
		(mid 141.784922 88.743501)
		(end 141.855633 88.77279)
		(width 0.15)
		(layer "F.Cu")
		(net 208)
	)
	(arc
		(start 140.3 87.5)
		(mid 140.329289 87.570711)
		(end 140.299999 87.641421)
		(width 0.15)
		(layer "F.Cu")
		(net 208)
	)
	(arc
		(start 141.289949 88.207106)
		(mid 141.319239 88.277816)
		(end 141.28995 88.348527)
		(width 0.15)
		(layer "F.Cu")
		(net 208)
	)
	(arc
		(start 142.421316 89.762737)
		(mid 142.492026 89.733448)
		(end 142.562736 89.762737)
		(width 0.15)
		(layer "F.Cu")
		(net 208)
	)
	(segment
		(start 147.800994 96.45)
		(end 147.65 96.600994)
		(width 0.15)
		(layer "B.Cu")
		(net 208)
	)
	(segment
		(start 147.65 96.600994)
		(end 147.65 98.625)
		(width 0.15)
		(layer "B.Cu")
		(net 208)
	)
	(segment
		(start 151.95 93.35)
		(end 151.95 92.7)
		(width 0.15)
		(layer "B.Cu")
		(net 208)
	)
	(segment
		(start 149.95 94.05)
		(end 150.9 94.05)
		(width 0.15)
		(layer "In3.Cu")
		(net 208)
	)
	(segment
		(start 150.9 94.05)
		(end 151.95 93)
		(width 0.15)
		(layer "In3.Cu")
		(net 208)
	)
	(segment
		(start 151.95 93)
		(end 151.95 92.7)
		(width 0.15)
		(layer "In3.Cu")
		(net 208)
	)
	(segment
		(start 147.800994 96.45)
		(end 147.800994 96.199006)
		(width 0.15)
		(layer "In3.Cu")
		(net 208)
	)
	(segment
		(start 147.800994 96.199006)
		(end 149.95 94.05)
		(width 0.15)
		(layer "In3.Cu")
		(net 208)
	)
	(segment
		(start 153.1 93.35)
		(end 153.1 92.75)
		(width 0.15)
		(layer "F.Cu")
		(net 209)
	)
	(segment
		(start 148.4 85.2)
		(end 151.6 85.2)
		(width 0.15)
		(layer "F.Cu")
		(net 209)
	)
	(segment
		(start 141.425 85.775)
		(end 141.425 84.655025)
		(width 0.09)
		(layer "F.Cu")
		(net 209)
	)
	(segment
		(start 142.636396 87.2)
		(end 142.742462 87.306066)
		(width 0.15)
		(layer "F.Cu")
		(net 209)
	)
	(segment
		(start 142.318199 87.199999)
		(end 142.318198 87.2)
		(width 0.15)
		(layer "F.Cu")
		(net 209)
	)
	(segment
		(start 141.219975 84.45)
		(end 140.125 84.45)
		(width 0.09)
		(layer "F.Cu")
		(net 209)
	)
	(segment
		(start 144.4 89.2)
		(end 148.4 85.2)
		(width 0.15)
		(layer "F.Cu")
		(net 209)
	)
	(segment
		(start 153.05 86.65)
		(end 153.05 92.7)
		(width 0.15)
		(layer "F.Cu")
		(net 209)
	)
	(segment
		(start 140.125 84.45)
		(end 139.675 84)
		(width 0.09)
		(layer "F.Cu")
		(net 209)
	)
	(segment
		(start 141.4 85.8)
		(end 141.4 86.6)
		(width 0.15)
		(layer "F.Cu")
		(net 209)
	)
	(segment
		(start 141.425 84.655025)
		(end 141.219975 84.45)
		(width 0.09)
		(layer "F.Cu")
		(net 209)
	)
	(segment
		(start 142.742461 87.624265)
		(end 142.742462 87.624264)
		(width 0.15)
		(layer "F.Cu")
		(net 209)
	)
	(segment
		(start 142.848528 88.048528)
		(end 144 89.2)
		(width 0.15)
		(layer "F.Cu")
		(net 209)
	)
	(segment
		(start 144 89.2)
		(end 144.4 89.2)
		(width 0.15)
		(layer "F.Cu")
		(net 209)
	)
	(segment
		(start 141.4 85.8)
		(end 141.425 85.775)
		(width 0.09)
		(layer "F.Cu")
		(net 209)
	)
	(segment
		(start 151.6 85.2)
		(end 153.05 86.65)
		(width 0.15)
		(layer "F.Cu")
		(net 209)
	)
	(segment
		(start 141.4 86.6)
		(end 142 87.2)
		(width 0.15)
		(layer "F.Cu")
		(net 209)
	)
	(segment
		(start 142.742462 87.942462)
		(end 142.848528 88.048528)
		(width 0.15)
		(layer "F.Cu")
		(net 209)
	)
	(segment
		(start 153.1 92.75)
		(end 153.05 92.7)
		(width 0.15)
		(layer "F.Cu")
		(net 209)
	)
	(via
		(at 148.8 96.45)
		(size 0.4)
		(drill 0.2)
		(layers "F.Cu" "B.Cu")
		(net 209)
	)
	(via
		(at 153.05 92.7)
		(size 0.4)
		(drill 0.2)
		(layers "F.Cu" "B.Cu")
		(net 209)
	)
	(arc
		(start 142.742462 87.306066)
		(mid 142.808364 87.465167)
		(end 142.742461 87.624265)
		(width 0.15)
		(layer "F.Cu")
		(net 209)
	)
	(arc
		(start 142.742462 87.624264)
		(mid 142.676561 87.783363)
		(end 142.742462 87.942462)
		(width 0.15)
		(layer "F.Cu")
		(net 209)
	)
	(arc
		(start 142.318198 87.2)
		(mid 142.477297 87.134099)
		(end 142.636396 87.2)
		(width 0.15)
		(layer "F.Cu")
		(net 209)
	)
	(arc
		(start 142 87.2)
		(mid 142.159101 87.265902)
		(end 142.318199 87.199999)
		(width 0.15)
		(layer "F.Cu")
		(net 209)
	)
	(segment
		(start 148.8 96.45)
		(end 148.65 96.6)
		(width 0.15)
		(layer "B.Cu")
		(net 209)
	)
	(segment
		(start 148.65 96.6)
		(end 148.65 98.625)
		(width 0.15)
		(layer "B.Cu")
		(net 209)
	)
	(segment
		(start 153.0875 92.7375)
		(end 153.05 92.7)
		(width 0.15)
		(layer "B.Cu")
		(net 209)
	)
	(segment
		(start 153.0875 93.35)
		(end 153.0875 92.7375)
		(width 0.15)
		(layer "B.Cu")
		(net 209)
	)
	(segment
		(start 148.8 96.334586)
		(end 150.384586 94.75)
		(width 0.15)
		(layer "In3.Cu")
		(net 209)
	)
	(segment
		(start 148.8 96.45)
		(end 148.8 96.334586)
		(width 0.15)
		(layer "In3.Cu")
		(net 209)
	)
	(segment
		(start 153.05 93.1)
		(end 153.05 92.7)
		(width 0.15)
		(layer "In3.Cu")
		(net 209)
	)
	(segment
		(start 151.4 94.75)
		(end 153.05 93.1)
		(width 0.15)
		(layer "In3.Cu")
		(net 209)
	)
	(segment
		(start 150.384586 94.75)
		(end 151.4 94.75)
		(width 0.15)
		(layer "In3.Cu")
		(net 209)
	)
	(via
		(at 140.375 83.2)
		(size 0.4)
		(drill 0.15)
		(layers "F.Cu" "B.Cu")
		(net 210)
	)
	(segment
		(start 147.661343 84.491355)
		(end 147.661344 84.491354)
		(width 0.1)
		(layer "B.Cu")
		(net 210)
	)
	(segment
		(start 149.55 97.144975)
		(end 149.65 97.244975)
		(width 0.1)
		(layer "B.Cu")
		(net 210)
	)
	(segment
		(start 149.322477 87.67503)
		(end 149.322476 87.675029)
		(width 0.1)
		(layer "B.Cu")
		(net 210)
	)
	(segment
		(start 142.668507 84.625179)
		(end 141.700977 84.625179)
		(width 0.1016)
		(layer "B.Cu")
		(net 210)
	)
	(segment
		(start 148.43916 88.029148)
		(end 148.439159 88.029149)
		(width 0.1)
		(layer "B.Cu")
		(net 210)
	)
	(segment
		(start 146.778028 84.316277)
		(end 147.132146 83.962156)
		(width 0.1)
		(layer "B.Cu")
		(net 210)
	)
	(segment
		(start 149.55 96.798897)
		(end 149.55 97.144975)
		(width 0.1)
		(layer "B.Cu")
		(net 210)
	)
	(segment
		(start 149.004844 85.834856)
		(end 149.004845 85.834855)
		(width 0.1)
		(layer "B.Cu")
		(net 210)
	)
	(segment
		(start 141.434088 84.625179)
		(end 141.700977 84.625179)
		(width 0.1)
		(layer "B.Cu")
		(net 210)
	)
	(segment
		(start 149.7992 88.151754)
		(end 149.7992 89.3108)
		(width 0.1)
		(layer "B.Cu")
		(net 210)
	)
	(segment
		(start 140.725 83.55)
		(end 140.725 84.15)
		(width 0.1)
		(layer "B.Cu")
		(net 210)
	)
	(segment
		(start 147.661344 84.491354)
		(end 146.281354 85.871344)
		(width 0.1)
		(layer "B.Cu")
		(net 210)
	)
	(segment
		(start 141.208909 84.4)
		(end 141.434088 84.625179)
		(width 0.1)
		(layer "B.Cu")
		(net 210)
	)
	(segment
		(start 140.375 83.2)
		(end 140.725 83.55)
		(width 0.1)
		(layer "B.Cu")
		(net 210)
	)
	(segment
		(start 149.322476 87.675029)
		(end 149.7992 88.151754)
		(width 0.1)
		(layer "B.Cu")
		(net 210)
	)
	(segment
		(start 149.004845 85.834855)
		(end 147.624855 87.214845)
		(width 0.1)
		(layer "B.Cu")
		(net 210)
	)
	(segment
		(start 150.4 89.9116)
		(end 150.6008 89.9116)
		(width 0.1)
		(layer "B.Cu")
		(net 210)
	)
	(segment
		(start 149.1992 90.71)
		(end 150.6008 90.71)
		(width 0.1)
		(layer "B.Cu")
		(net 210)
	)
	(segment
		(start 148.439159 88.029149)
		(end 148.793278 87.675029)
		(width 0.1)
		(layer "B.Cu")
		(net 210)
	)
	(segment
		(start 145.899046 84.2516)
		(end 145.963722 84.316275)
		(width 0.1)
		(layer "B.Cu")
		(net 210)
	)
	(segment
		(start 149.7992 92.3108)
		(end 149.7992 96.549697)
		(width 0.1)
		(layer "B.Cu")
		(net 210)
	)
	(segment
		(start 140.975 84.4)
		(end 141.208909 84.4)
		(width 0.1)
		(layer "B.Cu")
		(net 210)
	)
	(segment
		(start 147.095658 86.685648)
		(end 148.475647 85.305657)
		(width 0.1)
		(layer "B.Cu")
		(net 210)
	)
	(segment
		(start 149.65 97.244975)
		(end 149.65 98.625)
		(width 0.1)
		(layer "B.Cu")
		(net 210)
	)
	(segment
		(start 149.1992 91.9116)
		(end 149.4 91.9116)
		(width 0.1)
		(layer "B.Cu")
		(net 210)
	)
	(segment
		(start 143.042086 84.2516)
		(end 142.668507 84.625179)
		(width 0.1016)
		(layer "B.Cu")
		(net 210)
	)
	(segment
		(start 149.7992 96.549697)
		(end 149.55 96.798897)
		(width 0.1)
		(layer "B.Cu")
		(net 210)
	)
	(segment
		(start 147.095659 86.685647)
		(end 147.095658 86.685648)
		(width 0.1)
		(layer "B.Cu")
		(net 210)
	)
	(segment
		(start 143.042086 84.2516)
		(end 145.899046 84.2516)
		(width 0.1)
		(layer "B.Cu")
		(net 210)
	)
	(segment
		(start 140.725 84.15)
		(end 140.975 84.4)
		(width 0.1)
		(layer "B.Cu")
		(net 210)
	)
	(segment
		(start 147.661345 83.962157)
		(end 147.661344 83.962156)
		(width 0.1)
		(layer "B.Cu")
		(net 210)
	)
	(arc
		(start 147.661344 83.962156)
		(mid 147.770944 84.226756)
		(end 147.661343 84.491355)
		(width 0.1)
		(layer "B.Cu")
		(net 210)
	)
	(arc
		(start 149.004845 85.305657)
		(mid 149.114445 85.570257)
		(end 149.004844 85.834856)
		(width 0.1)
		(layer "B.Cu")
		(net 210)
	)
	(arc
		(start 146.281354 86.685648)
		(mid 146.688507 86.854296)
		(end 147.095659 86.685647)
		(width 0.1)
		(layer "B.Cu")
		(net 210)
	)
	(arc
		(start 147.624855 88.029149)
		(mid 148.032008 88.197797)
		(end 148.43916 88.029148)
		(width 0.1)
		(layer "B.Cu")
		(net 210)
	)
	(arc
		(start 150.6008 89.9116)
		(mid 150.883077 90.028523)
		(end 151 90.3108)
		(width 0.1)
		(layer "B.Cu")
		(net 210)
	)
	(arc
		(start 147.132146 83.962156)
		(mid 147.396746 83.852556)
		(end 147.661345 83.962157)
		(width 0.1)
		(layer "B.Cu")
		(net 210)
	)
	(arc
		(start 151 90.3108)
		(mid 150.883077 90.593077)
		(end 150.6008 90.71)
		(width 0.1)
		(layer "B.Cu")
		(net 210)
	)
	(arc
		(start 145.963722 84.316275)
		(mid 146.370876 84.484925)
		(end 146.778028 84.316277)
		(width 0.1)
		(layer "B.Cu")
		(net 210)
	)
	(arc
		(start 148.793278 87.675029)
		(mid 149.057878 87.565429)
		(end 149.322477 87.67503)
		(width 0.1)
		(layer "B.Cu")
		(net 210)
	)
	(arc
		(start 146.281354 85.871344)
		(mid 146.112706 86.278496)
		(end 146.281354 86.685648)
		(width 0.1)
		(layer "B.Cu")
		(net 210)
	)
	(arc
		(start 148.475647 85.305657)
		(mid 148.740247 85.196058)
		(end 149.004845 85.305657)
		(width 0.1)
		(layer "B.Cu")
		(net 210)
	)
	(arc
		(start 149.4 91.9116)
		(mid 149.682277 92.028523)
		(end 149.7992 92.3108)
		(width 0.1)
		(layer "B.Cu")
		(net 210)
	)
	(arc
		(start 148.5984 91.3108)
		(mid 148.77437 91.73563)
		(end 149.1992 91.9116)
		(width 0.1)
		(layer "B.Cu")
		(net 210)
	)
	(arc
		(start 149.1992 90.71)
		(mid 148.77437 90.88597)
		(end 148.5984 91.3108)
		(width 0.1)
		(layer "B.Cu")
		(net 210)
	)
	(arc
		(start 147.624855 87.214845)
		(mid 147.456207 87.621997)
		(end 147.624855 88.029149)
		(width 0.1)
		(layer "B.Cu")
		(net 210)
	)
	(arc
		(start 149.7992 89.3108)
		(mid 149.97517 89.73563)
		(end 150.4 89.9116)
		(width 0.1)
		(layer "B.Cu")
		(net 210)
	)
	(via
		(at 141.075 84)
		(size 0.4)
		(drill 0.15)
		(layers "F.Cu" "B.Cu")
		(net 211)
	)
	(segment
		(start 147.8039 83.819605)
		(end 147.803899 83.819604)
		(width 0.1)
		(layer "B.Cu")
		(net 211)
	)
	(segment
		(start 147.803899 84.633908)
		(end 146.423907 86.013897)
		(width 0.1)
		(layer "B.Cu")
		(net 211)
	)
	(segment
		(start 142.584335 84.421979)
		(end 141.700977 84.421979)
		(width 0.1016)
		(layer "B.Cu")
		(net 211)
	)
	(segment
		(start 149.46503 87.532477)
		(end 149.465029 87.532476)
		(width 0.1)
		(layer "B.Cu")
		(net 211)
	)
	(segment
		(start 142.957914 84.0484)
		(end 143.0416 84.0484)
		(width 0.1)
		(layer "B.Cu")
		(net 211)
	)
	(segment
		(start 150.25 97.144975)
		(end 150.15 97.244975)
		(width 0.1)
		(layer "B.Cu")
		(net 211)
	)
	(segment
		(start 150.6008 90.9116)
		(end 149.1992 90.9116)
		(width 0.1)
		(layer "B.Cu")
		(net 211)
	)
	(segment
		(start 148.296606 87.886596)
		(end 148.650725 87.532476)
		(width 0.1)
		(layer "B.Cu")
		(net 211)
	)
	(segment
		(start 141.091753 84)
		(end 141.513732 84.421979)
		(width 0.1)
		(layer "B.Cu")
		(net 211)
	)
	(segment
		(start 144.2916 84.0484)
		(end 144.3416 84.0484)
		(width 0.1)
		(layer "B.Cu")
		(net 211)
	)
	(segment
		(start 141.513732 84.421979)
		(end 141.700977 84.421979)
		(width 0.1)
		(layer "B.Cu")
		(net 211)
	)
	(segment
		(start 145.980954 84.0484)
		(end 146.106275 84.173722)
		(width 0.1)
		(layer "B.Cu")
		(net 211)
	)
	(segment
		(start 143.2166 83.8734)
		(end 143.2166 83.6734)
		(width 0.1)
		(layer "B.Cu")
		(net 211)
	)
	(segment
		(start 150.0008 88.068246)
		(end 150.0008 89.3108)
		(width 0.1)
		(layer "B.Cu")
		(net 211)
	)
	(segment
		(start 150.0008 92.3108)
		(end 150.0008 96.549697)
		(width 0.1)
		(layer "B.Cu")
		(net 211)
	)
	(segment
		(start 146.953106 86.543094)
		(end 146.953105 86.543095)
		(width 0.1)
		(layer "B.Cu")
		(net 211)
	)
	(segment
		(start 150.25 96.798897)
		(end 150.25 97.144975)
		(width 0.1)
		(layer "B.Cu")
		(net 211)
	)
	(segment
		(start 143.5666 83.6734)
		(end 143.5666 83.8734)
		(width 0.1)
		(layer "B.Cu")
		(net 211)
	)
	(segment
		(start 149.147398 85.977408)
		(end 147.767408 87.357398)
		(width 0.1)
		(layer "B.Cu")
		(net 211)
	)
	(segment
		(start 149.147397 85.977409)
		(end 149.147398 85.977408)
		(width 0.1)
		(layer "B.Cu")
		(net 211)
	)
	(segment
		(start 142.957914 84.0484)
		(end 142.584335 84.421979)
		(width 0.1016)
		(layer "B.Cu")
		(net 211)
	)
	(segment
		(start 141.075 84)
		(end 141.091753 84)
		(width 0.1)
		(layer "B.Cu")
		(net 211)
	)
	(segment
		(start 148.296607 87.886595)
		(end 148.296606 87.886596)
		(width 0.1)
		(layer "B.Cu")
		(net 211)
	)
	(segment
		(start 144.3416 84.0484)
		(end 145.980954 84.0484)
		(width 0.1)
		(layer "B.Cu")
		(net 211)
	)
	(segment
		(start 150.4 89.71)
		(end 150.6008 89.71)
		(width 0.1)
		(layer "B.Cu")
		(net 211)
	)
	(segment
		(start 147.803898 84.633909)
		(end 147.803899 84.633908)
		(width 0.1)
		(layer "B.Cu")
		(net 211)
	)
	(segment
		(start 149.1992 91.71)
		(end 149.4 91.71)
		(width 0.1)
		(layer "B.Cu")
		(net 211)
	)
	(segment
		(start 146.953105 86.543095)
		(end 148.333094 85.163104)
		(width 0.1)
		(layer "B.Cu")
		(net 211)
	)
	(segment
		(start 143.7416 84.0484)
		(end 143.7916 84.0484)
		(width 0.1)
		(layer "B.Cu")
		(net 211)
	)
	(segment
		(start 150.0008 96.549697)
		(end 150.25 96.798897)
		(width 0.1)
		(layer "B.Cu")
		(net 211)
	)
	(segment
		(start 149.465029 87.532476)
		(end 150.0008 88.068246)
		(width 0.1)
		(layer "B.Cu")
		(net 211)
	)
	(segment
		(start 150.15 97.244975)
		(end 150.15 98.625)
		(width 0.1)
		(layer "B.Cu")
		(net 211)
	)
	(segment
		(start 146.635475 84.173724)
		(end 146.635475 84.173723)
		(width 0.1)
		(layer "B.Cu")
		(net 211)
	)
	(segment
		(start 146.635475 84.173723)
		(end 146.989595 83.819604)
		(width 0.1)
		(layer "B.Cu")
		(net 211)
	)
	(arc
		(start 149.4 91.71)
		(mid 149.82483 91.88597)
		(end 150.0008 92.3108)
		(width 0.1)
		(layer "B.Cu")
		(net 211)
	)
	(arc
		(start 143.3916 83.4984)
		(mid 143.515344 83.549656)
		(end 143.5666 83.6734)
		(width 0.1)
		(layer "B.Cu")
		(net 211)
	)
	(arc
		(start 143.5666 83.8734)
		(mid 143.617856 83.997144)
		(end 143.7416 84.0484)
		(width 0.1)
		(layer "B.Cu")
		(net 211)
	)
	(arc
		(start 143.9166 83.9234)
		(mid 143.953212 83.835012)
		(end 144.0416 83.7984)
		(width 0.1)
		(layer "B.Cu")
		(net 211)
	)
	(arc
		(start 143.0416 84.0484)
		(mid 143.165344 83.997144)
		(end 143.2166 83.8734)
		(width 0.1)
		(layer "B.Cu")
		(net 211)
	)
	(arc
		(start 149.147398 85.163104)
		(mid 149.316047 85.570258)
		(end 149.147397 85.977409)
		(width 0.1)
		(layer "B.Cu")
		(net 211)
	)
	(arc
		(start 150.0008 89.3108)
		(mid 150.117723 89.593077)
		(end 150.4 89.71)
		(width 0.1)
		(layer "B.Cu")
		(net 211)
	)
	(arc
		(start 146.423907 86.013897)
		(mid 146.314307 86.278496)
		(end 146.423907 86.543095)
		(width 0.1)
		(layer "B.Cu")
		(net 211)
	)
	(arc
		(start 147.803899 83.819604)
		(mid 147.972546 84.226756)
		(end 147.803898 84.633909)
		(width 0.1)
		(layer "B.Cu")
		(net 211)
	)
	(arc
		(start 144.0416 83.7984)
		(mid 144.129988 83.835012)
		(end 144.1666 83.9234)
		(width 0.1)
		(layer "B.Cu")
		(net 211)
	)
	(arc
		(start 148.8 91.3108)
		(mid 148.916923 91.593077)
		(end 149.1992 91.71)
		(width 0.1)
		(layer "B.Cu")
		(net 211)
	)
	(arc
		(start 144.1666 83.9234)
		(mid 144.203212 84.011788)
		(end 144.2916 84.0484)
		(width 0.1)
		(layer "B.Cu")
		(net 211)
	)
	(arc
		(start 146.989595 83.819604)
		(mid 147.396747 83.650955)
		(end 147.8039 83.819605)
		(width 0.1)
		(layer "B.Cu")
		(net 211)
	)
	(arc
		(start 148.650725 87.532476)
		(mid 149.057878 87.363828)
		(end 149.46503 87.532477)
		(width 0.1)
		(layer "B.Cu")
		(net 211)
	)
	(arc
		(start 148.333094 85.163104)
		(mid 148.740246 84.994456)
		(end 149.147398 85.163104)
		(width 0.1)
		(layer "B.Cu")
		(net 211)
	)
	(arc
		(start 147.767408 87.357398)
		(mid 147.657808 87.621997)
		(end 147.767408 87.886596)
		(width 0.1)
		(layer "B.Cu")
		(net 211)
	)
	(arc
		(start 150.6008 89.71)
		(mid 151.02563 89.88597)
		(end 151.2016 90.3108)
		(width 0.1)
		(layer "B.Cu")
		(net 211)
	)
	(arc
		(start 143.2166 83.6734)
		(mid 143.267856 83.549656)
		(end 143.3916 83.4984)
		(width 0.1)
		(layer "B.Cu")
		(net 211)
	)
	(arc
		(start 149.1992 90.9116)
		(mid 148.916923 91.028523)
		(end 148.8 91.3108)
		(width 0.1)
		(layer "B.Cu")
		(net 211)
	)
	(arc
		(start 146.106275 84.173722)
		(mid 146.370875 84.283323)
		(end 146.635475 84.173724)
		(width 0.1)
		(layer "B.Cu")
		(net 211)
	)
	(arc
		(start 143.7916 84.0484)
		(mid 143.879988 84.011788)
		(end 143.9166 83.9234)
		(width 0.1)
		(layer "B.Cu")
		(net 211)
	)
	(arc
		(start 151.2016 90.3108)
		(mid 151.02563 90.73563)
		(end 150.6008 90.9116)
		(width 0.1)
		(layer "B.Cu")
		(net 211)
	)
	(arc
		(start 147.767408 87.886596)
		(mid 148.032008 87.996196)
		(end 148.296607 87.886595)
		(width 0.1)
		(layer "B.Cu")
		(net 211)
	)
	(arc
		(start 146.423907 86.543095)
		(mid 146.688507 86.652695)
		(end 146.953106 86.543094)
		(width 0.1)
		(layer "B.Cu")
		(net 211)
	)
	(segment
		(start 153.041422 76.100001)
		(end 153.041421 76.099999)
		(width 0.15)
		(layer "F.Cu")
		(net 212)
	)
	(segment
		(start 153.324264 76.665685)
		(end 153.465685 76.524263)
		(width 0.15)
		(layer "F.Cu")
		(net 212)
	)
	(segment
		(start 155.021316 78.362737)
		(end 155.162739 78.221318)
		(width 0.15)
		(layer "F.Cu")
		(net 212)
	)
	(segment
		(start 156.152684 79.635527)
		(end 155.869842 79.352685)
		(width 0.15)
		(layer "F.Cu")
		(net 212)
	)
	(segment
		(start 153.889947 76.948526)
		(end 153.748528 77.089949)
		(width 0.15)
		(layer "F.Cu")
		(net 212)
	)
	(segment
		(start 155.162739 78.221318)
		(end 155.16274 78.221317)
		(width 0.15)
		(layer "F.Cu")
		(net 212)
	)
	(segment
		(start 156.011265 78.928422)
		(end 155.728423 78.64558)
		(width 0.15)
		(layer "F.Cu")
		(net 212)
	)
	(segment
		(start 154.17279 77.514211)
		(end 154.314213 77.372792)
		(width 0.15)
		(layer "F.Cu")
		(net 212)
	)
	(segment
		(start 155.162739 78.079896)
		(end 154.879897 77.797054)
		(width 0.15)
		(layer "F.Cu")
		(net 212)
	)
	(segment
		(start 164.8 88)
		(end 157.29142 80.491421)
		(width 0.15)
		(layer "F.Cu")
		(net 212)
	)
	(segment
		(start 157.29142 80.491421)
		(end 157.274262 80.491421)
		(width 0.15)
		(layer "F.Cu")
		(net 212)
	)
	(segment
		(start 164.45 93.315)
		(end 164.495 93.315)
		(width 0.15)
		(layer "F.Cu")
		(net 212)
	)
	(segment
		(start 155.586999 78.645578)
		(end 155.44558 78.787001)
		(width 0.15)
		(layer "F.Cu")
		(net 212)
	)
	(segment
		(start 164.9755 92.8345)
		(end 164.9755 92.1)
		(width 0.15)
		(layer "F.Cu")
		(net 212)
	)
	(segment
		(start 164.495 93.315)
		(end 164.9755 92.8345)
		(width 0.15)
		(layer "F.Cu")
		(net 212)
	)
	(segment
		(start 152.4 75.6)
		(end 143.45 75.6)
		(width 0.15)
		(layer "F.Cu")
		(net 212)
	)
	(segment
		(start 154.597054 77.938475)
		(end 154.597053 77.938476)
		(width 0.15)
		(layer "F.Cu")
		(net 212)
	)
	(segment
		(start 156.435525 79.494104)
		(end 156.294106 79.635527)
		(width 0.15)
		(layer "F.Cu")
		(net 212)
	)
	(segment
		(start 164.9755 92.1)
		(end 164.8 91.9245)
		(width 0.15)
		(layer "F.Cu")
		(net 212)
	)
	(segment
		(start 157.132842 80.491421)
		(end 157.132842 80.491422)
		(width 0.15)
		(layer "F.Cu")
		(net 212)
	)
	(segment
		(start 159.9 96.550497)
		(end 159.9 98.625)
		(width 0.15)
		(layer "F.Cu")
		(net 212)
	)
	(segment
		(start 154.314213 77.372792)
		(end 154.314214 77.372791)
		(width 0.15)
		(layer "F.Cu")
		(net 212)
	)
	(segment
		(start 156.991421 80.491421)
		(end 156.708579 80.208579)
		(width 0.15)
		(layer "F.Cu")
		(net 212)
	)
	(segment
		(start 156.859791 79.776948)
		(end 156.576949 79.494106)
		(width 0.15)
		(layer "F.Cu")
		(net 212)
	)
	(segment
		(start 156.294106 79.635527)
		(end 156.294105 79.635528)
		(width 0.15)
		(layer "F.Cu")
		(net 212)
	)
	(segment
		(start 154.738473 77.797052)
		(end 154.597054 77.938475)
		(width 0.15)
		(layer "F.Cu")
		(net 212)
	)
	(segment
		(start 141.775 76.8)
		(end 141.7695 76.8)
		(width 0.15)
		(layer "F.Cu")
		(net 212)
	)
	(segment
		(start 154.314213 77.23137)
		(end 154.031371 76.948528)
		(width 0.15)
		(layer "F.Cu")
		(net 212)
	)
	(segment
		(start 152.9 76.1)
		(end 152.4 75.6)
		(width 0.15)
		(layer "F.Cu")
		(net 212)
	)
	(segment
		(start 155.304158 78.787001)
		(end 155.021316 78.504159)
		(width 0.15)
		(layer "F.Cu")
		(net 212)
	)
	(segment
		(start 153.182842 76.1)
		(end 153.182842 76.100001)
		(width 0.15)
		(layer "F.Cu")
		(net 212)
	)
	(segment
		(start 153.465684 76.382842)
		(end 153.182842 76.1)
		(width 0.15)
		(layer "F.Cu")
		(net 212)
	)
	(segment
		(start 153.748528 77.089949)
		(end 153.748527 77.08995)
		(width 0.15)
		(layer "F.Cu")
		(net 212)
	)
	(segment
		(start 156.011265 79.069844)
		(end 156.011266 79.069843)
		(width 0.15)
		(layer "F.Cu")
		(net 212)
	)
	(segment
		(start 153.607106 77.089949)
		(end 153.324264 76.807107)
		(width 0.15)
		(layer "F.Cu")
		(net 212)
	)
	(segment
		(start 164.8 91.9245)
		(end 164.8 88)
		(width 0.15)
		(layer "F.Cu")
		(net 212)
	)
	(segment
		(start 155.869842 79.211263)
		(end 156.011265 79.069844)
		(width 0.15)
		(layer "F.Cu")
		(net 212)
	)
	(segment
		(start 156.70858 80.067158)
		(end 156.711003 80.067158)
		(width 0.15)
		(layer "F.Cu")
		(net 212)
	)
	(segment
		(start 155.44558 78.787001)
		(end 155.445579 78.787002)
		(width 0.15)
		(layer "F.Cu")
		(net 212)
	)
	(segment
		(start 154.455632 77.938475)
		(end 154.17279 77.655633)
		(width 0.15)
		(layer "F.Cu")
		(net 212)
	)
	(segment
		(start 156.708579 80.208579)
		(end 156.70858 80.208578)
		(width 0.15)
		(layer "F.Cu")
		(net 212)
	)
	(segment
		(start 156.711003 80.067158)
		(end 156.859792 79.918369)
		(width 0.15)
		(layer "F.Cu")
		(net 212)
	)
	(segment
		(start 159.799503 96.45)
		(end 159.9 96.550497)
		(width 0.15)
		(layer "F.Cu")
		(net 212)
	)
	(via
		(at 141.7695 76.8)
		(size 0.4)
		(drill 0.2)
		(layers "F.Cu" "B.Cu")
		(net 212)
	)
	(via
		(at 164.9755 92.1)
		(size 0.4)
		(drill 0.2)
		(layers "F.Cu" "B.Cu")
		(net 212)
	)
	(via
		(at 143.45 75.6)
		(size 0.4)
		(drill 0.2)
		(layers "F.Cu" "B.Cu")
		(net 212)
	)
	(via
		(at 159.799503 96.45)
		(size 0.4)
		(drill 0.2)
		(layers "F.Cu" "B.Cu")
		(net 212)
	)
	(arc
		(start 153.182842 76.100001)
		(mid 153.112131 76.070711)
		(end 153.041422 76.100001)
		(width 0.15)
		(layer "F.Cu")
		(net 212)
	)
	(arc
		(start 154.879897 77.797054)
		(mid 154.809186 77.767765)
		(end 154.738473 77.797052)
		(width 0.15)
		(layer "F.Cu")
		(net 212)
	)
	(arc
		(start 154.031371 76.948528)
		(mid 153.96066 76.919239)
		(end 153.889947 76.948526)
		(width 0.15)
		(layer "F.Cu")
		(net 212)
	)
	(arc
		(start 153.465685 76.524263)
		(mid 153.494974 76.453552)
		(end 153.465684 76.382842)
		(width 0.15)
		(layer "F.Cu")
		(net 212)
	)
	(arc
		(start 153.324264 76.807107)
		(mid 153.294975 76.736396)
		(end 153.324264 76.665685)
		(width 0.15)
		(layer "F.Cu")
		(net 212)
	)
	(arc
		(start 155.728423 78.64558)
		(mid 155.657712 78.616291)
		(end 155.586999 78.645578)
		(width 0.15)
		(layer "F.Cu")
		(net 212)
	)
	(arc
		(start 155.869842 79.352685)
		(mid 155.840553 79.281974)
		(end 155.869842 79.211263)
		(width 0.15)
		(layer "F.Cu")
		(net 212)
	)
	(arc
		(start 156.859792 79.918369)
		(mid 156.889081 79.847658)
		(end 156.859791 79.776948)
		(width 0.15)
		(layer "F.Cu")
		(net 212)
	)
	(arc
		(start 153.748527 77.08995)
		(mid 153.677816 77.119239)
		(end 153.607106 77.089949)
		(width 0.15)
		(layer "F.Cu")
		(net 212)
	)
	(arc
		(start 155.021316 78.504159)
		(mid 154.992027 78.433448)
		(end 155.021316 78.362737)
		(width 0.15)
		(layer "F.Cu")
		(net 212)
	)
	(arc
		(start 156.70858 80.208578)
		(mid 156.679291 80.137868)
		(end 156.70858 80.067158)
		(width 0.15)
		(layer "F.Cu")
		(net 212)
	)
	(arc
		(start 156.294105 79.635528)
		(mid 156.223394 79.664817)
		(end 156.152684 79.635527)
		(width 0.15)
		(layer "F.Cu")
		(net 212)
	)
	(arc
		(start 156.011266 79.069843)
		(mid 156.040555 78.999132)
		(end 156.011265 78.928422)
		(width 0.15)
		(layer "F.Cu")
		(net 212)
	)
	(arc
		(start 154.314214 77.372791)
		(mid 154.343503 77.30208)
		(end 154.314213 77.23137)
		(width 0.15)
		(layer "F.Cu")
		(net 212)
	)
	(arc
		(start 155.16274 78.221317)
		(mid 155.192029 78.150606)
		(end 155.162739 78.079896)
		(width 0.15)
		(layer "F.Cu")
		(net 212)
	)
	(arc
		(start 154.17279 77.655633)
		(mid 154.143501 77.584922)
		(end 154.17279 77.514211)
		(width 0.15)
		(layer "F.Cu")
		(net 212)
	)
	(arc
		(start 157.274262 80.491421)
		(mid 157.203552 80.462132)
		(end 157.132842 80.491421)
		(width 0.15)
		(layer "F.Cu")
		(net 212)
	)
	(arc
		(start 153.041421 76.099999)
		(mid 152.970711 76.129289)
		(end 152.9 76.1)
		(width 0.15)
		(layer "F.Cu")
		(net 212)
	)
	(arc
		(start 154.597053 77.938476)
		(mid 154.526342 77.967765)
		(end 154.455632 77.938475)
		(width 0.15)
		(layer "F.Cu")
		(net 212)
	)
	(arc
		(start 155.445579 78.787002)
		(mid 155.374868 78.816291)
		(end 155.304158 78.787001)
		(width 0.15)
		(layer "F.Cu")
		(net 212)
	)
	(arc
		(start 156.576949 79.494106)
		(mid 156.506238 79.464817)
		(end 156.435525 79.494104)
		(width 0.15)
		(layer "F.Cu")
		(net 212)
	)
	(arc
		(start 157.132842 80.491422)
		(mid 157.062131 80.520711)
		(end 156.991421 80.491421)
		(width 0.15)
		(layer "F.Cu")
		(net 212)
	)
	(segment
		(start 165.1255 91.95)
		(end 165.965 91.95)
		(width 0.15)
		(layer "B.Cu")
		(net 212)
	)
	(segment
		(start 164.9755 92.1)
		(end 165.1255 91.95)
		(width 0.15)
		(layer "B.Cu")
		(net 212)
	)
	(segment
		(start 161.55 95.5)
		(end 160.749503 95.5)
		(width 0.15)
		(layer "In3.Cu")
		(net 212)
	)
	(segment
		(start 162.45 94.6)
		(end 161.55 95.5)
		(width 0.15)
		(layer "In3.Cu")
		(net 212)
	)
	(segment
		(start 164.9755 92.8245)
		(end 163.2 94.6)
		(width 0.15)
		(layer "In3.Cu")
		(net 212)
	)
	(segment
		(start 143.45 75.6)
		(end 142.25 76.8)
		(width 0.15)
		(layer "In3.Cu")
		(net 212)
	)
	(segment
		(start 142.25 76.8)
		(end 141.7695 76.8)
		(width 0.15)
		(layer "In3.Cu")
		(net 212)
	)
	(segment
		(start 163.2 94.6)
		(end 162.45 94.6)
		(width 0.15)
		(layer "In3.Cu")
		(net 212)
	)
	(segment
		(start 164.9755 92.1)
		(end 164.9755 92.8245)
		(width 0.15)
		(layer "In3.Cu")
		(net 212)
	)
	(segment
		(start 160.749503 95.5)
		(end 159.799503 96.45)
		(width 0.15)
		(layer "In3.Cu")
		(net 212)
	)
	(segment
		(start 145.9 82.9)
		(end 145.9 82.8)
		(width 0.15)
		(layer "F.Cu")
		(net 213)
	)
	(segment
		(start 152.4 82.8)
		(end 155.95 86.35)
		(width 0.15)
		(layer "F.Cu")
		(net 213)
	)
	(segment
		(start 145.3 82.7)
		(end 145.3 82.8)
		(width 0.15)
		(layer "F.Cu")
		(net 213)
	)
	(segment
		(start 144.2 83)
		(end 144.6 83)
		(width 0.15)
		(layer "F.Cu")
		(net 213)
	)
	(segment
		(start 145.4 83)
		(end 145.8 83)
		(width 0.15)
		(layer "F.Cu")
		(net 213)
	)
	(segment
		(start 147.8 82.8)
		(end 152.4 82.8)
		(width 0.15)
		(layer "F.Cu")
		(net 213)
	)
	(segment
		(start 155.95 93.35)
		(end 155.95 92.7)
		(width 0.15)
		(layer "F.Cu")
		(net 213)
	)
	(segment
		(start 141.075 82.4)
		(end 141.175 82.4)
		(width 0.09)
		(layer "F.Cu")
		(net 213)
	)
	(segment
		(start 147.1 82.8)
		(end 147.1 82.7)
		(width 0.15)
		(layer "F.Cu")
		(net 213)
	)
	(segment
		(start 144.7 82.8)
		(end 144.7 82.7)
		(width 0.15)
		(layer "F.Cu")
		(net 213)
	)
	(segment
		(start 143.6 82.6)
		(end 144 82.6)
		(width 0.15)
		(layer "F.Cu")
		(net 213)
	)
	(segment
		(start 144.1 82.8)
		(end 144.1 82.9)
		(width 0.15)
		(layer "F.Cu")
		(net 213)
	)
	(segment
		(start 146.6 83)
		(end 147 83)
		(width 0.15)
		(layer "F.Cu")
		(net 213)
	)
	(segment
		(start 144.1 82.7)
		(end 144.1 82.8)
		(width 0.15)
		(layer "F.Cu")
		(net 213)
	)
	(segment
		(start 145.3 82.8)
		(end 145.3 82.9)
		(width 0.15)
		(layer "F.Cu")
		(net 213)
	)
	(segment
		(start 147.2 82.6)
		(end 147.6 82.6)
		(width 0.15)
		(layer "F.Cu")
		(net 213)
	)
	(segment
		(start 143.5 82.9)
		(end 143.5 82.8)
		(width 0.15)
		(layer "F.Cu")
		(net 213)
	)
	(segment
		(start 147.1 82.9)
		(end 147.1 82.8)
		(width 0.15)
		(layer "F.Cu")
		(net 213)
	)
	(segment
		(start 155.95 86.35)
		(end 155.95 92.7)
		(width 0.15)
		(layer "F.Cu")
		(net 213)
	)
	(segment
		(start 146.5 82.8)
		(end 146.5 82.9)
		(width 0.15)
		(layer "F.Cu")
		(net 213)
	)
	(segment
		(start 141.575 82.8)
		(end 142.2 82.8)
		(width 0.09)
		(layer "F.Cu")
		(net 213)
	)
	(segment
		(start 143.5 82.8)
		(end 143.5 82.7)
		(width 0.15)
		(layer "F.Cu")
		(net 213)
	)
	(segment
		(start 151.4 98.625)
		(end 151.4 96.674835)
		(width 0.15)
		(layer "F.Cu")
		(net 213)
	)
	(segment
		(start 144.7 82.9)
		(end 144.7 82.8)
		(width 0.15)
		(layer "F.Cu")
		(net 213)
	)
	(segment
		(start 145.9 82.8)
		(end 145.9 82.7)
		(width 0.15)
		(layer "F.Cu")
		(net 213)
	)
	(segment
		(start 141.175 82.4)
		(end 141.575 82.8)
		(width 0.09)
		(layer "F.Cu")
		(net 213)
	)
	(segment
		(start 146 82.6)
		(end 146.4 82.6)
		(width 0.15)
		(layer "F.Cu")
		(net 213)
	)
	(segment
		(start 143 83)
		(end 143.4 83)
		(width 0.15)
		(layer "F.Cu")
		(net 213)
	)
	(segment
		(start 142.2 82.8)
		(end 142.8 82.8)
		(width 0.15)
		(layer "F.Cu")
		(net 213)
	)
	(segment
		(start 146.5 82.7)
		(end 146.5 82.8)
		(width 0.15)
		(layer "F.Cu")
		(net 213)
	)
	(segment
		(start 144.8 82.6)
		(end 145.2 82.6)
		(width 0.15)
		(layer "F.Cu")
		(net 213)
	)
	(segment
		(start 151.4 96.674835)
		(end 151.541289 96.533546)
		(width 0.15)
		(layer "F.Cu")
		(net 213)
	)
	(via
		(at 155.95 92.7)
		(size 0.4)
		(drill 0.2)
		(layers "F.Cu" "B.Cu")
		(net 213)
	)
	(via
		(at 151.541289 96.533546)
		(size 0.4)
		(drill 0.2)
		(layers "F.Cu" "B.Cu")
		(net 213)
	)
	(arc
		(start 143.5 82.7)
		(mid 143.529289 82.629289)
		(end 143.6 82.6)
		(width 0.15)
		(layer "F.Cu")
		(net 213)
	)
	(arc
		(start 145.2 82.6)
		(mid 145.270711 82.629289)
		(end 145.3 82.7)
		(width 0.15)
		(layer "F.Cu")
		(net 213)
	)
	(arc
		(start 147 83)
		(mid 147.070711 82.970711)
		(end 147.1 82.9)
		(width 0.15)
		(layer "F.Cu")
		(net 213)
	)
	(arc
		(start 146.4 82.6)
		(mid 146.470711 82.629289)
		(end 146.5 82.7)
		(width 0.15)
		(layer "F.Cu")
		(net 213)
	)
	(arc
		(start 146.5 82.9)
		(mid 146.529289 82.970711)
		(end 146.6 83)
		(width 0.15)
		(layer "F.Cu")
		(net 213)
	)
	(arc
		(start 145.8 83)
		(mid 145.870711 82.970711)
		(end 145.9 82.9)
		(width 0.15)
		(layer "F.Cu")
		(net 213)
	)
	(arc
		(start 147.6 82.6)
		(mid 147.670711 82.629289)
		(end 147.7 82.7)
		(width 0.15)
		(layer "F.Cu")
		(net 213)
	)
	(arc
		(start 143.4 83)
		(mid 143.470711 82.970711)
		(end 143.5 82.9)
		(width 0.15)
		(layer "F.Cu")
		(net 213)
	)
	(arc
		(start 145.3 82.9)
		(mid 145.329289 82.970711)
		(end 145.4 83)
		(width 0.15)
		(layer "F.Cu")
		(net 213)
	)
	(arc
		(start 144.6 83)
		(mid 144.670711 82.970711)
		(end 144.7 82.9)
		(width 0.15)
		(layer "F.Cu")
		(net 213)
	)
	(arc
		(start 144 82.6)
		(mid 144.070711 82.629289)
		(end 144.1 82.7)
		(width 0.15)
		(layer "F.Cu")
		(net 213)
	)
	(arc
		(start 144.7 82.7)
		(mid 144.729289 82.629289)
		(end 144.8 82.6)
		(width 0.15)
		(layer "F.Cu")
		(net 213)
	)
	(arc
		(start 144.1 82.9)
		(mid 144.129289 82.970711)
		(end 144.2 83)
		(width 0.15)
		(layer "F.Cu")
		(net 213)
	)
	(arc
		(start 147.1 82.7)
		(mid 147.129289 82.629289)
		(end 147.2 82.6)
		(width 0.15)
		(layer "F.Cu")
		(net 213)
	)
	(arc
		(start 142.9 82.9)
		(mid 142.929289 82.970711)
		(end 143 83)
		(width 0.15)
		(layer "F.Cu")
		(net 213)
	)
	(arc
		(start 142.8 82.8)
		(mid 142.870711 82.829289)
		(end 142.9 82.9)
		(width 0.15)
		(layer "F.Cu")
		(net 213)
	)
	(arc
		(start 145.9 82.7)
		(mid 145.929289 82.629289)
		(end 146 82.6)
		(width 0.15)
		(layer "F.Cu")
		(net 213)
	)
	(arc
		(start 147.7 82.7)
		(mid 147.729289 82.770711)
		(end 147.8 82.8)
		(width 0.15)
		(layer "F.Cu")
		(net 213)
	)
	(segment
		(start 155.95 93.35)
		(end 155.95 92.7)
		(width 0.15)
		(layer "B.Cu")
		(net 213)
	)
	(segment
		(start 151.541289 96.533546)
		(end 151.541289 96.523403)
		(width 0.15)
		(layer "In3.Cu")
		(net 213)
	)
	(segment
		(start 153.7 95.5)
		(end 155.95 93.25)
		(width 0.15)
		(layer "In3.Cu")
		(net 213)
	)
	(segment
		(start 155.95 93.25)
		(end 155.95 92.7)
		(width 0.15)
		(layer "In3.Cu")
		(net 213)
	)
	(segment
		(start 151.541289 96.523403)
		(end 152.564692 95.5)
		(width 0.15)
		(layer "In3.Cu")
		(net 213)
	)
	(segment
		(start 152.564692 95.5)
		(end 153.7 95.5)
		(width 0.15)
		(layer "In3.Cu")
		(net 213)
	)
	(segment
		(start 149.1 82.5)
		(end 149.4 82.5)
		(width 0.15)
		(layer "F.Cu")
		(net 214)
	)
	(segment
		(start 148.5 81.9)
		(end 148.8 81.9)
		(width 0.15)
		(layer "F.Cu")
		(net 214)
	)
	(segment
		(start 156.5875 92.7875)
		(end 156.5875 93.35)
		(width 0.15)
		(layer "F.Cu")
		(net 214)
	)
	(segment
		(start 148.95 82.2)
		(end 148.95 82.35)
		(width 0.15)
		(layer "F.Cu")
		(net 214)
	)
	(segment
		(start 142.425 82.2)
		(end 148.2 82.2)
		(width 0.15)
		(layer "F.Cu")
		(net 214)
	)
	(segment
		(start 156.5 92.7)
		(end 156.5875 92.7875)
		(width 0.15)
		(layer "F.Cu")
		(net 214)
	)
	(segment
		(start 142.2 81.975)
		(end 142.425 82.2)
		(width 0.15)
		(layer "F.Cu")
		(net 214)
	)
	(segment
		(start 142 81.975)
		(end 142.2 81.975)
		(width 0.15)
		(layer "F.Cu")
		(net 214)
	)
	(segment
		(start 140.75 81.975)
		(end 140.375 81.6)
		(width 0.09)
		(layer "F.Cu")
		(net 214)
	)
	(segment
		(start 149.7 82.2)
		(end 152.6 82.2)
		(width 0.15)
		(layer "F.Cu")
		(net 214)
	)
	(segment
		(start 152.6 82.2)
		(end 156.5 86.1)
		(width 0.15)
		(layer "F.Cu")
		(net 214)
	)
	(segment
		(start 142 81.975)
		(end 140.75 81.975)
		(width 0.09)
		(layer "F.Cu")
		(net 214)
	)
	(segment
		(start 156.5 86.1)
		(end 156.5 92.7)
		(width 0.15)
		(layer "F.Cu")
		(net 214)
	)
	(segment
		(start 148.95 82.05)
		(end 148.95 82.2)
		(width 0.15)
		(layer "F.Cu")
		(net 214)
	)
	(via
		(at 156.5 92.7)
		(size 0.4)
		(drill 0.2)
		(layers "F.Cu" "B.Cu")
		(net 214)
	)
	(via
		(at 152.05 96.545023)
		(size 0.4)
		(drill 0.2)
		(layers "F.Cu" "B.Cu")
		(net 214)
	)
	(arc
		(start 148.8 81.9)
		(mid 148.906066 81.943934)
		(end 148.95 82.05)
		(width 0.15)
		(layer "F.Cu")
		(net 214)
	)
	(arc
		(start 148.2 82.2)
		(mid 148.306066 82.156066)
		(end 148.35 82.05)
		(width 0.15)
		(layer "F.Cu")
		(net 214)
	)
	(arc
		(start 148.35 82.05)
		(mid 148.393934 81.943934)
		(end 148.5 81.9)
		(width 0.15)
		(layer "F.Cu")
		(net 214)
	)
	(arc
		(start 149.55 82.35)
		(mid 149.593934 82.243934)
		(end 149.7 82.2)
		(width 0.15)
		(layer "F.Cu")
		(net 214)
	)
	(arc
		(start 148.95 82.35)
		(mid 148.993934 82.456066)
		(end 149.1 82.5)
		(width 0.15)
		(layer "F.Cu")
		(net 214)
	)
	(arc
		(start 149.4 82.5)
		(mid 149.506066 82.456066)
		(end 149.55 82.35)
		(width 0.15)
		(layer "F.Cu")
		(net 214)
	)
	(segment
		(start 156.5875 93.35)
		(end 156.5875 92.7875)
		(width 0.15)
		(layer "B.Cu")
		(net 214)
	)
	(segment
		(start 152.05 96.545023)
		(end 152.15 96.645023)
		(width 0.15)
		(layer "B.Cu")
		(net 214)
	)
	(segment
		(start 152.15 96.645023)
		(end 152.15 98.625)
		(width 0.15)
		(layer "B.Cu")
		(net 214)
	)
	(segment
		(start 156.5875 92.7875)
		(end 156.5 92.7)
		(width 0.15)
		(layer "B.Cu")
		(net 214)
	)
	(segment
		(start 156.5 93.3)
		(end 156.5 92.7)
		(width 0.15)
		(layer "In3.Cu")
		(net 214)
	)
	(segment
		(start 152.795023 95.8)
		(end 154 95.8)
		(width 0.15)
		(layer "In3.Cu")
		(net 214)
	)
	(segment
		(start 152.05 96.545023)
		(end 152.795023 95.8)
		(width 0.15)
		(layer "In3.Cu")
		(net 214)
	)
	(segment
		(start 154 95.8)
		(end 156.5 93.3)
		(width 0.15)
		(layer "In3.Cu")
		(net 214)
	)
	(segment
		(start 141.425 82.95)
		(end 141.425 83.45)
		(width 0.09)
		(layer "F.Cu")
		(net 215)
	)
	(segment
		(start 141.575 83.6)
		(end 142 83.6)
		(width 0.09)
		(layer "F.Cu")
		(net 215)
	)
	(segment
		(start 155.45 92.75)
		(end 155.45 93.35)
		(width 0.15)
		(layer "F.Cu")
		(net 215)
	)
	(segment
		(start 139.325 82.625)
		(end 139.5 82.8)
		(width 0.09)
		(layer "F.Cu")
		(net 215)
	)
	(segment
		(start 139.5 82.8)
		(end 141.275 82.8)
		(width 0.09)
		(layer "F.Cu")
		(net 215)
	)
	(segment
		(start 155.4 92.7)
		(end 155.4 86.6)
		(width 0.15)
		(layer "F.Cu")
		(net 215)
	)
	(segment
		(start 155.4 92.7)
		(end 155.45 92.75)
		(width 0.15)
		(layer "F.Cu")
		(net 215)
	)
	(segment
		(start 141.275 82.8)
		(end 141.425 82.95)
		(width 0.09)
		(layer "F.Cu")
		(net 215)
	)
	(segment
		(start 139.325 81.95)
		(end 139.325 82.625)
		(width 0.09)
		(layer "F.Cu")
		(net 215)
	)
	(segment
		(start 141.425 83.45)
		(end 141.575 83.6)
		(width 0.09)
		(layer "F.Cu")
		(net 215)
	)
	(segment
		(start 142.2 83.4)
		(end 152.2 83.4)
		(width 0.15)
		(layer "F.Cu")
		(net 215)
	)
	(segment
		(start 138.975 81.6)
		(end 139.325 81.95)
		(width 0.09)
		(layer "F.Cu")
		(net 215)
	)
	(segment
		(start 155.4 86.6)
		(end 152.2 83.4)
		(width 0.15)
		(layer "F.Cu")
		(net 215)
	)
	(segment
		(start 142.2 83.4)
		(end 142 83.6)
		(width 0.15)
		(layer "F.Cu")
		(net 215)
	)
	(via
		(at 151.042133 96.552158)
		(size 0.4)
		(drill 0.2)
		(layers "F.Cu" "B.Cu")
		(net 215)
	)
	(via
		(at 155.4 92.7)
		(size 0.4)
		(drill 0.2)
		(layers "F.Cu" "B.Cu")
		(net 215)
	)
	(segment
		(start 151.15 98.625)
		(end 151.15 96.660025)
		(width 0.15)
		(layer "B.Cu")
		(net 215)
	)
	(segment
		(start 155.45 92.75)
		(end 155.45 93.35)
		(width 0.15)
		(layer "B.Cu")
		(net 215)
	)
	(segment
		(start 155.4 92.7)
		(end 155.45 92.75)
		(width 0.15)
		(layer "B.Cu")
		(net 215)
	)
	(segment
		(start 151.15 96.660025)
		(end 151.042133 96.552158)
		(width 0.15)
		(layer "B.Cu")
		(net 215)
	)
	(segment
		(start 155.4 92.7)
		(end 155.4 93.2)
		(width 0.15)
		(layer "In3.Cu")
		(net 215)
	)
	(segment
		(start 153.4 95.2)
		(end 152.3 95.2)
		(width 0.15)
		(layer "In3.Cu")
		(net 215)
	)
	(segment
		(start 152.3 95.2)
		(end 151.042133 96.457867)
		(width 0.15)
		(layer "In3.Cu")
		(net 215)
	)
	(segment
		(start 151.042133 96.457867)
		(end 151.042133 96.552158)
		(width 0.15)
		(layer "In3.Cu")
		(net 215)
	)
	(segment
		(start 155.4 93.2)
		(end 153.4 95.2)
		(width 0.15)
		(layer "In3.Cu")
		(net 215)
	)
	(segment
		(start 154.85 92.7)
		(end 154.8125 92.7375)
		(width 0.15)
		(layer "F.Cu")
		(net 216)
	)
	(segment
		(start 141.425 84.25)
		(end 141.425 83.825)
		(width 0.09)
		(layer "F.Cu")
		(net 216)
	)
	(segment
		(start 150.4 96.67216)
		(end 150.535501 96.536659)
		(width 0.15)
		(layer "F.Cu")
		(net 216)
	)
	(segment
		(start 141.2 83.6)
		(end 138.840012 83.6)
		(width 0.09)
		(layer "F.Cu")
		(net 216)
	)
	(segment
		(start 142.2 84.425)
		(end 142 84.425)
		(width 0.15)
		(layer "F.Cu")
		(net 216)
	)
	(segment
		(start 154.85 86.85)
		(end 152 84)
		(width 0.15)
		(layer "F.Cu")
		(net 216)
	)
	(segment
		(start 154.8125 92.7375)
		(end 154.8125 93.35)
		(width 0.15)
		(layer "F.Cu")
		(net 216)
	)
	(segment
		(start 141.425 83.825)
		(end 141.2 83.6)
		(width 0.09)
		(layer "F.Cu")
		(net 216)
	)
	(segment
		(start 141.6 84.425)
		(end 141.425 84.25)
		(width 0.09)
		(layer "F.Cu")
		(net 216)
	)
	(segment
		(start 150.4 98.625)
		(end 150.4 96.67216)
		(width 0.15)
		(layer "F.Cu")
		(net 216)
	)
	(segment
		(start 142.625 84)
		(end 142.2 84.425)
		(width 0.15)
		(layer "F.Cu")
		(net 216)
	)
	(segment
		(start 142 84.425)
		(end 141.6 84.425)
		(width 0.09)
		(layer "F.Cu")
		(net 216)
	)
	(segment
		(start 138.840012 83.6)
		(end 138.625 83.384988)
		(width 0.09)
		(layer "F.Cu")
		(net 216)
	)
	(segment
		(start 154.85 92.7)
		(end 154.85 86.85)
		(width 0.15)
		(layer "F.Cu")
		(net 216)
	)
	(segment
		(start 152 84)
		(end 142.625 84)
		(width 0.15)
		(layer "F.Cu")
		(net 216)
	)
	(segment
		(start 138.625 82.75)
		(end 138.275 82.4)
		(width 0.09)
		(layer "F.Cu")
		(net 216)
	)
	(segment
		(start 138.625 83.384988)
		(end 138.625 82.75)
		(width 0.09)
		(layer "F.Cu")
		(net 216)
	)
	(via
		(at 150.535501 96.536659)
		(size 0.4)
		(drill 0.2)
		(layers "F.Cu" "B.Cu")
		(net 216)
	)
	(via
		(at 154.85 92.7)
		(size 0.4)
		(drill 0.2)
		(layers "F.Cu" "B.Cu")
		(net 216)
	)
	(segment
		(start 154.8125 92.7375)
		(end 154.85 92.7)
		(width 0.15)
		(layer "B.Cu")
		(net 216)
	)
	(segment
		(start 154.8125 93.35)
		(end 154.8125 92.7375)
		(width 0.15)
		(layer "B.Cu")
		(net 216)
	)
	(segment
		(start 150.535501 96.368053)
		(end 152.003554 94.9)
		(width 0.15)
		(layer "In3.Cu")
		(net 216)
	)
	(segment
		(start 150.535501 96.536659)
		(end 150.535501 96.368053)
		(width 0.15)
		(layer "In3.Cu")
		(net 216)
	)
	(segment
		(start 154.85 93.15)
		(end 154.85 92.7)
		(width 0.15)
		(layer "In3.Cu")
		(net 216)
	)
	(segment
		(start 152.003554 94.9)
		(end 153.1 94.9)
		(width 0.15)
		(layer "In3.Cu")
		(net 216)
	)
	(segment
		(start 153.1 94.9)
		(end 154.85 93.15)
		(width 0.15)
		(layer "In3.Cu")
		(net 216)
	)
	(segment
		(start 149.75 76.2)
		(end 149.75 76.1)
		(width 0.15)
		(layer "F.Cu")
		(net 217)
	)
	(segment
		(start 138.275 77.6)
		(end 138.625 77.25)
		(width 0.09)
		(layer "F.Cu")
		(net 217)
	)
	(segment
		(start 150.5 76.2)
		(end 152 76.2)
		(width 0.15)
		(layer "F.Cu")
		(net 217)
	)
	(segment
		(start 146.5 76.2)
		(end 146.5 76.3)
		(width 0.15)
		(layer "F.Cu")
		(net 217)
	)
	(segment
		(start 149.85 76)
		(end 150.3 76)
		(width 0.15)
		(layer "F.Cu")
		(net 217)
	)
	(segment
		(start 148.45 76.3)
		(end 148.45 76.2)
		(width 0.15)
		(layer "F.Cu")
		(net 217)
	)
	(segment
		(start 163.6 92.75)
		(end 163.55 92.7)
		(width 0.15)
		(layer "F.Cu")
		(net 217)
	)
	(segment
		(start 142 75.6)
		(end 142.6 76.2)
		(width 0.15)
		(layer "F.Cu")
		(net 217)
	)
	(segment
		(start 144.55 76.2)
		(end 144.55 76.1)
		(width 0.15)
		(layer "F.Cu")
		(net 217)
	)
	(segment
		(start 146.5 76.1)
		(end 146.5 76.2)
		(width 0.15)
		(layer "F.Cu")
		(net 217)
	)
	(segment
		(start 141.425 76.175)
		(end 141.425 75.775)
		(width 0.09)
		(layer "F.Cu")
		(net 217)
	)
	(segment
		(start 145.3 76.4)
		(end 145.75 76.4)
		(width 0.15)
		(layer "F.Cu")
		(net 217)
	)
	(segment
		(start 142.6 76.2)
		(end 143.8 76.2)
		(width 0.15)
		(layer "F.Cu")
		(net 217)
	)
	(segment
		(start 149.2 76.4)
		(end 149.65 76.4)
		(width 0.15)
		(layer "F.Cu")
		(net 217)
	)
	(segment
		(start 147.15 76.2)
		(end 147.15 76.1)
		(width 0.15)
		(layer "F.Cu")
		(net 217)
	)
	(segment
		(start 144.65 76)
		(end 145.1 76)
		(width 0.15)
		(layer "F.Cu")
		(net 217)
	)
	(segment
		(start 149.1 76.1)
		(end 149.1 76.2)
		(width 0.15)
		(layer "F.Cu")
		(net 217)
	)
	(segment
		(start 145.2 76.1)
		(end 145.2 76.2)
		(width 0.15)
		(layer "F.Cu")
		(net 217)
	)
	(segment
		(start 152 76.2)
		(end 163.55 87.75)
		(width 0.15)
		(layer "F.Cu")
		(net 217)
	)
	(segment
		(start 147.25 76)
		(end 147.7 76)
		(width 0.15)
		(layer "F.Cu")
		(net 217)
	)
	(segment
		(start 138.625 76.575)
		(end 138.8 76.4)
		(width 0.09)
		(layer "F.Cu")
		(net 217)
	)
	(segment
		(start 145.85 76.2)
		(end 145.85 76.1)
		(width 0.15)
		(layer "F.Cu")
		(net 217)
	)
	(segment
		(start 145.2 76.2)
		(end 145.2 76.3)
		(width 0.15)
		(layer "F.Cu")
		(net 217)
	)
	(segment
		(start 141.8 75.6)
		(end 142 75.6)
		(width 0.15)
		(layer "F.Cu")
		(net 217)
	)
	(segment
		(start 147.8 76.1)
		(end 147.8 76.2)
		(width 0.15)
		(layer "F.Cu")
		(net 217)
	)
	(segment
		(start 147.15 76.3)
		(end 147.15 76.2)
		(width 0.15)
		(layer "F.Cu")
		(net 217)
	)
	(segment
		(start 141.425 75.775)
		(end 141.6 75.6)
		(width 0.09)
		(layer "F.Cu")
		(net 217)
	)
	(segment
		(start 141.2 76.4)
		(end 141.425 76.175)
		(width 0.09)
		(layer "F.Cu")
		(net 217)
	)
	(segment
		(start 144 76.4)
		(end 144.45 76.4)
		(width 0.15)
		(layer "F.Cu")
		(net 217)
	)
	(segment
		(start 149.1 76.2)
		(end 149.1 76.3)
		(width 0.15)
		(layer "F.Cu")
		(net 217)
	)
	(segment
		(start 163.55 87.75)
		(end 163.55 92.7)
		(width 0.15)
		(layer "F.Cu")
		(net 217)
	)
	(segment
		(start 141.6 75.6)
		(end 141.8 75.6)
		(width 0.09)
		(layer "F.Cu")
		(net 217)
	)
	(segment
		(start 148.55 76)
		(end 149 76)
		(width 0.15)
		(layer "F.Cu")
		(net 217)
	)
	(segment
		(start 147.9 76.4)
		(end 148.35 76.4)
		(width 0.15)
		(layer "F.Cu")
		(net 217)
	)
	(segment
		(start 145.95 76)
		(end 146.4 76)
		(width 0.15)
		(layer "F.Cu")
		(net 217)
	)
	(segment
		(start 163.6 93.35)
		(end 163.6 92.75)
		(width 0.15)
		(layer "F.Cu")
		(net 217)
	)
	(segment
		(start 149.75 76.3)
		(end 149.75 76.2)
		(width 0.15)
		(layer "F.Cu")
		(net 217)
	)
	(segment
		(start 148.45 76.2)
		(end 148.45 76.1)
		(width 0.15)
		(layer "F.Cu")
		(net 217)
	)
	(segment
		(start 147.8 76.2)
		(end 147.8 76.3)
		(width 0.15)
		(layer "F.Cu")
		(net 217)
	)
	(segment
		(start 144.55 76.3)
		(end 144.55 76.2)
		(width 0.15)
		(layer "F.Cu")
		(net 217)
	)
	(segment
		(start 138.8 76.4)
		(end 141.2 76.4)
		(width 0.09)
		(layer "F.Cu")
		(net 217)
	)
	(segment
		(start 146.6 76.4)
		(end 147.05 76.4)
		(width 0.15)
		(layer "F.Cu")
		(net 217)
	)
	(segment
		(start 145.85 76.3)
		(end 145.85 76.2)
		(width 0.15)
		(layer "F.Cu")
		(net 217)
	)
	(segment
		(start 138.625 77.25)
		(end 138.625 76.575)
		(width 0.09)
		(layer "F.Cu")
		(net 217)
	)
	(via
		(at 163.55 92.7)
		(size 0.4)
		(drill 0.2)
		(layers "F.Cu" "B.Cu")
		(net 217)
	)
	(via
		(at 159.3 96.45)
		(size 0.4)
		(drill 0.2)
		(layers "F.Cu" "B.Cu")
		(net 217)
	)
	(arc
		(start 146.4 76)
		(mid 146.470711 76.029289)
		(end 146.5 76.1)
		(width 0.15)
		(layer "F.Cu")
		(net 217)
	)
	(arc
		(start 146.5 76.3)
		(mid 146.529289 76.370711)
		(end 146.6 76.4)
		(width 0.15)
		(layer "F.Cu")
		(net 217)
	)
	(arc
		(start 144.45 76.4)
		(mid 144.520711 76.370711)
		(end 144.55 76.3)
		(width 0.15)
		(layer "F.Cu")
		(net 217)
	)
	(arc
		(start 147.7 76)
		(mid 147.770711 76.029289)
		(end 147.8 76.1)
		(width 0.15)
		(layer "F.Cu")
		(net 217)
	)
	(arc
		(start 149.75 76.1)
		(mid 149.779289 76.029289)
		(end 149.85 76)
		(width 0.15)
		(layer "F.Cu")
		(net 217)
	)
	(arc
		(start 147.15 76.1)
		(mid 147.179289 76.029289)
		(end 147.25 76)
		(width 0.15)
		(layer "F.Cu")
		(net 217)
	)
	(arc
		(start 148.45 76.1)
		(mid 148.479289 76.029289)
		(end 148.55 76)
		(width 0.15)
		(layer "F.Cu")
		(net 217)
	)
	(arc
		(start 145.1 76)
		(mid 145.170711 76.029289)
		(end 145.2 76.1)
		(width 0.15)
		(layer "F.Cu")
		(net 217)
	)
	(arc
		(start 143.9 76.3)
		(mid 143.929289 76.370711)
		(end 144 76.4)
		(width 0.15)
		(layer "F.Cu")
		(net 217)
	)
	(arc
		(start 149 76)
		(mid 149.070711 76.029289)
		(end 149.1 76.1)
		(width 0.15)
		(layer "F.Cu")
		(net 217)
	)
	(arc
		(start 144.55 76.1)
		(mid 144.579289 76.029289)
		(end 144.65 76)
		(width 0.15)
		(layer "F.Cu")
		(net 217)
	)
	(arc
		(start 145.2 76.3)
		(mid 145.229289 76.370711)
		(end 145.3 76.4)
		(width 0.15)
		(layer "F.Cu")
		(net 217)
	)
	(arc
		(start 143.8 76.2)
		(mid 143.870711 76.229289)
		(end 143.9 76.3)
		(width 0.15)
		(layer "F.Cu")
		(net 217)
	)
	(arc
		(start 150.4 76.1)
		(mid 150.429289 76.170711)
		(end 150.5 76.2)
		(width 0.15)
		(layer "F.Cu")
		(net 217)
	)
	(arc
		(start 147.05 76.4)
		(mid 147.120711 76.370711)
		(end 147.15 76.3)
		(width 0.15)
		(layer "F.Cu")
		(net 217)
	)
	(arc
		(start 148.35 76.4)
		(mid 148.420711 76.370711)
		(end 148.45 76.3)
		(width 0.15)
		(layer "F.Cu")
		(net 217)
	)
	(arc
		(start 149.65 76.4)
		(mid 149.720711 76.370711)
		(end 149.75 76.3)
		(width 0.15)
		(layer "F.Cu")
		(net 217)
	)
	(arc
		(start 145.85 76.1)
		(mid 145.879289 76.029289)
		(end 145.95 76)
		(width 0.15)
		(layer "F.Cu")
		(net 217)
	)
	(arc
		(start 145.75 76.4)
		(mid 145.820711 76.370711)
		(end 145.85 76.3)
		(width 0.15)
		(layer "F.Cu")
		(net 217)
	)
	(arc
		(start 149.1 76.3)
		(mid 149.129289 76.370711)
		(end 149.2 76.4)
		(width 0.15)
		(layer "F.Cu")
		(net 217)
	)
	(arc
		(start 150.3 76)
		(mid 150.370711 76.029289)
		(end 150.4 76.1)
		(width 0.15)
		(layer "F.Cu")
		(net 217)
	)
	(arc
		(start 147.8 76.3)
		(mid 147.829289 76.370711)
		(end 147.9 76.4)
		(width 0.15)
		(layer "F.Cu")
		(net 217)
	)
	(segment
		(start 159.3 96.45)
		(end 159.15 96.6)
		(width 0.15)
		(layer "B.Cu")
		(net 217)
	)
	(segment
		(start 163.6 92.75)
		(end 163.55 92.7)
		(width 0.15)
		(layer "B.Cu")
		(net 217)
	)
	(segment
		(start 159.15 96.6)
		(end 159.15 98.625)
		(width 0.15)
		(layer "B.Cu")
		(net 217)
	)
	(segment
		(start 163.6 93.35)
		(end 163.6 92.75)
		(width 0.15)
		(layer "B.Cu")
		(net 217)
	)
	(segment
		(start 160.884586 94.75)
		(end 161.9 94.75)
		(width 0.15)
		(layer "In3.Cu")
		(net 217)
	)
	(segment
		(start 159.3 96.45)
		(end 159.3 96.334586)
		(width 0.15)
		(layer "In3.Cu")
		(net 217)
	)
	(segment
		(start 161.9 94.75)
		(end 163.55 93.1)
		(width 0.15)
		(layer "In3.Cu")
		(net 217)
	)
	(segment
		(start 159.3 96.334586)
		(end 160.884586 94.75)
		(width 0.15)
		(layer "In3.Cu")
		(net 217)
	)
	(segment
		(start 163.55 93.1)
		(end 163.55 92.7)
		(width 0.15)
		(layer "In3.Cu")
		(net 217)
	)
	(segment
		(start 155.369842 80.711263)
		(end 155.511261 80.56984)
		(width 0.15)
		(layer "F.Cu")
		(net 218)
	)
	(segment
		(start 158.9 96.549503)
		(end 158.9 98.625)
		(width 0.15)
		(layer "F.Cu")
		(net 218)
	)
	(segment
		(start 157.349737 82.266894)
		(end 157.632579 82.549736)
		(width 0.15)
		(layer "F.Cu")
		(net 218)
	)
	(segment
		(start 141.425 76.575)
		(end 141.6 76.4)
		(width 0.09)
		(layer "F.Cu")
		(net 218)
	)
	(segment
		(start 159.046789 83.963946)
		(end 159.329631 84.246788)
		(width 0.15)
		(layer "F.Cu")
		(net 218)
	)
	(segment
		(start 139.626875 77.15315)
		(end 141.24685 77.15315)
		(width 0.09)
		(layer "F.Cu")
		(net 218)
	)
	(segment
		(start 155.369841 80.711264)
		(end 155.369842 80.711263)
		(width 0.15)
		(layer "F.Cu")
		(net 218)
	)
	(segment
		(start 142.2 76.4)
		(end 142.6 76.8)
		(width 0.15)
		(layer "F.Cu")
		(net 218)
	)
	(segment
		(start 154.238475 79.297054)
		(end 154.097052 79.438473)
		(width 0.15)
		(layer "F.Cu")
		(net 218)
	)
	(segment
		(start 139.325 78.05)
		(end 139.325 77.455025)
		(width 0.09)
		(layer "F.Cu")
		(net 218)
	)
	(segment
		(start 157.066893 82.408316)
		(end 157.066894 82.408315)
		(width 0.15)
		(layer "F.Cu")
		(net 218)
	)
	(segment
		(start 153.38995 78.448527)
		(end 153.389949 78.448528)
		(width 0.15)
		(layer "F.Cu")
		(net 218)
	)
	(segment
		(start 156.64263 82.125473)
		(end 156.925472 82.408315)
		(width 0.15)
		(layer "F.Cu")
		(net 218)
	)
	(segment
		(start 157.632579 82.691158)
		(end 157.491156 82.832577)
		(width 0.15)
		(layer "F.Cu")
		(net 218)
	)
	(segment
		(start 157.066894 82.408315)
		(end 157.208313 82.266892)
		(width 0.15)
		(layer "F.Cu")
		(net 218)
	)
	(segment
		(start 142.6 76.8)
		(end 151.6 76.8)
		(width 0.15)
		(layer "F.Cu")
		(net 218)
	)
	(segment
		(start 155.935527 80.994106)
		(end 155.794104 81.135525)
		(width 0.15)
		(layer "F.Cu")
		(net 218)
	)
	(segment
		(start 154.804159 79.721316)
		(end 155.087001 80.004158)
		(width 0.15)
		(layer "F.Cu")
		(net 218)
	)
	(segment
		(start 156.218367 81.55979)
		(end 156.218368 81.559789)
		(width 0.15)
		(layer "F.Cu")
		(net 218)
	)
	(segment
		(start 152.399999 77.741421)
		(end 152.4 77.741421)
		(width 0.15)
		(layer "F.Cu")
		(net 218)
	)
	(segment
		(start 155.794104 81.276947)
		(end 156.076946 81.559789)
		(width 0.15)
		(layer "F.Cu")
		(net 218)
	)
	(segment
		(start 153.248526 78.731369)
		(end 153.531368 79.014211)
		(width 0.15)
		(layer "F.Cu")
		(net 218)
	)
	(segment
		(start 157.63258 82.691157)
		(end 157.632579 82.691158)
		(width 0.15)
		(layer "F.Cu")
		(net 218)
	)
	(segment
		(start 158.339682 83.822525)
		(end 158.622524 84.105367)
		(width 0.15)
		(layer "F.Cu")
		(net 218)
	)
	(segment
		(start 153.107107 78.024264)
		(end 153.389949 78.307106)
		(width 0.15)
		(layer "F.Cu")
		(net 218)
	)
	(segment
		(start 156.784054 81.842631)
		(end 156.784053 81.842632)
		(width 0.15)
		(layer "F.Cu")
		(net 218)
	)
	(segment
		(start 141.8 76.4)
		(end 142.2 76.4)
		(width 0.15)
		(layer "F.Cu")
		(net 218)
	)
	(segment
		(start 152.4 77.882842)
		(end 152.682842 78.165684)
		(width 0.15)
		(layer "F.Cu")
		(net 218)
	)
	(segment
		(start 157.915419 83.256842)
		(end 157.91542 83.256841)
		(width 0.15)
		(layer "F.Cu")
		(net 218)
	)
	(segment
		(start 152.4 77.882841)
		(end 152.4 77.882842)
		(width 0.15)
		(layer "F.Cu")
		(net 218)
	)
	(segment
		(start 157.491156 82.973999)
		(end 157.773998 83.256841)
		(width 0.15)
		(layer "F.Cu")
		(net 218)
	)
	(segment
		(start 153.955633 78.87279)
		(end 154.238475 79.155632)
		(width 0.15)
		(layer "F.Cu")
		(net 218)
	)
	(segment
		(start 158.763946 84.105367)
		(end 158.905365 83.963944)
		(width 0.15)
		(layer "F.Cu")
		(net 218)
	)
	(segment
		(start 156.218368 81.559789)
		(end 156.359787 81.418366)
		(width 0.15)
		(layer "F.Cu")
		(net 218)
	)
	(segment
		(start 154.521316 79.862737)
		(end 154.662735 79.721314)
		(width 0.15)
		(layer "F.Cu")
		(net 218)
	)
	(segment
		(start 159.329632 84.388209)
		(end 159.329631 84.38821)
		(width 0.15)
		(layer "F.Cu")
		(net 218)
	)
	(segment
		(start 158.481105 83.539684)
		(end 158.339682 83.681103)
		(width 0.15)
		(layer "F.Cu")
		(net 218)
	)
	(segment
		(start 141.24685 77.15315)
		(end 141.425 76.975)
		(width 0.09)
		(layer "F.Cu")
		(net 218)
	)
	(segment
		(start 163 88.2)
		(end 163 92.7)
		(width 0.15)
		(layer "F.Cu")
		(net 218)
	)
	(segment
		(start 158.800497 96.45)
		(end 158.9 96.549503)
		(width 0.15)
		(layer "F.Cu")
		(net 218)
	)
	(segment
		(start 152.824263 78.165685)
		(end 152.824264 78.165684)
		(width 0.15)
		(layer "F.Cu")
		(net 218)
	)
	(segment
		(start 152.824264 78.165684)
		(end 152.965683 78.024262)
		(width 0.15)
		(layer "F.Cu")
		(net 218)
	)
	(segment
		(start 155.087002 80.145579)
		(end 155.087001 80.14558)
		(width 0.15)
		(layer "F.Cu")
		(net 218)
	)
	(segment
		(start 157.91542 83.256841)
		(end 158.056839 83.115418)
		(width 0.15)
		(layer "F.Cu")
		(net 218)
	)
	(segment
		(start 158.481106 83.539683)
		(end 158.481105 83.539684)
		(width 0.15)
		(layer "F.Cu")
		(net 218)
	)
	(segment
		(start 155.935528 80.994105)
		(end 155.935527 80.994106)
		(width 0.15)
		(layer "F.Cu")
		(net 218)
	)
	(segment
		(start 154.238476 79.297053)
		(end 154.238475 79.297054)
		(width 0.15)
		(layer "F.Cu")
		(net 218)
	)
	(segment
		(start 153.672789 79.014212)
		(end 153.67279 79.014211)
		(width 0.15)
		(layer "F.Cu")
		(net 218)
	)
	(segment
		(start 154.521315 79.862738)
		(end 154.521316 79.862737)
		(width 0.15)
		(layer "F.Cu")
		(net 218)
	)
	(segment
		(start 162.9625 92.7375)
		(end 162.9625 93.35)
		(width 0.15)
		(layer "F.Cu")
		(net 218)
	)
	(segment
		(start 155.087001 80.14558)
		(end 154.945578 80.286999)
		(width 0.15)
		(layer "F.Cu")
		(net 218)
	)
	(segment
		(start 153.67279 79.014211)
		(end 153.814209 78.872788)
		(width 0.15)
		(layer "F.Cu")
		(net 218)
	)
	(segment
		(start 159.32963 84.52963)
		(end 163 88.2)
		(width 0.15)
		(layer "F.Cu")
		(net 218)
	)
	(segment
		(start 155.652685 80.569842)
		(end 155.935527 80.852684)
		(width 0.15)
		(layer "F.Cu")
		(net 218)
	)
	(segment
		(start 141.6 76.4)
		(end 141.8 76.4)
		(width 0.09)
		(layer "F.Cu")
		(net 218)
	)
	(segment
		(start 141.425 76.975)
		(end 141.425 76.575)
		(width 0.09)
		(layer "F.Cu")
		(net 218)
	)
	(segment
		(start 154.097052 79.579895)
		(end 154.379894 79.862737)
		(width 0.15)
		(layer "F.Cu")
		(net 218)
	)
	(segment
		(start 163 92.7)
		(end 162.9625 92.7375)
		(width 0.15)
		(layer "F.Cu")
		(net 218)
	)
	(segment
		(start 154.945578 80.428421)
		(end 155.22842 80.711263)
		(width 0.15)
		(layer "F.Cu")
		(net 218)
	)
	(segment
		(start 139.325 77.455025)
		(end 139.626875 77.15315)
		(width 0.09)
		(layer "F.Cu")
		(net 218)
	)
	(segment
		(start 138.975 78.4)
		(end 139.325 78.05)
		(width 0.09)
		(layer "F.Cu")
		(net 218)
	)
	(segment
		(start 158.763945 84.105368)
		(end 158.763946 84.105367)
		(width 0.15)
		(layer "F.Cu")
		(net 218)
	)
	(segment
		(start 156.501211 81.418368)
		(end 156.784053 81.70121)
		(width 0.15)
		(layer "F.Cu")
		(net 218)
	)
	(segment
		(start 153.389949 78.448528)
		(end 153.248526 78.589947)
		(width 0.15)
		(layer "F.Cu")
		(net 218)
	)
	(segment
		(start 159.329631 84.52963)
		(end 159.32963 84.52963)
		(width 0.15)
		(layer "F.Cu")
		(net 218)
	)
	(segment
		(start 151.6 76.8)
		(end 152.4 77.6)
		(width 0.15)
		(layer "F.Cu")
		(net 218)
	)
	(segment
		(start 158.198263 83.11542)
		(end 158.481105 83.398262)
		(width 0.15)
		(layer "F.Cu")
		(net 218)
	)
	(segment
		(start 156.784053 81.842632)
		(end 156.64263 81.984051)
		(width 0.15)
		(layer "F.Cu")
		(net 218)
	)
	(via
		(at 163 92.7)
		(size 0.4)
		(drill 0.2)
		(layers "F.Cu" "B.Cu")
		(net 218)
	)
	(via
		(at 158.800497 96.45)
		(size 0.4)
		(drill 0.2)
		(layers "F.Cu" "B.Cu")
		(net 218)
	)
	(arc
		(start 152.965683 78.024262)
		(mid 153.036396 77.994975)
		(end 153.107107 78.024264)
		(width 0.15)
		(layer "F.Cu")
		(net 218)
	)
	(arc
		(start 153.814209 78.872788)
		(mid 153.884922 78.843501)
		(end 153.955633 78.87279)
		(width 0.15)
		(layer "F.Cu")
		(net 218)
	)
	(arc
		(start 158.339682 83.681103)
		(mid 158.310393 83.751814)
		(end 158.339682 83.822525)
		(width 0.15)
		(layer "F.Cu")
		(net 218)
	)
	(arc
		(start 152.4 77.741421)
		(mid 152.370711 77.812131)
		(end 152.4 77.882841)
		(width 0.15)
		(layer "F.Cu")
		(net 218)
	)
	(arc
		(start 154.662735 79.721314)
		(mid 154.733448 79.692027)
		(end 154.804159 79.721316)
		(width 0.15)
		(layer "F.Cu")
		(net 218)
	)
	(arc
		(start 156.359787 81.418366)
		(mid 156.4305 81.389079)
		(end 156.501211 81.418368)
		(width 0.15)
		(layer "F.Cu")
		(net 218)
	)
	(arc
		(start 159.329631 84.246788)
		(mid 159.358921 84.317498)
		(end 159.329632 84.388209)
		(width 0.15)
		(layer "F.Cu")
		(net 218)
	)
	(arc
		(start 155.794104 81.135525)
		(mid 155.764815 81.206236)
		(end 155.794104 81.276947)
		(width 0.15)
		(layer "F.Cu")
		(net 218)
	)
	(arc
		(start 155.935527 80.852684)
		(mid 155.964817 80.923394)
		(end 155.935528 80.994105)
		(width 0.15)
		(layer "F.Cu")
		(net 218)
	)
	(arc
		(start 158.622524 84.105367)
		(mid 158.693234 84.134657)
		(end 158.763945 84.105368)
		(width 0.15)
		(layer "F.Cu")
		(net 218)
	)
	(arc
		(start 159.329631 84.38821)
		(mid 159.300341 84.458919)
		(end 159.329631 84.52963)
		(width 0.15)
		(layer "F.Cu")
		(net 218)
	)
	(arc
		(start 153.531368 79.014211)
		(mid 153.602078 79.043501)
		(end 153.672789 79.014212)
		(width 0.15)
		(layer "F.Cu")
		(net 218)
	)
	(arc
		(start 157.491156 82.832577)
		(mid 157.461867 82.903288)
		(end 157.491156 82.973999)
		(width 0.15)
		(layer "F.Cu")
		(net 218)
	)
	(arc
		(start 158.481105 83.398262)
		(mid 158.510395 83.468972)
		(end 158.481106 83.539683)
		(width 0.15)
		(layer "F.Cu")
		(net 218)
	)
	(arc
		(start 155.511261 80.56984)
		(mid 155.581974 80.540553)
		(end 155.652685 80.569842)
		(width 0.15)
		(layer "F.Cu")
		(net 218)
	)
	(arc
		(start 154.238475 79.155632)
		(mid 154.267765 79.226342)
		(end 154.238476 79.297053)
		(width 0.15)
		(layer "F.Cu")
		(net 218)
	)
	(arc
		(start 155.087001 80.004158)
		(mid 155.116291 80.074868)
		(end 155.087002 80.145579)
		(width 0.15)
		(layer "F.Cu")
		(net 218)
	)
	(arc
		(start 153.248526 78.589947)
		(mid 153.219237 78.660658)
		(end 153.248526 78.731369)
		(width 0.15)
		(layer "F.Cu")
		(net 218)
	)
	(arc
		(start 156.076946 81.559789)
		(mid 156.147656 81.589079)
		(end 156.218367 81.55979)
		(width 0.15)
		(layer "F.Cu")
		(net 218)
	)
	(arc
		(start 157.208313 82.266892)
		(mid 157.279026 82.237605)
		(end 157.349737 82.266894)
		(width 0.15)
		(layer "F.Cu")
		(net 218)
	)
	(arc
		(start 155.22842 80.711263)
		(mid 155.29913 80.740553)
		(end 155.369841 80.711264)
		(width 0.15)
		(layer "F.Cu")
		(net 218)
	)
	(arc
		(start 154.945578 80.286999)
		(mid 154.916289 80.35771)
		(end 154.945578 80.428421)
		(width 0.15)
		(layer "F.Cu")
		(net 218)
	)
	(arc
		(start 157.773998 83.256841)
		(mid 157.844708 83.286131)
		(end 157.915419 83.256842)
		(width 0.15)
		(layer "F.Cu")
		(net 218)
	)
	(arc
		(start 152.682842 78.165684)
		(mid 152.753552 78.194974)
		(end 152.824263 78.165685)
		(width 0.15)
		(layer "F.Cu")
		(net 218)
	)
	(arc
		(start 158.905365 83.963944)
		(mid 158.976078 83.934657)
		(end 159.046789 83.963946)
		(width 0.15)
		(layer "F.Cu")
		(net 218)
	)
	(arc
		(start 154.097052 79.438473)
		(mid 154.067763 79.509184)
		(end 154.097052 79.579895)
		(width 0.15)
		(layer "F.Cu")
		(net 218)
	)
	(arc
		(start 153.389949 78.307106)
		(mid 153.419239 78.377816)
		(end 153.38995 78.448527)
		(width 0.15)
		(layer "F.Cu")
		(net 218)
	)
	(arc
		(start 154.379894 79.862737)
		(mid 154.450604 79.892027)
		(end 154.521315 79.862738)
		(width 0.15)
		(layer "F.Cu")
		(net 218)
	)
	(arc
		(start 157.632579 82.549736)
		(mid 157.661869 82.620446)
		(end 157.63258 82.691157)
		(width 0.15)
		(layer "F.Cu")
		(net 218)
	)
	(arc
		(start 156.64263 81.984051)
		(mid 156.613341 82.054762)
		(end 156.64263 82.125473)
		(width 0.15)
		(layer "F.Cu")
		(net 218)
	)
	(arc
		(start 156.925472 82.408315)
		(mid 156.996182 82.437605)
		(end 157.066893 82.408316)
		(width 0.15)
		(layer "F.Cu")
		(net 218)
	)
	(arc
		(start 156.784053 81.70121)
		(mid 156.813343 81.77192)
		(end 156.784054 81.842631)
		(width 0.15)
		(layer "F.Cu")
		(net 218)
	)
	(arc
		(start 158.056839 83.115418)
		(mid 158.127552 83.086131)
		(end 158.198263 83.11542)
		(width 0.15)
		(layer "F.Cu")
		(net 218)
	)
	(arc
		(start 152.4 77.6)
		(mid 152.429289 77.670711)
		(end 152.399999 77.741421)
		(width 0.15)
		(layer "F.Cu")
		(net 218)
	)
	(segment
		(start 162.9625 92.7375)
		(end 163 92.7)
		(width 0.15)
		(layer "B.Cu")
		(net 218)
	)
	(segment
		(start 162.9625 93.35)
		(end 162.9625 92.7375)
		(width 0.15)
		(layer "B.Cu")
		(net 218)
	)
	(segment
		(start 163 92.7)
		(end 163 93.05)
		(width 0.15)
		(layer "In3.Cu")
		(net 218)
	)
	(segment
		(start 163 93.05)
		(end 161.65 94.4)
		(width 0.15)
		(layer "In3.Cu")
		(net 218)
	)
	(segment
		(start 160.65 94.4)
		(end 158.800497 96.249503)
		(width 0.15)
		(layer "In3.Cu")
		(net 218)
	)
	(segment
		(start 161.65 94.4)
		(end 160.65 94.4)
		(width 0.15)
		(layer "In3.Cu")
		(net 218)
	)
	(segment
		(start 158.800497 96.249503)
		(end 158.800497 96.45)
		(width 0.15)
		(layer "In3.Cu")
		(net 218)
	)
	(segment
		(start 157.363946 84.988211)
		(end 157.576078 85.200343)
		(width 0.15)
		(layer "F.Cu")
		(net 219)
	)
	(segment
		(start 155.666894 83.079027)
		(end 155.879029 82.866896)
		(width 0.15)
		(layer "F.Cu")
		(net 219)
	)
	(segment
		(start 153.121316 80.533449)
		(end 153.333451 80.321318)
		(width 0.15)
		(layer "F.Cu")
		(net 219)
	)
	(segment
		(start 159.485262 86.897395)
		(end 159.697393 86.68526)
		(width 0.15)
		(layer "F.Cu")
		(net 219)
	)
	(segment
		(start 151.424264 78.2)
		(end 151.636396 78.412132)
		(width 0.15)
		(layer "F.Cu")
		(net 219)
	)
	(segment
		(start 158.212472 85.624605)
		(end 158.424607 85.412474)
		(width 0.15)
		(layer "F.Cu")
		(net 219)
	)
	(segment
		(start 157.78821 85.200343)
		(end 158.000341 84.988208)
		(width 0.15)
		(layer "F.Cu")
		(net 219)
	)
	(segment
		(start 154.818368 82.230501)
		(end 155.030503 82.01837)
		(width 0.15)
		(layer "F.Cu")
		(net 219)
	)
	(segment
		(start 157.363946 84.776079)
		(end 157.576081 84.563948)
		(width 0.15)
		(layer "F.Cu")
		(net 219)
	)
	(segment
		(start 156.939684 84.351817)
		(end 157.151815 84.139682)
		(width 0.15)
		(layer "F.Cu")
		(net 219)
	)
	(segment
		(start 161.9 92.7)
		(end 161.825 92.775)
		(width 0.15)
		(layer "F.Cu")
		(net 219)
	)
	(segment
		(start 153.969842 81.594107)
		(end 154.181974 81.806239)
		(width 0.15)
		(layer "F.Cu")
		(net 219)
	)
	(segment
		(start 154.394106 81.806239)
		(end 154.606237 81.594104)
		(width 0.15)
		(layer "F.Cu")
		(net 219)
	)
	(segment
		(start 158.212476 84.988211)
		(end 158.212475 84.98821)
		(width 0.15)
		(layer "F.Cu")
		(net 219)
	)
	(segment
		(start 157.363947 84.988212)
		(end 157.363946 84.988211)
		(width 0.15)
		(layer "F.Cu")
		(net 219)
	)
	(segment
		(start 155.242632 82.654765)
		(end 155.454763 82.44263)
		(width 0.15)
		(layer "F.Cu")
		(net 219)
	)
	(segment
		(start 151.424264 79.048529)
		(end 151.636396 79.260661)
		(width 0.15)
		(layer "F.Cu")
		(net 219)
	)
	(segment
		(start 153.969842 81.381975)
		(end 154.181977 81.169844)
		(width 0.15)
		(layer "F.Cu")
		(net 219)
	)
	(segment
		(start 155.666894 83.291159)
		(end 155.879026 83.503291)
		(width 0.15)
		(layer "F.Cu")
		(net 219)
	)
	(segment
		(start 154.818368 82.442633)
		(end 155.0305 82.654765)
		(width 0.15)
		(layer "F.Cu")
		(net 219)
	)
	(segment
		(start 157.9 96.548509)
		(end 157.9 98.625)
		(width 0.15)
		(layer "F.Cu")
		(net 219)
	)
	(segment
		(start 153.969846 80.745581)
		(end 153.969845 80.74558)
		(width 0.15)
		(layer "F.Cu")
		(net 219)
	)
	(segment
		(start 158.212472 85.836737)
		(end 158.424604 86.048869)
		(width 0.15)
		(layer "F.Cu")
		(net 219)
	)
	(segment
		(start 161.825 92.775)
		(end 161.825 93.35)
		(width 0.15)
		(layer "F.Cu")
		(net 219)
	)
	(segment
		(start 153.969845 80.74558)
		(end 154.181977 80.957712)
		(width 0.15)
		(layer "F.Cu")
		(net 219)
	)
	(segment
		(start 150.8 78)
		(end 151 78.2)
		(width 0.15)
		(layer "F.Cu")
		(net 219)
	)
	(segment
		(start 153.12132 79.897055)
		(end 153.121319 79.897054)
		(width 0.15)
		(layer "F.Cu")
		(net 219)
	)
	(segment
		(start 140.375 78.4)
		(end 140.775 78)
		(width 0.09)
		(layer "F.Cu")
		(net 219)
	)
	(segment
		(start 153.54558 80.957713)
		(end 153.757711 80.745578)
		(width 0.15)
		(layer "F.Cu")
		(net 219)
	)
	(segment
		(start 157.801491 96.45)
		(end 157.9 96.548509)
		(width 0.15)
		(layer "F.Cu")
		(net 219)
	)
	(segment
		(start 159.909528 86.685263)
		(end 159.909527 86.685262)
		(width 0.15)
		(layer "F.Cu")
		(net 219)
	)
	(segment
		(start 153.121317 80.745582)
		(end 153.121316 80.745581)
		(width 0.15)
		(layer "F.Cu")
		(net 219)
	)
	(segment
		(start 158.212475 84.98821)
		(end 158.424607 85.200342)
		(width 0.15)
		(layer "F.Cu")
		(net 219)
	)
	(segment
		(start 155.666897 82.442632)
		(end 155.879029 82.654764)
		(width 0.15)
		(layer "F.Cu")
		(net 219)
	)
	(segment
		(start 151.848528 79.260661)
		(end 152.060659 79.048526)
		(width 0.15)
		(layer "F.Cu")
		(net 219)
	)
	(segment
		(start 156.515424 83.291159)
		(end 156.515423 83.291158)
		(width 0.15)
		(layer "F.Cu")
		(net 219)
	)
	(segment
		(start 159.060998 86.473131)
		(end 159.273133 86.261)
		(width 0.15)
		(layer "F.Cu")
		(net 219)
	)
	(segment
		(start 159.060998 86.685263)
		(end 159.27313 86.897395)
		(width 0.15)
		(layer "F.Cu")
		(net 219)
	)
	(segment
		(start 151.424265 79.04853)
		(end 151.424264 79.048529)
		(width 0.15)
		(layer "F.Cu")
		(net 219)
	)
	(segment
		(start 156.091158 83.503291)
		(end 156.303289 83.291156)
		(width 0.15)
		(layer "F.Cu")
		(net 219)
	)
	(segment
		(start 161.9 89.1)
		(end 161.9 92.7)
		(width 0.15)
		(layer "F.Cu")
		(net 219)
	)
	(segment
		(start 152.27279 79.684923)
		(end 152.484925 79.472792)
		(width 0.15)
		(layer "F.Cu")
		(net 219)
	)
	(segment
		(start 154.818371 81.594106)
		(end 155.030503 81.806238)
		(width 0.15)
		(layer "F.Cu")
		(net 219)
	)
	(segment
		(start 156.51542 83.927553)
		(end 156.727555 83.715422)
		(width 0.15)
		(layer "F.Cu")
		(net 219)
	)
	(segment
		(start 155.666898 82.442633)
		(end 155.666897 82.442632)
		(width 0.15)
		(layer "F.Cu")
		(net 219)
	)
	(segment
		(start 155.666895 83.29116)
		(end 155.666894 83.291159)
		(width 0.15)
		(layer "F.Cu")
		(net 219)
	)
	(segment
		(start 159.060999 86.685264)
		(end 159.060998 86.685263)
		(width 0.15)
		(layer "F.Cu")
		(net 219)
	)
	(segment
		(start 156.51542 84.139685)
		(end 156.727552 84.351817)
		(width 0.15)
		(layer "F.Cu")
		(net 219)
	)
	(segment
		(start 153.969843 81.594108)
		(end 153.969842 81.594107)
		(width 0.15)
		(layer "F.Cu")
		(net 219)
	)
	(segment
		(start 152.697054 80.109187)
		(end 152.909185 79.897052)
		(width 0.15)
		(layer "F.Cu")
		(net 219)
	)
	(segment
		(start 141.8 78)
		(end 150.8 78)
		(width 0.15)
		(layer "F.Cu")
		(net 219)
	)
	(segment
		(start 140.775 78)
		(end 141.8 78)
		(width 0.09)
		(layer "F.Cu")
		(net 219)
	)
	(segment
		(start 151.212133 78.199999)
		(end 151.212132 78.2)
		(width 0.15)
		(layer "F.Cu")
		(net 219)
	)
	(segment
		(start 160.121659 87.321658)
		(end 161.9 89.1)
		(width 0.15)
		(layer "F.Cu")
		(net 219)
	)
	(segment
		(start 153.121316 80.745581)
		(end 153.333448 80.957713)
		(width 0.15)
		(layer "F.Cu")
		(net 219)
	)
	(segment
		(start 158.636736 86.048869)
		(end 158.848867 85.836734)
		(width 0.15)
		(layer "F.Cu")
		(net 219)
	)
	(segment
		(start 157.363949 84.139684)
		(end 157.576081 84.351816)
		(width 0.15)
		(layer "F.Cu")
		(net 219)
	)
	(segment
		(start 153.121319 79.897054)
		(end 153.333451 80.109186)
		(width 0.15)
		(layer "F.Cu")
		(net 219)
	)
	(segment
		(start 156.515421 84.139686)
		(end 156.51542 84.139685)
		(width 0.15)
		(layer "F.Cu")
		(net 219)
	)
	(segment
		(start 151.636396 78.624264)
		(end 151.53033 78.730331)
		(width 0.15)
		(layer "F.Cu")
		(net 219)
	)
	(segment
		(start 152.272794 79.048529)
		(end 152.272793 79.048528)
		(width 0.15)
		(layer "F.Cu")
		(net 219)
	)
	(segment
		(start 154.818369 82.442634)
		(end 154.818368 82.442633)
		(width 0.15)
		(layer "F.Cu")
		(net 219)
	)
	(segment
		(start 154.818372 81.594107)
		(end 154.818371 81.594106)
		(width 0.15)
		(layer "F.Cu")
		(net 219)
	)
	(segment
		(start 158.212473 85.836738)
		(end 158.212472 85.836737)
		(width 0.15)
		(layer "F.Cu")
		(net 219)
	)
	(segment
		(start 151.53033 78.730331)
		(end 151.424264 78.836397)
		(width 0.15)
		(layer "F.Cu")
		(net 219)
	)
	(segment
		(start 159.061001 85.836736)
		(end 159.273133 86.048868)
		(width 0.15)
		(layer "F.Cu")
		(net 219)
	)
	(segment
		(start 156.515423 83.291158)
		(end 156.727555 83.50329)
		(width 0.15)
		(layer "F.Cu")
		(net 219)
	)
	(segment
		(start 152.27279 79.897055)
		(end 152.484922 80.109187)
		(width 0.15)
		(layer "F.Cu")
		(net 219)
	)
	(segment
		(start 159.061002 85.836737)
		(end 159.061001 85.836736)
		(width 0.15)
		(layer "F.Cu")
		(net 219)
	)
	(segment
		(start 159.909527 86.685262)
		(end 160.121659 86.897394)
		(width 0.15)
		(layer "F.Cu")
		(net 219)
	)
	(segment
		(start 157.36395 84.139685)
		(end 157.363949 84.139684)
		(width 0.15)
		(layer "F.Cu")
		(net 219)
	)
	(segment
		(start 152.272791 79.897056)
		(end 152.27279 79.897055)
		(width 0.15)
		(layer "F.Cu")
		(net 219)
	)
	(segment
		(start 152.272793 79.048528)
		(end 152.484925 79.26066)
		(width 0.15)
		(layer "F.Cu")
		(net 219)
	)
	(via
		(at 161.9 92.7)
		(size 0.4)
		(drill 0.2)
		(layers "F.Cu" "B.Cu")
		(net 219)
	)
	(via
		(at 157.801491 96.45)
		(size 0.4)
		(drill 0.2)
		(layers "F.Cu" "B.Cu")
		(net 219)
	)
	(arc
		(start 151.636396 79.260661)
		(mid 151.742462 79.304595)
		(end 151.848528 79.260661)
		(width 0.15)
		(layer "F.Cu")
		(net 219)
	)
	(arc
		(start 160.121659 87.109526)
		(mid 160.077725 87.215592)
		(end 160.121659 87.321658)
		(width 0.15)
		(layer "F.Cu")
		(net 219)
	)
	(arc
		(start 155.0305 82.654765)
		(mid 155.136566 82.698699)
		(end 155.242632 82.654765)
		(width 0.15)
		(layer "F.Cu")
		(net 219)
	)
	(arc
		(start 155.879029 82.654764)
		(mid 155.922963 82.76083)
		(end 155.879029 82.866896)
		(width 0.15)
		(layer "F.Cu")
		(net 219)
	)
	(arc
		(start 152.909185 79.897052)
		(mid 153.015253 79.853119)
		(end 153.12132 79.897055)
		(width 0.15)
		(layer "F.Cu")
		(net 219)
	)
	(arc
		(start 158.424607 85.200342)
		(mid 158.468541 85.306408)
		(end 158.424607 85.412474)
		(width 0.15)
		(layer "F.Cu")
		(net 219)
	)
	(arc
		(start 152.484922 80.109187)
		(mid 152.590988 80.153121)
		(end 152.697054 80.109187)
		(width 0.15)
		(layer "F.Cu")
		(net 219)
	)
	(arc
		(start 155.879026 83.503291)
		(mid 155.985092 83.547225)
		(end 156.091158 83.503291)
		(width 0.15)
		(layer "F.Cu")
		(net 219)
	)
	(arc
		(start 156.727555 83.50329)
		(mid 156.771489 83.609356)
		(end 156.727555 83.715422)
		(width 0.15)
		(layer "F.Cu")
		(net 219)
	)
	(arc
		(start 157.363946 84.776079)
		(mid 157.320012 84.882146)
		(end 157.363947 84.988212)
		(width 0.15)
		(layer "F.Cu")
		(net 219)
	)
	(arc
		(start 156.303289 83.291156)
		(mid 156.409357 83.247223)
		(end 156.515424 83.291159)
		(width 0.15)
		(layer "F.Cu")
		(net 219)
	)
	(arc
		(start 157.576081 84.351816)
		(mid 157.620015 84.457882)
		(end 157.576081 84.563948)
		(width 0.15)
		(layer "F.Cu")
		(net 219)
	)
	(arc
		(start 153.121316 80.533449)
		(mid 153.077382 80.639516)
		(end 153.121317 80.745582)
		(width 0.15)
		(layer "F.Cu")
		(net 219)
	)
	(arc
		(start 153.333451 80.109186)
		(mid 153.377385 80.215252)
		(end 153.333451 80.321318)
		(width 0.15)
		(layer "F.Cu")
		(net 219)
	)
	(arc
		(start 151.424264 78.836397)
		(mid 151.38033 78.942464)
		(end 151.424265 79.04853)
		(width 0.15)
		(layer "F.Cu")
		(net 219)
	)
	(arc
		(start 157.576078 85.200343)
		(mid 157.682144 85.244277)
		(end 157.78821 85.200343)
		(width 0.15)
		(layer "F.Cu")
		(net 219)
	)
	(arc
		(start 154.181977 80.957712)
		(mid 154.225911 81.063778)
		(end 154.181977 81.169844)
		(width 0.15)
		(layer "F.Cu")
		(net 219)
	)
	(arc
		(start 152.060659 79.048526)
		(mid 152.166727 79.004593)
		(end 152.272794 79.048529)
		(width 0.15)
		(layer "F.Cu")
		(net 219)
	)
	(arc
		(start 158.848867 85.836734)
		(mid 158.954935 85.792801)
		(end 159.061002 85.836737)
		(width 0.15)
		(layer "F.Cu")
		(net 219)
	)
	(arc
		(start 156.727552 84.351817)
		(mid 156.833618 84.395751)
		(end 156.939684 84.351817)
		(width 0.15)
		(layer "F.Cu")
		(net 219)
	)
	(arc
		(start 152.484925 79.26066)
		(mid 152.528859 79.366726)
		(end 152.484925 79.472792)
		(width 0.15)
		(layer "F.Cu")
		(net 219)
	)
	(arc
		(start 159.697393 86.68526)
		(mid 159.803461 86.641327)
		(end 159.909528 86.685263)
		(width 0.15)
		(layer "F.Cu")
		(net 219)
	)
	(arc
		(start 153.757711 80.745578)
		(mid 153.863779 80.701645)
		(end 153.969846 80.745581)
		(width 0.15)
		(layer "F.Cu")
		(net 219)
	)
	(arc
		(start 151.636396 78.412132)
		(mid 151.68033 78.518198)
		(end 151.636396 78.624264)
		(width 0.15)
		(layer "F.Cu")
		(net 219)
	)
	(arc
		(start 152.27279 79.684923)
		(mid 152.228856 79.79099)
		(end 152.272791 79.897056)
		(width 0.15)
		(layer "F.Cu")
		(net 219)
	)
	(arc
		(start 155.666894 83.079027)
		(mid 155.62296 83.185094)
		(end 155.666895 83.29116)
		(width 0.15)
		(layer "F.Cu")
		(net 219)
	)
	(arc
		(start 155.454763 82.44263)
		(mid 155.560831 82.398697)
		(end 155.666898 82.442633)
		(width 0.15)
		(layer "F.Cu")
		(net 219)
	)
	(arc
		(start 153.333448 80.957713)
		(mid 153.439514 81.001647)
		(end 153.54558 80.957713)
		(width 0.15)
		(layer "F.Cu")
		(net 219)
	)
	(arc
		(start 158.212472 85.624605)
		(mid 158.168538 85.730672)
		(end 158.212473 85.836738)
		(width 0.15)
		(layer "F.Cu")
		(net 219)
	)
	(arc
		(start 155.030503 81.806238)
		(mid 155.074437 81.912304)
		(end 155.030503 82.01837)
		(width 0.15)
		(layer "F.Cu")
		(net 219)
	)
	(arc
		(start 154.606237 81.594104)
		(mid 154.712305 81.550171)
		(end 154.818372 81.594107)
		(width 0.15)
		(layer "F.Cu")
		(net 219)
	)
	(arc
		(start 151 78.2)
		(mid 151.106068 78.243935)
		(end 151.212133 78.199999)
		(width 0.15)
		(layer "F.Cu")
		(net 219)
	)
	(arc
		(start 159.27313 86.897395)
		(mid 159.379196 86.941329)
		(end 159.485262 86.897395)
		(width 0.15)
		(layer "F.Cu")
		(net 219)
	)
	(arc
		(start 153.969842 81.381975)
		(mid 153.925908 81.488042)
		(end 153.969843 81.594108)
		(width 0.15)
		(layer "F.Cu")
		(net 219)
	)
	(arc
		(start 158.000341 84.988208)
		(mid 158.106409 84.944275)
		(end 158.212476 84.988211)
		(width 0.15)
		(layer "F.Cu")
		(net 219)
	)
	(arc
		(start 158.424604 86.048869)
		(mid 158.53067 86.092803)
		(end 158.636736 86.048869)
		(width 0.15)
		(layer "F.Cu")
		(net 219)
	)
	(arc
		(start 159.060998 86.473131)
		(mid 159.017064 86.579198)
		(end 159.060999 86.685264)
		(width 0.15)
		(layer "F.Cu")
		(net 219)
	)
	(arc
		(start 159.273133 86.048868)
		(mid 159.317067 86.154934)
		(end 159.273133 86.261)
		(width 0.15)
		(layer "F.Cu")
		(net 219)
	)
	(arc
		(start 157.151815 84.139682)
		(mid 157.257883 84.095749)
		(end 157.36395 84.139685)
		(width 0.15)
		(layer "F.Cu")
		(net 219)
	)
	(arc
		(start 154.181974 81.806239)
		(mid 154.28804 81.850173)
		(end 154.394106 81.806239)
		(width 0.15)
		(layer "F.Cu")
		(net 219)
	)
	(arc
		(start 154.818368 82.230501)
		(mid 154.774434 82.336568)
		(end 154.818369 82.442634)
		(width 0.15)
		(layer "F.Cu")
		(net 219)
	)
	(arc
		(start 160.121659 86.897394)
		(mid 160.165593 87.00346)
		(end 160.121659 87.109526)
		(width 0.15)
		(layer "F.Cu")
		(net 219)
	)
	(arc
		(start 151.212132 78.2)
		(mid 151.318198 78.156066)
		(end 151.424264 78.2)
		(width 0.15)
		(layer "F.Cu")
		(net 219)
	)
	(arc
		(start 156.51542 83.927553)
		(mid 156.471486 84.03362)
		(end 156.515421 84.139686)
		(width 0.15)
		(layer "F.Cu")
		(net 219)
	)
	(segment
		(start 161.825 93.35)
		(end 161.825 92.775)
		(width 0.15)
		(layer "B.Cu")
		(net 219)
	)
	(segment
		(start 161.825 92.775)
		(end 161.9 92.7)
		(width 0.15)
		(layer "B.Cu")
		(net 219)
	)
	(segment
		(start 161.9 92.7)
		(end 161.9 93)
		(width 0.15)
		(layer "In3.Cu")
		(net 219)
	)
	(segment
		(start 161.2 93.7)
		(end 160.25 93.7)
		(width 0.15)
		(layer "In3.Cu")
		(net 219)
	)
	(segment
		(start 157.801491 96.148509)
		(end 157.801491 96.45)
		(width 0.15)
		(layer "In3.Cu")
		(net 219)
	)
	(segment
		(start 161.9 93)
		(end 161.2 93.7)
		(width 0.15)
		(layer "In3.Cu")
		(net 219)
	)
	(segment
		(start 160.25 93.7)
		(end 157.801491 96.148509)
		(width 0.15)
		(layer "In3.Cu")
		(net 219)
	)
	(segment
		(start 157.963429 84.022006)
		(end 157.963428 84.022007)
		(width 0.15)
		(layer "F.Cu")
		(net 220)
	)
	(segment
		(start 157.41542 83.721487)
		(end 157.468453 83.668453)
		(width 0.15)
		(layer "F.Cu")
		(net 220)
	)
	(segment
		(start 149.725 77.4)
		(end 149.725 77.275)
		(width 0.15)
		(layer "F.Cu")
		(net 220)
	)
	(segment
		(start 154.021316 80.327383)
		(end 154.074349 80.274349)
		(width 0.15)
		(layer "F.Cu")
		(net 220)
	)
	(segment
		(start 154.569324 80.627903)
		(end 154.445578 80.751645)
		(width 0.15)
		(layer "F.Cu")
		(net 220)
	)
	(segment
		(start 147.325 77.525)
		(end 147.325 77.4)
		(width 0.15)
		(layer "F.Cu")
		(net 220)
	)
	(segment
		(start 159.165505 85.365505)
		(end 159.236214 85.294793)
		(width 0.15)
		(layer "F.Cu")
		(net 220)
	)
	(segment
		(start 155.983534 81.900691)
		(end 156.266376 82.183533)
		(width 0.15)
		(layer "F.Cu")
		(net 220)
	)
	(segment
		(start 142.7 77.4)
		(end 143 77.4)
		(width 0.15)
		(layer "F.Cu")
		(net 220)
	)
	(segment
		(start 149.125 77.4)
		(end 149.125 77.525)
		(width 0.15)
		(layer "F.Cu")
		(net 220)
	)
	(segment
		(start 158.263946 84.570013)
		(end 158.316979 84.516979)
		(width 0.15)
		(layer "F.Cu")
		(net 220)
	)
	(segment
		(start 146.725 77.4)
		(end 146.725 77.525)
		(width 0.15)
		(layer "F.Cu")
		(net 220)
	)
	(segment
		(start 149.125 77.275)
		(end 149.125 77.4)
		(width 0.15)
		(layer "F.Cu")
		(net 220)
	)
	(segment
		(start 157.468453 83.668453)
		(end 157.539162 83.597741)
		(width 0.15)
		(layer "F.Cu")
		(net 220)
	)
	(segment
		(start 148.525 77.525)
		(end 148.525 77.4)
		(width 0.15)
		(layer "F.Cu")
		(net 220)
	)
	(segment
		(start 152.872273 78.93085)
		(end 152.872272 78.930851)
		(width 0.15)
		(layer "F.Cu")
		(net 220)
	)
	(segment
		(start 142.5 77.2)
		(end 142.7 77.4)
		(width 0.15)
		(layer "F.Cu")
		(net 220)
	)
	(segment
		(start 144.45 77.65)
		(end 144.8 77.65)
		(width 0.15)
		(layer "F.Cu")
		(net 220)
	)
	(segment
		(start 144.325 77.275)
		(end 144.325 77.4)
		(width 0.15)
		(layer "F.Cu")
		(net 220)
	)
	(segment
		(start 147.45 77.15)
		(end 147.8 77.15)
		(width 0.15)
		(layer "F.Cu")
		(net 220)
	)
	(segment
		(start 144.925 77.4)
		(end 144.925 77.275)
		(width 0.15)
		(layer "F.Cu")
		(net 220)
	)
	(segment
		(start 157.839682 84.251815)
		(end 158.15788 84.570013)
		(width 0.15)
		(layer "F.Cu")
		(net 220)
	)
	(segment
		(start 152.748527 79.16066)
		(end 152.748526 79.160659)
		(width 0.15)
		(layer "F.Cu")
		(net 220)
	)
	(segment
		(start 144.925 77.525)
		(end 144.925 77.4)
		(width 0.15)
		(layer "F.Cu")
		(net 220)
	)
	(segment
		(start 147.325 77.4)
		(end 147.325 77.275)
		(width 0.15)
		(layer "F.Cu")
		(net 220)
	)
	(segment
		(start 159.536735 85.948868)
		(end 159.536734 85.948867)
		(width 0.15)
		(layer "F.Cu")
		(net 220)
	)
	(segment
		(start 146.125 77.525)
		(end 146.125 77.4)
		(width 0.15)
		(layer "F.Cu")
		(net 220)
	)
	(segment
		(start 159.377638 85.294795)
		(end 159.66048 85.577637)
		(width 0.15)
		(layer "F.Cu")
		(net 220)
	)
	(segment
		(start 148.65 77.15)
		(end 149 77.15)
		(width 0.15)
		(layer "F.Cu")
		(net 220)
	)
	(segment
		(start 156.991157 83.40329)
		(end 156.991156 83.403289)
		(width 0.15)
		(layer "F.Cu")
		(net 220)
	)
	(segment
		(start 154.286482 80.203639)
		(end 154.569324 80.486481)
		(width 0.15)
		(layer "F.Cu")
		(net 220)
	)
	(segment
		(start 154.569325 80.627902)
		(end 154.569324 80.627903)
		(width 0.15)
		(layer "F.Cu")
		(net 220)
	)
	(segment
		(start 152.872272 78.930851)
		(end 152.748526 79.054593)
		(width 0.15)
		(layer "F.Cu")
		(net 220)
	)
	(segment
		(start 153.225823 79.425823)
		(end 153.296532 79.355111)
		(width 0.15)
		(layer "F.Cu")
		(net 220)
	)
	(segment
		(start 158.811954 84.870533)
		(end 158.688208 84.994275)
		(width 0.15)
		(layer "F.Cu")
		(net 220)
	)
	(segment
		(start 151.899999 78.206067)
		(end 151.9 78.206066)
		(width 0.15)
		(layer "F.Cu")
		(net 220)
	)
	(segment
		(start 158.688209 85.100342)
		(end 158.688208 85.100341)
		(width 0.15)
		(layer "F.Cu")
		(net 220)
	)
	(segment
		(start 157.114902 83.173481)
		(end 156.991156 83.297223)
		(width 0.15)
		(layer "F.Cu")
		(net 220)
	)
	(segment
		(start 154.445578 80.857711)
		(end 154.763776 81.175909)
		(width 0.15)
		(layer "F.Cu")
		(net 220)
	)
	(segment
		(start 154.869842 81.175909)
		(end 154.922875 81.122875)
		(width 0.15)
		(layer "F.Cu")
		(net 220)
	)
	(segment
		(start 143.725 77.525)
		(end 143.725 77.4)
		(width 0.15)
		(layer "F.Cu")
		(net 220)
	)
	(segment
		(start 157.839683 84.251816)
		(end 157.839682 84.251815)
		(width 0.15)
		(layer "F.Cu")
		(net 220)
	)
	(segment
		(start 151.9 78.312132)
		(end 152.218198 78.63033)
		(width 0.15)
		(layer "F.Cu")
		(net 220)
	)
	(segment
		(start 155.718368 82.024435)
		(end 155.771401 81.971401)
		(width 0.15)
		(layer "F.Cu")
		(net 220)
	)
	(segment
		(start 156.619927 82.819927)
		(end 156.690636 82.749215)
		(width 0.15)
		(layer "F.Cu")
		(net 220)
	)
	(segment
		(start 153.597052 80.009185)
		(end 153.91525 80.327383)
		(width 0.15)
		(layer "F.Cu")
		(net 220)
	)
	(segment
		(start 146.25 77.15)
		(end 146.6 77.15)
		(width 0.15)
		(layer "F.Cu")
		(net 220)
	)
	(segment
		(start 155.135008 81.052165)
		(end 155.41785 81.335007)
		(width 0.15)
		(layer "F.Cu")
		(net 220)
	)
	(segment
		(start 162.45 88.65)
		(end 162.45 92.7)
		(width 0.15)
		(layer "F.Cu")
		(net 220)
	)
	(segment
		(start 145.525 77.4)
		(end 145.525 77.525)
		(width 0.15)
		(layer "F.Cu")
		(net 220)
	)
	(segment
		(start 156.14263 82.554763)
		(end 156.460828 82.872961)
		(width 0.15)
		(layer "F.Cu")
		(net 220)
	)
	(segment
		(start 146.125 77.4)
		(end 146.125 77.275)
		(width 0.15)
		(layer "F.Cu")
		(net 220)
	)
	(segment
		(start 155.294104 81.706237)
		(end 155.612302 82.024435)
		(width 0.15)
		(layer "F.Cu")
		(net 220)
	)
	(segment
		(start 152.377297 78.577296)
		(end 152.448006 78.506585)
		(width 0.15)
		(layer "F.Cu")
		(net 220)
	)
	(segment
		(start 145.525 77.275)
		(end 145.525 77.4)
		(width 0.15)
		(layer "F.Cu")
		(net 220)
	)
	(segment
		(start 155.294105 81.706238)
		(end 155.294104 81.706237)
		(width 0.15)
		(layer "F.Cu")
		(net 220)
	)
	(segment
		(start 143.25 77.65)
		(end 143.6 77.65)
		(width 0.15)
		(layer "F.Cu")
		(net 220)
	)
	(segment
		(start 162.4625 93.35)
		(end 162.4625 92.7125)
		(width 0.15)
		(layer "F.Cu")
		(net 220)
	)
	(segment
		(start 152.748526 79.160659)
		(end 153.066724 79.478857)
		(width 0.15)
		(layer "F.Cu")
		(net 220)
	)
	(segment
		(start 141.8 77.2)
		(end 142.5 77.2)
		(width 0.15)
		(layer "F.Cu")
		(net 220)
	)
	(segment
		(start 157.114903 83.17348)
		(end 157.114902 83.173481)
		(width 0.15)
		(layer "F.Cu")
		(net 220)
	)
	(segment
		(start 152.58943 78.506587)
		(end 152.872272 78.789429)
		(width 0.15)
		(layer "F.Cu")
		(net 220)
	)
	(segment
		(start 153.720799 79.779376)
		(end 153.720798 79.779377)
		(width 0.15)
		(layer "F.Cu")
		(net 220)
	)
	(segment
		(start 156.266376 82.324955)
		(end 156.14263 82.448697)
		(width 0.15)
		(layer "F.Cu")
		(net 220)
	)
	(segment
		(start 141.475 77.2)
		(end 141.8 77.2)
		(width 0.09)
		(layer "F.Cu")
		(net 220)
	)
	(segment
		(start 159.66048 85.719059)
		(end 159.536734 85.842801)
		(width 0.15)
		(layer "F.Cu")
		(net 220)
	)
	(segment
		(start 147.925 77.4)
		(end 147.925 77.525)
		(width 0.15)
		(layer "F.Cu")
		(net 220)
	)
	(segment
		(start 158.811955 84.870532)
		(end 158.811954 84.870533)
		(width 0.15)
		(layer "F.Cu")
		(net 220)
	)
	(segment
		(start 153.17279 79.478857)
		(end 153.225823 79.425823)
		(width 0.15)
		(layer "F.Cu")
		(net 220)
	)
	(segment
		(start 154.074349 80.274349)
		(end 154.145058 80.203637)
		(width 0.15)
		(layer "F.Cu")
		(net 220)
	)
	(segment
		(start 149.725 77.525)
		(end 149.725 77.4)
		(width 0.15)
		(layer "F.Cu")
		(net 220)
	)
	(segment
		(start 144.325 77.4)
		(end 144.325 77.525)
		(width 0.15)
		(layer "F.Cu")
		(net 220)
	)
	(segment
		(start 156.142631 82.554764)
		(end 156.14263 82.554763)
		(width 0.15)
		(layer "F.Cu")
		(net 220)
	)
	(segment
		(start 145.65 77.65)
		(end 146 77.65)
		(width 0.15)
		(layer "F.Cu")
		(net 220)
	)
	(segment
		(start 159.660481 85.719058)
		(end 159.66048 85.719059)
		(width 0.15)
		(layer "F.Cu")
		(net 220)
	)
	(segment
		(start 156.83206 82.749217)
		(end 157.114902 83.032059)
		(width 0.15)
		(layer "F.Cu")
		(net 220)
	)
	(segment
		(start 156.266377 82.324954)
		(end 156.266376 82.324955)
		(width 0.15)
		(layer "F.Cu")
		(net 220)
	)
	(segment
		(start 156.566894 82.872961)
		(end 156.619927 82.819927)
		(width 0.15)
		(layer "F.Cu")
		(net 220)
	)
	(segment
		(start 155.417851 81.476428)
		(end 155.41785 81.476429)
		(width 0.15)
		(layer "F.Cu")
		(net 220)
	)
	(segment
		(start 157.680586 83.597743)
		(end 157.963428 83.880585)
		(width 0.15)
		(layer "F.Cu")
		(net 220)
	)
	(segment
		(start 154.922875 81.122875)
		(end 154.993584 81.052163)
		(width 0.15)
		(layer "F.Cu")
		(net 220)
	)
	(segment
		(start 149.85 77.15)
		(end 150.2 77.15)
		(width 0.15)
		(layer "F.Cu")
		(net 220)
	)
	(segment
		(start 159.112472 85.418539)
		(end 159.165505 85.365505)
		(width 0.15)
		(layer "F.Cu")
		(net 220)
	)
	(segment
		(start 153.720798 79.779377)
		(end 153.597052 79.903119)
		(width 0.15)
		(layer "F.Cu")
		(net 220)
	)
	(segment
		(start 153.597053 80.009186)
		(end 153.597052 80.009185)
		(width 0.15)
		(layer "F.Cu")
		(net 220)
	)
	(segment
		(start 155.771401 81.971401)
		(end 155.84211 81.900689)
		(width 0.15)
		(layer "F.Cu")
		(net 220)
	)
	(segment
		(start 143.85 77.15)
		(end 144.2 77.15)
		(width 0.15)
		(layer "F.Cu")
		(net 220)
	)
	(segment
		(start 141.075 77.6)
		(end 141.475 77.2)
		(width 0.09)
		(layer "F.Cu")
		(net 220)
	)
	(segment
		(start 153.437956 79.355113)
		(end 153.720798 79.637955)
		(width 0.15)
		(layer "F.Cu")
		(net 220)
	)
	(segment
		(start 146.85 77.65)
		(end 147.2 77.65)
		(width 0.15)
		(layer "F.Cu")
		(net 220)
	)
	(segment
		(start 160.067064 86.267065)
		(end 162.45 88.65)
		(width 0.15)
		(layer "F.Cu")
		(net 220)
	)
	(segment
		(start 143.725 77.4)
		(end 143.725 77.275)
		(width 0.15)
		(layer "F.Cu")
		(net 220)
	)
	(segment
		(start 146.725 77.275)
		(end 146.725 77.4)
		(width 0.15)
		(layer "F.Cu")
		(net 220)
	)
	(segment
		(start 157.963428 84.022007)
		(end 157.839682 84.145749)
		(width 0.15)
		(layer "F.Cu")
		(net 220)
	)
	(segment
		(start 155.41785 81.476429)
		(end 155.294104 81.600171)
		(width 0.15)
		(layer "F.Cu")
		(net 220)
	)
	(segment
		(start 147.925 77.275)
		(end 147.925 77.4)
		(width 0.15)
		(layer "F.Cu")
		(net 220)
	)
	(segment
		(start 162.4625 92.7125)
		(end 162.45 92.7)
		(width 0.15)
		(layer "F.Cu")
		(net 220)
	)
	(segment
		(start 151.2 77.4)
		(end 151.9 78.1)
		(width 0.15)
		(layer "F.Cu")
		(net 220)
	)
	(segment
		(start 158.529112 84.446269)
		(end 158.811954 84.729111)
		(width 0.15)
		(layer "F.Cu")
		(net 220)
	)
	(segment
		(start 150.45 77.4)
		(end 151.2 77.4)
		(width 0.15)
		(layer "F.Cu")
		(net 220)
	)
	(segment
		(start 156.991156 83.403289)
		(end 157.309354 83.721487)
		(width 0.15)
		(layer "F.Cu")
		(net 220)
	)
	(segment
		(start 152.324264 78.63033)
		(end 152.377297 78.577296)
		(width 0.15)
		(layer "F.Cu")
		(net 220)
	)
	(segment
		(start 154.445579 80.857712)
		(end 154.445578 80.857711)
		(width 0.15)
		(layer "F.Cu")
		(net 220)
	)
	(segment
		(start 145.05 77.15)
		(end 145.4 77.15)
		(width 0.15)
		(layer "F.Cu")
		(net 220)
	)
	(segment
		(start 148.525 77.4)
		(end 148.525 77.275)
		(width 0.15)
		(layer "F.Cu")
		(net 220)
	)
	(segment
		(start 158.316979 84.516979)
		(end 158.387688 84.446267)
		(width 0.15)
		(layer "F.Cu")
		(net 220)
	)
	(segment
		(start 159.536734 85.948867)
		(end 159.854932 86.267065)
		(width 0.15)
		(layer "F.Cu")
		(net 220)
	)
	(segment
		(start 158.688208 85.100341)
		(end 159.006406 85.418539)
		(width 0.15)
		(layer "F.Cu")
		(net 220)
	)
	(segment
		(start 149.25 77.65)
		(end 149.6 77.65)
		(width 0.15)
		(layer "F.Cu")
		(net 220)
	)
	(segment
		(start 148.05 77.65)
		(end 148.4 77.65)
		(width 0.15)
		(layer "F.Cu")
		(net 220)
	)
	(via
		(at 162.45 92.7)
		(size 0.4)
		(drill 0.2)
		(layers "F.Cu" "B.Cu")
		(net 220)
	)
	(via
		(at 158.300994 96.45)
		(size 0.4)
		(drill 0.2)
		(layers "F.Cu" "B.Cu")
		(net 220)
	)
	(arc
		(start 145.4 77.15)
		(mid 145.488388 77.186612)
		(end 145.525 77.275)
		(width 0.15)
		(layer "F.Cu")
		(net 220)
	)
	(arc
		(start 153.296532 79.355111)
		(mid 153.367245 79.325824)
		(end 153.437956 79.355113)
		(width 0.15)
		(layer "F.Cu")
		(net 220)
	)
	(arc
		(start 146.125 77.275)
		(mid 146.161612 77.186612)
		(end 146.25 77.15)
		(width 0.15)
		(layer "F.Cu")
		(net 220)
	)
	(arc
		(start 155.84211 81.900689)
		(mid 155.912823 81.871402)
		(end 155.983534 81.900691)
		(width 0.15)
		(layer "F.Cu")
		(net 220)
	)
	(arc
		(start 157.839682 84.145749)
		(mid 157.817715 84.198783)
		(end 157.839683 84.251816)
		(width 0.15)
		(layer "F.Cu")
		(net 220)
	)
	(arc
		(start 155.41785 81.335007)
		(mid 155.44714 81.405717)
		(end 155.417851 81.476428)
		(width 0.15)
		(layer "F.Cu")
		(net 220)
	)
	(arc
		(start 155.612302 82.024435)
		(mid 155.665335 82.046402)
		(end 155.718368 82.024435)
		(width 0.15)
		(layer "F.Cu")
		(net 220)
	)
	(arc
		(start 149.6 77.65)
		(mid 149.688388 77.613388)
		(end 149.725 77.525)
		(width 0.15)
		(layer "F.Cu")
		(net 220)
	)
	(arc
		(start 158.387688 84.446267)
		(mid 158.458401 84.41698)
		(end 158.529112 84.446269)
		(width 0.15)
		(layer "F.Cu")
		(net 220)
	)
	(arc
		(start 158.15788 84.570013)
		(mid 158.210913 84.59198)
		(end 158.263946 84.570013)
		(width 0.15)
		(layer "F.Cu")
		(net 220)
	)
	(arc
		(start 150.325 77.275)
		(mid 150.361612 77.363388)
		(end 150.45 77.4)
		(width 0.15)
		(layer "F.Cu")
		(net 220)
	)
	(arc
		(start 145.525 77.525)
		(mid 145.561612 77.613388)
		(end 145.65 77.65)
		(width 0.15)
		(layer "F.Cu")
		(net 220)
	)
	(arc
		(start 152.218198 78.63033)
		(mid 152.271231 78.652297)
		(end 152.324264 78.63033)
		(width 0.15)
		(layer "F.Cu")
		(net 220)
	)
	(arc
		(start 146.725 77.525)
		(mid 146.761612 77.613388)
		(end 146.85 77.65)
		(width 0.15)
		(layer "F.Cu")
		(net 220)
	)
	(arc
		(start 153.720798 79.637955)
		(mid 153.750088 79.708665)
		(end 153.720799 79.779376)
		(width 0.15)
		(layer "F.Cu")
		(net 220)
	)
	(arc
		(start 156.14263 82.448697)
		(mid 156.120663 82.501731)
		(end 156.142631 82.554764)
		(width 0.15)
		(layer "F.Cu")
		(net 220)
	)
	(arc
		(start 157.963428 83.880585)
		(mid 157.992718 83.951295)
		(end 157.963429 84.022006)
		(width 0.15)
		(layer "F.Cu")
		(net 220)
	)
	(arc
		(start 144.8 77.65)
		(mid 144.888388 77.613388)
		(end 144.925 77.525)
		(width 0.15)
		(layer "F.Cu")
		(net 220)
	)
	(arc
		(start 149 77.15)
		(mid 149.088388 77.186612)
		(end 149.125 77.275)
		(width 0.15)
		(layer "F.Cu")
		(net 220)
	)
	(arc
		(start 152.448006 78.506585)
		(mid 152.518719 78.477298)
		(end 152.58943 78.506587)
		(width 0.15)
		(layer "F.Cu")
		(net 220)
	)
	(arc
		(start 158.811954 84.729111)
		(mid 158.841244 84.799821)
		(end 158.811955 84.870532)
		(width 0.15)
		(layer "F.Cu")
		(net 220)
	)
	(arc
		(start 153.066724 79.478857)
		(mid 153.119757 79.500824)
		(end 153.17279 79.478857)
		(width 0.15)
		(layer "F.Cu")
		(net 220)
	)
	(arc
		(start 152.872272 78.789429)
		(mid 152.901562 78.860139)
		(end 152.872273 78.93085)
		(width 0.15)
		(layer "F.Cu")
		(net 220)
	)
	(arc
		(start 147.325 77.275)
		(mid 147.361612 77.186612)
		(end 147.45 77.15)
		(width 0.15)
		(layer "F.Cu")
		(net 220)
	)
	(arc
		(start 147.2 77.65)
		(mid 147.288388 77.613388)
		(end 147.325 77.525)
		(width 0.15)
		(layer "F.Cu")
		(net 220)
	)
	(arc
		(start 148.4 77.65)
		(mid 148.488388 77.613388)
		(end 148.525 77.525)
		(width 0.15)
		(layer "F.Cu")
		(net 220)
	)
	(arc
		(start 159.536734 85.842801)
		(mid 159.514767 85.895835)
		(end 159.536735 85.948868)
		(width 0.15)
		(layer "F.Cu")
		(net 220)
	)
	(arc
		(start 154.763776 81.175909)
		(mid 154.816809 81.197876)
		(end 154.869842 81.175909)
		(width 0.15)
		(layer "F.Cu")
		(net 220)
	)
	(arc
		(start 146 77.65)
		(mid 146.088388 77.613388)
		(end 146.125 77.525)
		(width 0.15)
		(layer "F.Cu")
		(net 220)
	)
	(arc
		(start 151.9 78.206066)
		(mid 151.878033 78.259099)
		(end 151.9 78.312132)
		(width 0.15)
		(layer "F.Cu")
		(net 220)
	)
	(arc
		(start 159.854932 86.267065)
		(mid 159.907965 86.289032)
		(end 159.960998 86.267065)
		(width 0.15)
		(layer "F.Cu")
		(net 220)
	)
	(arc
		(start 146.6 77.15)
		(mid 146.688388 77.186612)
		(end 146.725 77.275)
		(width 0.15)
		(layer "F.Cu")
		(net 220)
	)
	(arc
		(start 143.6 77.65)
		(mid 143.688388 77.613388)
		(end 143.725 77.525)
		(width 0.15)
		(layer "F.Cu")
		(net 220)
	)
	(arc
		(start 152.748526 79.054593)
		(mid 152.726559 79.107627)
		(end 152.748527 79.16066)
		(width 0.15)
		(layer "F.Cu")
		(net 220)
	)
	(arc
		(start 149.125 77.525)
		(mid 149.161612 77.613388)
		(end 149.25 77.65)
		(width 0.15)
		(layer "F.Cu")
		(net 220)
	)
	(arc
		(start 159.66048 85.577637)
		(mid 159.68977 85.648347)
		(end 159.660481 85.719058)
		(width 0.15)
		(layer "F.Cu")
		(net 220)
	)
	(arc
		(start 156.991156 83.297223)
		(mid 156.969189 83.350257)
		(end 156.991157 83.40329)
		(width 0.15)
		(layer "F.Cu")
		(net 220)
	)
	(arc
		(start 157.539162 83.597741)
		(mid 157.609875 83.568454)
		(end 157.680586 83.597743)
		(width 0.15)
		(layer "F.Cu")
		(net 220)
	)
	(arc
		(start 144.925 77.275)
		(mid 144.961612 77.186612)
		(end 145.05 77.15)
		(width 0.15)
		(layer "F.Cu")
		(net 220)
	)
	(arc
		(start 153.597052 79.903119)
		(mid 153.575085 79.956153)
		(end 153.597053 80.009186)
		(width 0.15)
		(layer "F.Cu")
		(net 220)
	)
	(arc
		(start 147.8 77.15)
		(mid 147.888388 77.186612)
		(end 147.925 77.275)
		(width 0.15)
		(layer "F.Cu")
		(net 220)
	)
	(arc
		(start 143.125 77.525)
		(mid 143.161612 77.613388)
		(end 143.25 77.65)
		(width 0.15)
		(layer "F.Cu")
		(net 220)
	)
	(arc
		(start 149.725 77.275)
		(mid 149.761612 77.186612)
		(end 149.85 77.15)
		(width 0.15)
		(layer "F.Cu")
		(net 220)
	)
	(arc
		(start 147.925 77.525)
		(mid 147.961612 77.613388)
		(end 148.05 77.65)
		(width 0.15)
		(layer "F.Cu")
		(net 220)
	)
	(arc
		(start 143.725 77.275)
		(mid 143.761612 77.186612)
		(end 143.85 77.15)
		(width 0.15)
		(layer "F.Cu")
		(net 220)
	)
	(arc
		(start 143 77.4)
		(mid 143.088388 77.436612)
		(end 143.125 77.525)
		(width 0.15)
		(layer "F.Cu")
		(net 220)
	)
	(arc
		(start 148.525 77.275)
		(mid 148.561612 77.186612)
		(end 148.65 77.15)
		(width 0.15)
		(layer "F.Cu")
		(net 220)
	)
	(arc
		(start 159.960998 86.267065)
		(mid 160.014031 86.245098)
		(end 160.067064 86.267065)
		(width 0.15)
		(layer "F.Cu")
		(net 220)
	)
	(arc
		(start 159.006406 85.418539)
		(mid 159.059439 85.440506)
		(end 159.112472 85.418539)
		(width 0.15)
		(layer "F.Cu")
		(net 220)
	)
	(arc
		(start 144.325 77.525)
		(mid 144.361612 77.613388)
		(end 144.45 77.65)
		(width 0.15)
		(layer "F.Cu")
		(net 220)
	)
	(arc
		(start 158.688208 84.994275)
		(mid 158.666241 85.047309)
		(end 158.688209 85.100342)
		(width 0.15)
		(layer "F.Cu")
		(net 220)
	)
	(arc
		(start 144.2 77.15)
		(mid 144.288388 77.186612)
		(end 144.325 77.275)
		(width 0.15)
		(layer "F.Cu")
		(net 220)
	)
	(arc
		(start 156.460828 82.872961)
		(mid 156.513861 82.894928)
		(end 156.566894 82.872961)
		(width 0.15)
		(layer "F.Cu")
		(net 220)
	)
	(arc
		(start 154.569324 80.486481)
		(mid 154.598614 80.557191)
		(end 154.569325 80.627902)
		(width 0.15)
		(layer "F.Cu")
		(net 220)
	)
	(arc
		(start 156.690636 82.749215)
		(mid 156.761349 82.719928)
		(end 156.83206 82.749217)
		(width 0.15)
		(layer "F.Cu")
		(net 220)
	)
	(arc
		(start 159.236214 85.294793)
		(mid 159.306927 85.265506)
		(end 159.377638 85.294795)
		(width 0.15)
		(layer "F.Cu")
		(net 220)
	)
	(arc
		(start 157.309354 83.721487)
		(mid 157.362387 83.743454)
		(end 157.41542 83.721487)
		(width 0.15)
		(layer "F.Cu")
		(net 220)
	)
	(arc
		(start 150.2 77.15)
		(mid 150.288388 77.186612)
		(end 150.325 77.275)
		(width 0.15)
		(layer "F.Cu")
		(net 220)
	)
	(arc
		(start 153.91525 80.327383)
		(mid 153.968283 80.34935)
		(end 154.021316 80.327383)
		(width 0.15)
		(layer "F.Cu")
		(net 220)
	)
	(arc
		(start 154.445578 80.751645)
		(mid 154.423611 80.804679)
		(end 154.445579 80.857712)
		(width 0.15)
		(layer "F.Cu")
		(net 220)
	)
	(arc
		(start 154.145058 80.203637)
		(mid 154.215771 80.17435)
		(end 154.286482 80.203639)
		(width 0.15)
		(layer "F.Cu")
		(net 220)
	)
	(arc
		(start 154.993584 81.052163)
		(mid 155.064297 81.022876)
		(end 155.135008 81.052165)
		(width 0.15)
		(layer "F.Cu")
		(net 220)
	)
	(arc
		(start 155.294104 81.600171)
		(mid 155.272137 81.653205)
		(end 155.294105 81.706238)
		(width 0.15)
		(layer "F.Cu")
		(net 220)
	)
	(arc
		(start 157.114902 83.032059)
		(mid 157.144192 83.102769)
		(end 157.114903 83.17348)
		(width 0.15)
		(layer "F.Cu")
		(net 220)
	)
	(arc
		(start 151.9 78.1)
		(mid 151.921967 78.153034)
		(end 151.899999 78.206067)
		(width 0.15)
		(layer "F.Cu")
		(net 220)
	)
	(arc
		(start 156.266376 82.183533)
		(mid 156.295666 82.254243)
		(end 156.266377 82.324954)
		(width 0.15)
		(layer "F.Cu")
		(net 220)
	)
	(segment
		(start 162.4625 92.7125)
		(end 162.45 92.7)
		(width 0.15)
		(layer "B.Cu")
		(net 220)
	)
	(segment
		(start 158.15 96.600994)
		(end 158.15 98.625)
		(width 0.15)
		(layer "B.Cu")
		(net 220)
	)
	(segment
		(start 158.300994 96.45)
		(end 158.15 96.600994)
		(width 0.15)
		(layer "B.Cu")
		(net 220)
	)
	(segment
		(start 162.4625 93.35)
		(end 162.4625 92.7125)
		(width 0.15)
		(layer "B.Cu")
		(net 220)
	)
	(segment
		(start 161.4 94.05)
		(end 162.45 93)
		(width 0.15)
		(layer "In3.Cu")
		(net 220)
	)
	(segment
		(start 158.300994 96.199006)
		(end 160.45 94.05)
		(width 0.15)
		(layer "In3.Cu")
		(net 220)
	)
	(segment
		(start 160.45 94.05)
		(end 161.4 94.05)
		(width 0.15)
		(layer "In3.Cu")
		(net 220)
	)
	(segment
		(start 158.300994 96.45)
		(end 158.300994 96.199006)
		(width 0.15)
		(layer "In3.Cu")
		(net 220)
	)
	(segment
		(start 162.45 93)
		(end 162.45 92.7)
		(width 0.15)
		(layer "In3.Cu")
		(net 220)
	)
	(segment
		(start 158.558399 87.239199)
		(end 158.558399 91.652084)
		(width 0.1016)
		(layer "F.Cu")
		(net 221)
	)
	(segment
		(start 158.4092 87.09)
		(end 158.558399 87.239199)
		(width 0.1016)
		(layer "F.Cu")
		(net 221)
	)
	(segment
		(start 159.552657 92.646342)
		(end 159.552657 92.857343)
		(width 0.1016)
		(layer "F.Cu")
		(net 221)
	)
	(segment
		(start 158.558399 91.652084)
		(end 159.552657 92.646342)
		(width 0.1016)
		(layer "F.Cu")
		(net 221)
	)
	(via
		(at 140.375 76.8)
		(size 0.4)
		(drill 0.15)
		(layers "F.Cu" "B.Cu")
		(net 221)
	)
	(via
		(at 158.4092 87.09)
		(size 0.4)
		(drill 0.2)
		(layers "F.Cu" "B.Cu")
		(net 221)
	)
	(via
		(at 159.552657 92.857343)
		(size 0.4)
		(drill 0.2)
		(layers "F.Cu" "B.Cu")
		(net 221)
	)
	(segment
		(start 159.763658 92.857343)
		(end 159.552657 92.857343)
		(width 0.1016)
		(layer "B.Cu")
		(net 221)
	)
	(segment
		(start 140.825 76.35)
		(end 140.87 76.35)
		(width 0.1016)
		(layer "B.Cu")
		(net 221)
	)
	(segment
		(start 158.558399 86.940801)
		(end 158.4092 87.09)
		(width 0.1016)
		(layer "B.Cu")
		(net 221)
	)
	(segment
		(start 159.135 80.065)
		(end 159.286601 80.065)
		(width 0.1016)
		(layer "B.Cu")
		(net 221)
	)
	(segment
		(start 142.2884 76.2016)
		(end 156.589046 76.2016)
		(width 0.1016)
		(layer "B.Cu")
		(net 221)
	)
	(segment
		(start 158.558399 78.170953)
		(end 158.558399 79.488399)
		(width 0.1016)
		(layer "B.Cu")
		(net 221)
	)
	(segment
		(start 160.15 97.246107)
		(end 160.0492 97.145307)
		(width 0.1016)
		(layer "B.Cu")
		(net 221)
	)
	(segment
		(start 158.033399 82.711798)
		(end 159.286601 82.711798)
		(width 0.1016)
		(layer "B.Cu")
		(net 221)
	)
	(segment
		(start 160.2984 93.392085)
		(end 159.763658 92.857343)
		(width 0.1016)
		(layer "B.Cu")
		(net 221)
	)
	(segment
		(start 160.15 98.625)
		(end 160.15 97.246107)
		(width 0.1016)
		(layer "B.Cu")
		(net 221)
	)
	(segment
		(start 158.558399 84.238399)
		(end 158.558399 86.940801)
		(width 0.1016)
		(layer "B.Cu")
		(net 221)
	)
	(segment
		(start 142.1392 76.3508)
		(end 142.2884 76.2016)
		(width 0.1016)
		(layer "B.Cu")
		(net 221)
	)
	(segment
		(start 160.0492 96.854693)
		(end 160.2984 96.605493)
		(width 0.1016)
		(layer "B.Cu")
		(net 221)
	)
	(segment
		(start 160.0492 97.145307)
		(end 160.0492 96.854693)
		(width 0.1016)
		(layer "B.Cu")
		(net 221)
	)
	(segment
		(start 158.033399 83.865)
		(end 158.185 83.865)
		(width 0.1016)
		(layer "B.Cu")
		(net 221)
	)
	(segment
		(start 140.87 76.35)
		(end 140.8708 76.3508)
		(width 0.1016)
		(layer "B.Cu")
		(net 221)
	)
	(segment
		(start 160.2984 96.605493)
		(end 160.2984 93.392085)
		(width 0.1016)
		(layer "B.Cu")
		(net 221)
	)
	(segment
		(start 158.033399 80.811798)
		(end 159.286601 80.811798)
		(width 0.1016)
		(layer "B.Cu")
		(net 221)
	)
	(segment
		(start 158.033399 81.965)
		(end 159.286601 81.965)
		(width 0.1016)
		(layer "B.Cu")
		(net 221)
	)
	(segment
		(start 140.8708 76.3508)
		(end 142.1392 76.3508)
		(width 0.1016)
		(layer "B.Cu")
		(net 221)
	)
	(segment
		(start 156.589046 76.2016)
		(end 158.558399 78.170953)
		(width 0.1016)
		(layer "B.Cu")
		(net 221)
	)
	(segment
		(start 140.375 76.8)
		(end 140.825 76.35)
		(width 0.1016)
		(layer "B.Cu")
		(net 221)
	)
	(arc
		(start 158.185 83.865)
		(mid 158.449033 83.974366)
		(end 158.558399 84.238399)
		(width 0.1016)
		(layer "B.Cu")
		(net 221)
	)
	(arc
		(start 157.456798 83.288399)
		(mid 157.625681 83.696117)
		(end 158.033399 83.865)
		(width 0.1016)
		(layer "B.Cu")
		(net 221)
	)
	(arc
		(start 159.66 82.338399)
		(mid 159.550634 82.602432)
		(end 159.286601 82.711798)
		(width 0.1016)
		(layer "B.Cu")
		(net 221)
	)
	(arc
		(start 158.033399 82.711798)
		(mid 157.625681 82.880681)
		(end 157.456798 83.288399)
		(width 0.1016)
		(layer "B.Cu")
		(net 221)
	)
	(arc
		(start 159.66 80.438399)
		(mid 159.550634 80.702432)
		(end 159.286601 80.811798)
		(width 0.1016)
		(layer "B.Cu")
		(net 221)
	)
	(arc
		(start 158.558399 79.488399)
		(mid 158.727282 79.896117)
		(end 159.135 80.065)
		(width 0.1016)
		(layer "B.Cu")
		(net 221)
	)
	(arc
		(start 157.456798 81.388399)
		(mid 157.625681 81.796117)
		(end 158.033399 81.965)
		(width 0.1016)
		(layer "B.Cu")
		(net 221)
	)
	(arc
		(start 159.286601 80.065)
		(mid 159.550634 80.174366)
		(end 159.66 80.438399)
		(width 0.1016)
		(layer "B.Cu")
		(net 221)
	)
	(arc
		(start 159.286601 81.965)
		(mid 159.550634 82.074366)
		(end 159.66 82.338399)
		(width 0.1016)
		(layer "B.Cu")
		(net 221)
	)
	(arc
		(start 158.033399 80.811798)
		(mid 157.625681 80.980681)
		(end 157.456798 81.388399)
		(width 0.1016)
		(layer "B.Cu")
		(net 221)
	)
	(segment
		(start 159.696342 92.502657)
		(end 159.907343 92.502657)
		(width 0.1016)
		(layer "F.Cu")
		(net 222)
	)
	(segment
		(start 158.761601 87.239199)
		(end 158.761601 91.567916)
		(width 0.1016)
		(layer "F.Cu")
		(net 222)
	)
	(segment
		(start 158.9108 87.09)
		(end 158.761601 87.239199)
		(width 0.1016)
		(layer "F.Cu")
		(net 222)
	)
	(segment
		(start 158.761601 91.567916)
		(end 159.696342 92.502657)
		(width 0.1016)
		(layer "F.Cu")
		(net 222)
	)
	(via
		(at 141.075 76)
		(size 0.4)
		(drill 0.15)
		(layers "F.Cu" "B.Cu")
		(net 222)
	)
	(via
		(at 158.9108 87.09)
		(size 0.4)
		(drill 0.2)
		(layers "F.Cu" "B.Cu")
		(net 222)
	)
	(via
		(at 159.907343 92.502657)
		(size 0.4)
		(drill 0.2)
		(layers "F.Cu" "B.Cu")
		(net 222)
	)
	(segment
		(start 159.907343 92.713658)
		(end 159.907343 92.502657)
		(width 0.1016)
		(layer "B.Cu")
		(net 222)
	)
	(segment
		(start 141.4258 75.6492)
		(end 141.9292 75.6492)
		(width 0.1016)
		(layer "B.Cu")
		(net 222)
	)
	(segment
		(start 144.6084 75.9984)
		(end 156.670954 75.9984)
		(width 0.1016)
		(layer "B.Cu")
		(net 222)
	)
	(segment
		(start 160.65 98.625)
		(end 160.65 97.246107)
		(width 0.1016)
		(layer "B.Cu")
		(net 222)
	)
	(segment
		(start 160.5016 96.605493)
		(end 160.5016 93.307915)
		(width 0.1016)
		(layer "B.Cu")
		(net 222)
	)
	(segment
		(start 156.670954 75.9984)
		(end 158.761601 78.089047)
		(width 0.1016)
		(layer "B.Cu")
		(net 222)
	)
	(segment
		(start 142.2784 75.9984)
		(end 143.8084 75.9984)
		(width 0.1016)
		(layer "B.Cu")
		(net 222)
	)
	(segment
		(start 160.7508 97.145307)
		(end 160.7508 96.854693)
		(width 0.1016)
		(layer "B.Cu")
		(net 222)
	)
	(segment
		(start 159.286601 82.915)
		(end 158.033399 82.915)
		(width 0.1016)
		(layer "B.Cu")
		(net 222)
	)
	(segment
		(start 144.5084 75.9984)
		(end 144.6084 75.9984)
		(width 0.1016)
		(layer "B.Cu")
		(net 222)
	)
	(segment
		(start 160.7508 96.854693)
		(end 160.5016 96.605493)
		(width 0.1016)
		(layer "B.Cu")
		(net 222)
	)
	(segment
		(start 160.65 97.246107)
		(end 160.7508 97.145307)
		(width 0.1016)
		(layer "B.Cu")
		(net 222)
	)
	(segment
		(start 160.5016 93.307915)
		(end 159.907343 92.713658)
		(width 0.1016)
		(layer "B.Cu")
		(net 222)
	)
	(segment
		(start 141.075 76)
		(end 141.4258 75.6492)
		(width 0.1016)
		(layer "B.Cu")
		(net 222)
	)
	(segment
		(start 158.761601 84.238399)
		(end 158.761601 86.940801)
		(width 0.1016)
		(layer "B.Cu")
		(net 222)
	)
	(segment
		(start 158.033399 83.661798)
		(end 158.185 83.661798)
		(width 0.1016)
		(layer "B.Cu")
		(net 222)
	)
	(segment
		(start 144.1084 75.6984)
		(end 144.2084 75.6984)
		(width 0.1016)
		(layer "B.Cu")
		(net 222)
	)
	(segment
		(start 158.761601 78.089047)
		(end 158.761601 79.488399)
		(width 0.1016)
		(layer "B.Cu")
		(net 222)
	)
	(segment
		(start 141.9292 75.6492)
		(end 142.2784 75.9984)
		(width 0.1016)
		(layer "B.Cu")
		(net 222)
	)
	(segment
		(start 159.135 79.861798)
		(end 159.286601 79.861798)
		(width 0.1016)
		(layer "B.Cu")
		(net 222)
	)
	(segment
		(start 158.761601 86.940801)
		(end 158.9108 87.09)
		(width 0.1016)
		(layer "B.Cu")
		(net 222)
	)
	(segment
		(start 159.286601 81.015)
		(end 158.033399 81.015)
		(width 0.1016)
		(layer "B.Cu")
		(net 222)
	)
	(segment
		(start 158.033399 81.761798)
		(end 159.286601 81.761798)
		(width 0.1016)
		(layer "B.Cu")
		(net 222)
	)
	(arc
		(start 157.66 83.288399)
		(mid 157.769366 83.552432)
		(end 158.033399 83.661798)
		(width 0.1016)
		(layer "B.Cu")
		(net 222)
	)
	(arc
		(start 158.185 83.661798)
		(mid 158.592718 83.830681)
		(end 158.761601 84.238399)
		(width 0.1016)
		(layer "B.Cu")
		(net 222)
	)
	(arc
		(start 158.033399 81.015)
		(mid 157.769366 81.124366)
		(end 157.66 81.388399)
		(width 0.1016)
		(layer "B.Cu")
		(net 222)
	)
	(arc
		(start 143.9584 75.8484)
		(mid 144.002334 75.742334)
		(end 144.1084 75.6984)
		(width 0.1016)
		(layer "B.Cu")
		(net 222)
	)
	(arc
		(start 159.286601 79.861798)
		(mid 159.694319 80.030681)
		(end 159.863202 80.438399)
		(width 0.1016)
		(layer "B.Cu")
		(net 222)
	)
	(arc
		(start 158.761601 79.488399)
		(mid 158.870967 79.752432)
		(end 159.135 79.861798)
		(width 0.1016)
		(layer "B.Cu")
		(net 222)
	)
	(arc
		(start 157.66 81.388399)
		(mid 157.769366 81.652432)
		(end 158.033399 81.761798)
		(width 0.1016)
		(layer "B.Cu")
		(net 222)
	)
	(arc
		(start 159.286601 81.761798)
		(mid 159.694319 81.930681)
		(end 159.863202 82.338399)
		(width 0.1016)
		(layer "B.Cu")
		(net 222)
	)
	(arc
		(start 143.8084 75.9984)
		(mid 143.914466 75.954466)
		(end 143.9584 75.8484)
		(width 0.1016)
		(layer "B.Cu")
		(net 222)
	)
	(arc
		(start 144.2084 75.6984)
		(mid 144.314466 75.742334)
		(end 144.3584 75.8484)
		(width 0.1016)
		(layer "B.Cu")
		(net 222)
	)
	(arc
		(start 158.033399 82.915)
		(mid 157.769366 83.024366)
		(end 157.66 83.288399)
		(width 0.1016)
		(layer "B.Cu")
		(net 222)
	)
	(arc
		(start 144.3584 75.8484)
		(mid 144.402334 75.954466)
		(end 144.5084 75.9984)
		(width 0.1016)
		(layer "B.Cu")
		(net 222)
	)
	(arc
		(start 159.863202 82.338399)
		(mid 159.694319 82.746117)
		(end 159.286601 82.915)
		(width 0.1016)
		(layer "B.Cu")
		(net 222)
	)
	(arc
		(start 159.863202 80.438399)
		(mid 159.694319 80.846117)
		(end 159.286601 81.015)
		(width 0.1016)
		(layer "B.Cu")
		(net 222)
	)
	(segment
		(start 154.015331 93.315)
		(end 154.4755 92.854831)
		(width 0.15)
		(layer "F.Cu")
		(net 223)
	)
	(segment
		(start 153.95 93.315)
		(end 154.015331 93.315)
		(width 0.15)
		(layer "F.Cu")
		(net 223)
	)
	(segment
		(start 151.8 84.6)
		(end 147.75 84.6)
		(width 0.15)
		(layer "F.Cu")
		(net 223)
	)
	(segment
		(start 145.825 84.475)
		(end 145.825 84.725)
		(width 0.15)
		(layer "F.Cu")
		(net 223)
	)
	(segment
		(start 145.1 84.35)
		(end 144.75 84.35)
		(width 0.15)
		(layer "F.Cu")
		(net 223)
	)
	(segment
		(start 153.95 91.5245)
		(end 153.95 86.75)
		(width 0.15)
		(layer "F.Cu")
		(net 223)
	)
	(segment
		(start 154.4755 92.05)
		(end 153.95 91.5245)
		(width 0.15)
		(layer "F.Cu")
		(net 223)
	)
	(segment
		(start 146.425 84.725)
		(end 146.425 84.475)
		(width 0.15)
		(layer "F.Cu")
		(net 223)
	)
	(segment
		(start 146.3 84.35)
		(end 145.95 84.35)
		(width 0.15)
		(layer "F.Cu")
		(net 223)
	)
	(segment
		(start 147.025 84.475)
		(end 147.025 84.725)
		(width 0.15)
		(layer "F.Cu")
		(net 223)
	)
	(segment
		(start 146.9 84.85)
		(end 146.55 84.85)
		(width 0.15)
		(layer "F.Cu")
		(net 223)
	)
	(segment
		(start 154.4755 92.854831)
		(end 154.4755 92.05)
		(width 0.15)
		(layer "F.Cu")
		(net 223)
	)
	(segment
		(start 144.5 84.9)
		(end 144.15 84.9)
		(width 0.15)
		(layer "F.Cu")
		(net 223)
	)
	(segment
		(start 144.625 84.475)
		(end 144.625 84.775)
		(width 0.15)
		(layer "F.Cu")
		(net 223)
	)
	(segment
		(start 145.7 84.85)
		(end 145.35 84.85)
		(width 0.15)
		(layer "F.Cu")
		(net 223)
	)
	(segment
		(start 143.9 84.6)
		(end 143.3511 84.6)
		(width 0.15)
		(layer "F.Cu")
		(net 223)
	)
	(segment
		(start 149.4 96.550497)
		(end 149.4 98.625)
		(width 0.15)
		(layer "F.Cu")
		(net 223)
	)
	(segment
		(start 145.225 84.725)
		(end 145.225 84.475)
		(width 0.15)
		(layer "F.Cu")
		(net 223)
	)
	(segment
		(start 153.95 86.75)
		(end 151.8 84.6)
		(width 0.15)
		(layer "F.Cu")
		(net 223)
	)
	(segment
		(start 147.5 84.35)
		(end 147.15 84.35)
		(width 0.15)
		(layer "F.Cu")
		(net 223)
	)
	(segment
		(start 144.025 84.775)
		(end 144.025 84.725)
		(width 0.15)
		(layer "F.Cu")
		(net 223)
	)
	(segment
		(start 149.299503 96.45)
		(end 149.4 96.550497)
		(width 0.15)
		(layer "F.Cu")
		(net 223)
	)
	(segment
		(start 143.3511 84.6)
		(end 143.35 84.6011)
		(width 0.15)
		(layer "F.Cu")
		(net 223)
	)
	(via
		(at 149.299503 96.45)
		(size 0.4)
		(drill 0.2)
		(layers "F.Cu" "B.Cu")
		(net 223)
	)
	(via
		(at 143.35 84.6011)
		(size 0.4)
		(drill 0.2)
		(layers "F.Cu" "B.Cu")
		(net 223)
	)
	(via
		(at 141.775 83.2)
		(size 0.4)
		(drill 0.15)
		(layers "F.Cu" "B.Cu")
		(net 223)
	)
	(via
		(at 154.4755 92.05)
		(size 0.4)
		(drill 0.2)
		(layers "F.Cu" "B.Cu")
		(net 223)
	)
	(arc
		(start 145.825 84.725)
		(mid 145.788388 84.813388)
		(end 145.7 84.85)
		(width 0.15)
		(layer "F.Cu")
		(net 223)
	)
	(arc
		(start 145.95 84.35)
		(mid 145.861612 84.386612)
		(end 145.825 84.475)
		(width 0.15)
		(layer "F.Cu")
		(net 223)
	)
	(arc
		(start 147.625 84.475)
		(mid 147.588388 84.386612)
		(end 147.5 84.35)
		(width 0.15)
		(layer "F.Cu")
		(net 223)
	)
	(arc
		(start 147.75 84.6)
		(mid 147.661612 84.563388)
		(end 147.625 84.475)
		(width 0.15)
		(layer "F.Cu")
		(net 223)
	)
	(arc
		(start 144.15 84.9)
		(mid 144.061612 84.863388)
		(end 144.025 84.775)
		(width 0.15)
		(layer "F.Cu")
		(net 223)
	)
	(arc
		(start 145.35 84.85)
		(mid 145.261612 84.813388)
		(end 145.225 84.725)
		(width 0.15)
		(layer "F.Cu")
		(net 223)
	)
	(arc
		(start 144.75 84.35)
		(mid 144.661612 84.386612)
		(end 144.625 84.475)
		(width 0.15)
		(layer "F.Cu")
		(net 223)
	)
	(arc
		(start 144.625 84.775)
		(mid 144.588388 84.863388)
		(end 144.5 84.9)
		(width 0.15)
		(layer "F.Cu")
		(net 223)
	)
	(arc
		(start 146.55 84.85)
		(mid 146.461612 84.813388)
		(end 146.425 84.725)
		(width 0.15)
		(layer "F.Cu")
		(net 223)
	)
	(arc
		(start 146.425 84.475)
		(mid 146.388388 84.386612)
		(end 146.3 84.35)
		(width 0.15)
		(layer "F.Cu")
		(net 223)
	)
	(arc
		(start 145.225 84.475)
		(mid 145.188388 84.386612)
		(end 145.1 84.35)
		(width 0.15)
		(layer "F.Cu")
		(net 223)
	)
	(arc
		(start 147.025 84.725)
		(mid 146.988388 84.813388)
		(end 146.9 84.85)
		(width 0.15)
		(layer "F.Cu")
		(net 223)
	)
	(arc
		(start 147.15 84.35)
		(mid 147.061612 84.386612)
		(end 147.025 84.475)
		(width 0.15)
		(layer "F.Cu")
		(net 223)
	)
	(arc
		(start 144.025 84.725)
		(mid 143.988388 84.636612)
		(end 143.9 84.6)
		(width 0.15)
		(layer "F.Cu")
		(net 223)
	)
	(segment
		(start 154.4755 92.05)
		(end 155.365 92.05)
		(width 0.15)
		(layer "B.Cu")
		(net 223)
	)
	(segment
		(start 155.365 92.05)
		(end 155.415 92)
		(width 0.15)
		(layer "B.Cu")
		(net 223)
	)
	(segment
		(start 143.35 84.6011)
		(end 143.1761 84.6011)
		(width 0.15)
		(layer "In3.Cu")
		(net 223)
	)
	(segment
		(start 154.4755 92.05)
		(end 154.4755 92.8245)
		(width 0.15)
		(layer "In3.Cu")
		(net 223)
	)
	(segment
		(start 154.4755 92.8245)
		(end 152.7 94.6)
		(width 0.15)
		(layer "In3.Cu")
		(net 223)
	)
	(segment
		(start 152.7 94.6)
		(end 151.95 94.6)
		(width 0.15)
		(layer "In3.Cu")
		(net 223)
	)
	(segment
		(start 150.249503 95.5)
		(end 149.299503 96.45)
		(width 0.15)
		(layer "In3.Cu")
		(net 223)
	)
	(segment
		(start 143.1761 84.6011)
		(end 141.775 83.2)
		(width 0.15)
		(layer "In3.Cu")
		(net 223)
	)
	(segment
		(start 151.95 94.6)
		(end 151.05 95.5)
		(width 0.15)
		(layer "In3.Cu")
		(net 223)
	)
	(segment
		(start 151.05 95.5)
		(end 150.249503 95.5)
		(width 0.15)
		(layer "In3.Cu")
		(net 223)
	)
	(segment
		(start 146.6 75.2)
		(end 147 75.2)
		(width 0.15)
		(layer "F.Cu")
		(net 224)
	)
	(segment
		(start 146 74.8)
		(end 146.4 74.8)
		(width 0.15)
		(layer "F.Cu")
		(net 224)
	)
	(segment
		(start 141.2 75.6)
		(end 140.075 75.6)
		(width 0.09)
		(layer "F.Cu")
		(net 224)
	)
	(segment
		(start 165.3125 92.7375)
		(end 165.3125 93.35)
		(width 0.15)
		(layer "F.Cu")
		(net 224)
	)
	(segment
		(start 149.6 74.8)
		(end 150 74.8)
		(width 0.15)
		(layer "F.Cu")
		(net 224)
	)
	(segment
		(start 165.35 87.55)
		(end 165.35 92.7)
		(width 0.15)
		(layer "F.Cu")
		(net 224)
	)
	(segment
		(start 148.3 75)
		(end 148.3 74.9)
		(width 0.15)
		(layer "F.Cu")
		(net 224)
	)
	(segment
		(start 152.8 75)
		(end 165.35 87.55)
		(width 0.15)
		(layer "F.Cu")
		(net 224)
	)
	(segment
		(start 160.9 98.625)
		(end 160.9 96.67216)
		(width 0.15)
		(layer "F.Cu")
		(net 224)
	)
	(segment
		(start 150.2 75)
		(end 152.8 75)
		(width 0.15)
		(layer "F.Cu")
		(net 224)
	)
	(segment
		(start 147.8 75.2)
		(end 148.2 75.2)
		(width 0.15)
		(layer "F.Cu")
		(net 224)
	)
	(segment
		(start 148.9 75)
		(end 148.9 75.1)
		(width 0.15)
		(layer "F.Cu")
		(net 224)
	)
	(segment
		(start 147.1 75)
		(end 147.1 74.9)
		(width 0.15)
		(layer "F.Cu")
		(net 224)
	)
	(segment
		(start 141.425 75.055025)
		(end 141.425 75.375)
		(width 0.09)
		(layer "F.Cu")
		(net 224)
	)
	(segment
		(start 147.7 75)
		(end 147.7 75.1)
		(width 0.15)
		(layer "F.Cu")
		(net 224)
	)
	(segment
		(start 160.9 96.67216)
		(end 161.035501 96.536659)
		(width 0.15)
		(layer "F.Cu")
		(net 224)
	)
	(segment
		(start 148.9 74.9)
		(end 148.9 75)
		(width 0.15)
		(layer "F.Cu")
		(net 224)
	)
	(segment
		(start 144.7 75)
		(end 144.7 74.9)
		(width 0.15)
		(layer "F.Cu")
		(net 224)
	)
	(segment
		(start 145.4 75.2)
		(end 145.8 75.2)
		(width 0.15)
		(layer "F.Cu")
		(net 224)
	)
	(segment
		(start 145.3 75)
		(end 145.3 75.1)
		(width 0.15)
		(layer "F.Cu")
		(net 224)
	)
	(segment
		(start 146.5 74.9)
		(end 146.5 75)
		(width 0.15)
		(layer "F.Cu")
		(net 224)
	)
	(segment
		(start 145.9 75)
		(end 145.9 74.9)
		(width 0.15)
		(layer "F.Cu")
		(net 224)
	)
	(segment
		(start 147.7 74.9)
		(end 147.7 75)
		(width 0.15)
		(layer "F.Cu")
		(net 224)
	)
	(segment
		(start 147.1 75.1)
		(end 147.1 75)
		(width 0.15)
		(layer "F.Cu")
		(net 224)
	)
	(segment
		(start 142.2 74.8)
		(end 142.4 75)
		(width 0.15)
		(layer "F.Cu")
		(net 224)
	)
	(segment
		(start 149.5 75.1)
		(end 149.5 75)
		(width 0.15)
		(layer "F.Cu")
		(net 224)
	)
	(segment
		(start 149 75.2)
		(end 149.4 75.2)
		(width 0.15)
		(layer "F.Cu")
		(net 224)
	)
	(segment
		(start 142.4 75)
		(end 144 75)
		(width 0.15)
		(layer "F.Cu")
		(net 224)
	)
	(segment
		(start 144.7 75.1)
		(end 144.7 75)
		(width 0.15)
		(layer "F.Cu")
		(net 224)
	)
	(segment
		(start 140.075 75.6)
		(end 139.675 76)
		(width 0.09)
		(layer "F.Cu")
		(net 224)
	)
	(segment
		(start 141.8 74.8)
		(end 142.2 74.8)
		(width 0.15)
		(layer "F.Cu")
		(net 224)
	)
	(segment
		(start 145.9 75.1)
		(end 145.9 75)
		(width 0.15)
		(layer "F.Cu")
		(net 224)
	)
	(segment
		(start 149.5 75)
		(end 149.5 74.9)
		(width 0.15)
		(layer "F.Cu")
		(net 224)
	)
	(segment
		(start 141.8 74.8)
		(end 141.680025 74.8)
		(width 0.09)
		(layer "F.Cu")
		(net 224)
	)
	(segment
		(start 146.5 75)
		(end 146.5 75.1)
		(width 0.15)
		(layer "F.Cu")
		(net 224)
	)
	(segment
		(start 145.3 74.9)
		(end 145.3 75)
		(width 0.15)
		(layer "F.Cu")
		(net 224)
	)
	(segment
		(start 144.8 74.8)
		(end 145.2 74.8)
		(width 0.15)
		(layer "F.Cu")
		(net 224)
	)
	(segment
		(start 147.2 74.8)
		(end 147.6 74.8)
		(width 0.15)
		(layer "F.Cu")
		(net 224)
	)
	(segment
		(start 165.35 92.7)
		(end 165.3125 92.7375)
		(width 0.15)
		(layer "F.Cu")
		(net 224)
	)
	(segment
		(start 141.425 75.375)
		(end 141.2 75.6)
		(width 0.09)
		(layer "F.Cu")
		(net 224)
	)
	(segment
		(start 148.4 74.8)
		(end 148.8 74.8)
		(width 0.15)
		(layer "F.Cu")
		(net 224)
	)
	(segment
		(start 144.2 75.2)
		(end 144.6 75.2)
		(width 0.15)
		(layer "F.Cu")
		(net 224)
	)
	(segment
		(start 148.3 75.1)
		(end 148.3 75)
		(width 0.15)
		(layer "F.Cu")
		(net 224)
	)
	(segment
		(start 141.680025 74.8)
		(end 141.425 75.055025)
		(width 0.09)
		(layer "F.Cu")
		(net 224)
	)
	(via
		(at 161.035501 96.536659)
		(size 0.4)
		(drill 0.2)
		(layers "F.Cu" "B.Cu")
		(net 224)
	)
	(via
		(at 165.35 92.7)
		(size 0.4)
		(drill 0.2)
		(layers "F.Cu" "B.Cu")
		(net 224)
	)
	(arc
		(start 148.8 74.8)
		(mid 148.870711 74.829289)
		(end 148.9 74.9)
		(width 0.15)
		(layer "F.Cu")
		(net 224)
	)
	(arc
		(start 144.7 74.9)
		(mid 144.729289 74.829289)
		(end 144.8 74.8)
		(width 0.15)
		(layer "F.Cu")
		(net 224)
	)
	(arc
		(start 146.5 75.1)
		(mid 146.529289 75.170711)
		(end 146.6 75.2)
		(width 0.15)
		(layer "F.Cu")
		(net 224)
	)
	(arc
		(start 149.4 75.2)
		(mid 149.470711 75.170711)
		(end 149.5 75.1)
		(width 0.15)
		(layer "F.Cu")
		(net 224)
	)
	(arc
		(start 145.3 75.1)
		(mid 145.329289 75.170711)
		(end 145.4 75.2)
		(width 0.15)
		(layer "F.Cu")
		(net 224)
	)
	(arc
		(start 144.1 75.1)
		(mid 144.129289 75.170711)
		(end 144.2 75.2)
		(width 0.15)
		(layer "F.Cu")
		(net 224)
	)
	(arc
		(start 146.4 74.8)
		(mid 146.470711 74.829289)
		(end 146.5 74.9)
		(width 0.15)
		(layer "F.Cu")
		(net 224)
	)
	(arc
		(start 149.5 74.9)
		(mid 149.529289 74.829289)
		(end 149.6 74.8)
		(width 0.15)
		(layer "F.Cu")
		(net 224)
	)
	(arc
		(start 145.8 75.2)
		(mid 145.870711 75.170711)
		(end 145.9 75.1)
		(width 0.15)
		(layer "F.Cu")
		(net 224)
	)
	(arc
		(start 144.6 75.2)
		(mid 144.670711 75.170711)
		(end 144.7 75.1)
		(width 0.15)
		(layer "F.Cu")
		(net 224)
	)
	(arc
		(start 150.1 74.9)
		(mid 150.129289 74.970711)
		(end 150.2 75)
		(width 0.15)
		(layer "F.Cu")
		(net 224)
	)
	(arc
		(start 147.1 74.9)
		(mid 147.129289 74.829289)
		(end 147.2 74.8)
		(width 0.15)
		(layer "F.Cu")
		(net 224)
	)
	(arc
		(start 150 74.8)
		(mid 150.070711 74.829289)
		(end 150.1 74.9)
		(width 0.15)
		(layer "F.Cu")
		(net 224)
	)
	(arc
		(start 148.3 74.9)
		(mid 148.329289 74.829289)
		(end 148.4 74.8)
		(width 0.15)
		(layer "F.Cu")
		(net 224)
	)
	(arc
		(start 145.2 74.8)
		(mid 145.270711 74.829289)
		(end 145.3 74.9)
		(width 0.15)
		(layer "F.Cu")
		(net 224)
	)
	(arc
		(start 148.9 75.1)
		(mid 148.929289 75.170711)
		(end 149 75.2)
		(width 0.15)
		(layer "F.Cu")
		(net 224)
	)
	(arc
		(start 145.9 74.9)
		(mid 145.929289 74.829289)
		(end 146 74.8)
		(width 0.15)
		(layer "F.Cu")
		(net 224)
	)
	(arc
		(start 147.6 74.8)
		(mid 147.670711 74.829289)
		(end 147.7 74.9)
		(width 0.15)
		(layer "F.Cu")
		(net 224)
	)
	(arc
		(start 147.7 75.1)
		(mid 147.729289 75.170711)
		(end 147.8 75.2)
		(width 0.15)
		(layer "F.Cu")
		(net 224)
	)
	(arc
		(start 147 75.2)
		(mid 147.070711 75.170711)
		(end 147.1 75.1)
		(width 0.15)
		(layer "F.Cu")
		(net 224)
	)
	(arc
		(start 144 75)
		(mid 144.070711 75.029289)
		(end 144.1 75.1)
		(width 0.15)
		(layer "F.Cu")
		(net 224)
	)
	(arc
		(start 148.2 75.2)
		(mid 148.270711 75.170711)
		(end 148.3 75.1)
		(width 0.15)
		(layer "F.Cu")
		(net 224)
	)
	(segment
		(start 165.3125 93.35)
		(end 165.3125 92.7375)
		(width 0.15)
		(layer "B.Cu")
		(net 224)
	)
	(segment
		(start 165.3125 92.7375)
		(end 165.35 92.7)
		(width 0.15)
		(layer "B.Cu")
		(net 224)
	)
	(segment
		(start 163.5 94.9)
		(end 165.35 93.05)
		(width 0.15)
		(layer "In3.Cu")
		(net 224)
	)
	(segment
		(start 161.035501 96.536659)
		(end 161.035501 96.368053)
		(width 0.15)
		(layer "In3.Cu")
		(net 224)
	)
	(segment
		(start 165.35 93.05)
		(end 165.35 92.7)
		(width 0.15)
		(layer "In3.Cu")
		(net 224)
	)
	(segment
		(start 161.035501 96.368053)
		(end 162.503554 94.9)
		(width 0.15)
		(layer "In3.Cu")
		(net 224)
	)
	(segment
		(start 162.503554 94.9)
		(end 163.5 94.9)
		(width 0.15)
		(layer "In3.Cu")
		(net 224)
	)
	(segment
		(start 161.9 98.625)
		(end 161.9 96.674835)
		(width 0.15)
		(layer "F.Cu")
		(net 225)
	)
	(segment
		(start 139.8 74.8)
		(end 139.375 74.8)
		(width 0.09)
		(layer "F.Cu")
		(net 225)
	)
	(segment
		(start 166.45 93.35)
		(end 166.45 92.7)
		(width 0.15)
		(layer "F.Cu")
		(net 225)
	)
	(segment
		(start 140.6 73.6)
		(end 142.132977 73.6)
		(width 0.15)
		(layer "F.Cu")
		(net 225)
	)
	(segment
		(start 140.025 74.175)
		(end 140.6 73.6)
		(width 0.15)
		(layer "F.Cu")
		(net 225)
	)
	(segment
		(start 140.025 74.575)
		(end 139.8 74.8)
		(width 0.09)
		(layer "F.Cu")
		(net 225)
	)
	(segment
		(start 140.025 74.225)
		(end 140.025 74.575)
		(width 0.09)
		(layer "F.Cu")
		(net 225)
	)
	(segment
		(start 153.6 73.8)
		(end 166.45 86.65)
		(width 0.15)
		(layer "F.Cu")
		(net 225)
	)
	(segment
		(start 142.132977 73.6)
		(end 142.332977 73.8)
		(width 0.15)
		(layer "F.Cu")
		(net 225)
	)
	(segment
		(start 142.332977 73.8)
		(end 153.6 73.8)
		(width 0.15)
		(layer "F.Cu")
		(net 225)
	)
	(segment
		(start 139.375 74.8)
		(end 138.975 75.2)
		(width 0.09)
		(layer "F.Cu")
		(net 225)
	)
	(segment
		(start 140.025 74.225)
		(end 140.025 74.175)
		(width 0.15)
		(layer "F.Cu")
		(net 225)
	)
	(segment
		(start 161.9 96.674835)
		(end 162.041289 96.533546)
		(width 0.15)
		(layer "F.Cu")
		(net 225)
	)
	(segment
		(start 166.45 86.65)
		(end 166.45 92.7)
		(width 0.15)
		(layer "F.Cu")
		(net 225)
	)
	(via
		(at 162.041289 96.533546)
		(size 0.4)
		(drill 0.2)
		(layers "F.Cu" "B.Cu")
		(net 225)
	)
	(via
		(at 166.45 92.7)
		(size 0.4)
		(drill 0.2)
		(layers "F.Cu" "B.Cu")
		(net 225)
	)
	(segment
		(start 166.45 93.35)
		(end 166.45 92.7)
		(width 0.15)
		(layer "B.Cu")
		(net 225)
	)
	(segment
		(start 166.45 93.15)
		(end 166.45 92.7)
		(width 0.15)
		(layer "In3.Cu")
		(net 225)
	)
	(segment
		(start 162.041289 96.533546)
		(end 162.041289 96.523403)
		(width 0.15)
		(layer "In3.Cu")
		(net 225)
	)
	(segment
		(start 163.064692 95.5)
		(end 164.1 95.5)
		(width 0.15)
		(layer "In3.Cu")
		(net 225)
	)
	(segment
		(start 162.041289 96.523403)
		(end 163.064692 95.5)
		(width 0.15)
		(layer "In3.Cu")
		(net 225)
	)
	(segment
		(start 164.1 95.5)
		(end 166.45 93.15)
		(width 0.15)
		(layer "In3.Cu")
		(net 225)
	)
	(segment
		(start 156.298096 77.639518)
		(end 156.439516 77.498095)
		(width 0.15)
		(layer "F.Cu")
		(net 226)
	)
	(segment
		(start 154.742462 75.659619)
		(end 155.06066 75.977817)
		(width 0.15)
		(layer "F.Cu")
		(net 226)
	)
	(segment
		(start 156.899137 77.957715)
		(end 156.757716 78.099137)
		(width 0.15)
		(layer "F.Cu")
		(net 226)
	)
	(segment
		(start 140.725 74.85)
		(end 140.725 74.212598)
		(width 0.09)
		(layer "F.Cu")
		(net 226)
	)
	(segment
		(start 157.500179 78.417336)
		(end 157.818377 78.735534)
		(width 0.15)
		(layer "F.Cu")
		(net 226)
	)
	(segment
		(start 155.060659 76.119237)
		(end 154.919238 76.260659)
		(width 0.15)
		(layer "F.Cu")
		(net 226)
	)
	(segment
		(start 157.818376 78.876955)
		(end 157.818376 78.876954)
		(width 0.15)
		(layer "F.Cu")
		(net 226)
	)
	(segment
		(start 154.919238 76.402081)
		(end 155.237436 76.720279)
		(width 0.15)
		(layer "F.Cu")
		(net 226)
	)
	(segment
		(start 140.725 74.212598)
		(end 140.743799 74.193799)
		(width 0.09)
		(layer "F.Cu")
		(net 226)
	)
	(segment
		(start 154.459619 75.801039)
		(end 154.459619 75.80104)
		(width 0.15)
		(layer "F.Cu")
		(net 226)
	)
	(segment
		(start 165.95 92.746902)
		(end 165.903098 92.7)
		(width 0.15)
		(layer "F.Cu")
		(net 226)
	)
	(segment
		(start 141.912402 74)
		(end 142.312402 74.4)
		(width 0.15)
		(layer "F.Cu")
		(net 226)
	)
	(segment
		(start 155.378857 76.720279)
		(end 155.520277 76.578856)
		(width 0.15)
		(layer "F.Cu")
		(net 226)
	)
	(segment
		(start 155.979898 77.038477)
		(end 155.979898 77.038476)
		(width 0.15)
		(layer "F.Cu")
		(net 226)
	)
	(segment
		(start 140.725 74.85)
		(end 140.375 75.2)
		(width 0.09)
		(layer "F.Cu")
		(net 226)
	)
	(segment
		(start 153.2 74.4)
		(end 154 75.2)
		(width 0.15)
		(layer "F.Cu")
		(net 226)
	)
	(segment
		(start 156.298096 77.639517)
		(end 156.298096 77.639518)
		(width 0.15)
		(layer "F.Cu")
		(net 226)
	)
	(segment
		(start 140.743799 74.193799)
		(end 140.937598 74)
		(width 0.15)
		(layer "F.Cu")
		(net 226)
	)
	(segment
		(start 155.661701 76.578858)
		(end 155.979899 76.897056)
		(width 0.15)
		(layer "F.Cu")
		(net 226)
	)
	(segment
		(start 156.757716 78.240559)
		(end 157.075914 78.558757)
		(width 0.15)
		(layer "F.Cu")
		(net 226)
	)
	(segment
		(start 156.899137 77.957716)
		(end 156.899137 77.957715)
		(width 0.15)
		(layer "F.Cu")
		(net 226)
	)
	(segment
		(start 157.217335 78.558757)
		(end 157.358755 78.417334)
		(width 0.15)
		(layer "F.Cu")
		(net 226)
	)
	(segment
		(start 154 75.482841)
		(end 154 75.482842)
		(width 0.15)
		(layer "F.Cu")
		(net 226)
	)
	(segment
		(start 155.979898 77.038476)
		(end 155.838477 77.179898)
		(width 0.15)
		(layer "F.Cu")
		(net 226)
	)
	(segment
		(start 155.060659 76.119238)
		(end 155.060659 76.119237)
		(width 0.15)
		(layer "F.Cu")
		(net 226)
	)
	(segment
		(start 156.58094 77.498097)
		(end 156.899138 77.816295)
		(width 0.15)
		(layer "F.Cu")
		(net 226)
	)
	(segment
		(start 165.95 93.35)
		(end 165.95 92.746902)
		(width 0.15)
		(layer "F.Cu")
		(net 226)
	)
	(segment
		(start 154 75.482842)
		(end 154.318198 75.80104)
		(width 0.15)
		(layer "F.Cu")
		(net 226)
	)
	(segment
		(start 140.937598 74)
		(end 141.912402 74)
		(width 0.15)
		(layer "F.Cu")
		(net 226)
	)
	(segment
		(start 157.818377 79.018376)
		(end 165.903098 87.103098)
		(width 0.15)
		(layer "F.Cu")
		(net 226)
	)
	(segment
		(start 155.378857 76.720278)
		(end 155.378857 76.720279)
		(width 0.15)
		(layer "F.Cu")
		(net 226)
	)
	(segment
		(start 154.459619 75.80104)
		(end 154.601038 75.659617)
		(width 0.15)
		(layer "F.Cu")
		(net 226)
	)
	(segment
		(start 165.903098 87.103098)
		(end 165.903098 92.7)
		(width 0.15)
		(layer "F.Cu")
		(net 226)
	)
	(segment
		(start 157.217335 78.558756)
		(end 157.217335 78.558757)
		(width 0.15)
		(layer "F.Cu")
		(net 226)
	)
	(segment
		(start 142.312402 74.4)
		(end 153.2 74.4)
		(width 0.15)
		(layer "F.Cu")
		(net 226)
	)
	(segment
		(start 155.838477 77.32132)
		(end 156.156675 77.639518)
		(width 0.15)
		(layer "F.Cu")
		(net 226)
	)
	(segment
		(start 157.818376 79.018374)
		(end 157.818377 79.018376)
		(width 0.15)
		(layer "F.Cu")
		(net 226)
	)
	(segment
		(start 153.999999 75.341421)
		(end 154 75.341421)
		(width 0.15)
		(layer "F.Cu")
		(net 226)
	)
	(via
		(at 161.542133 96.552158)
		(size 0.4)
		(drill 0.2)
		(layers "F.Cu" "B.Cu")
		(net 226)
	)
	(via
		(at 165.903098 92.7)
		(size 0.4)
		(drill 0.2)
		(layers "F.Cu" "B.Cu")
		(net 226)
	)
	(arc
		(start 156.899138 77.816295)
		(mid 156.928427 77.887006)
		(end 156.899137 77.957716)
		(width 0.15)
		(layer "F.Cu")
		(net 226)
	)
	(arc
		(start 157.818377 78.735534)
		(mid 157.847666 78.806245)
		(end 157.818376 78.876955)
		(width 0.15)
		(layer "F.Cu")
		(net 226)
	)
	(arc
		(start 155.237436 76.720279)
		(mid 155.308147 76.749568)
		(end 155.378857 76.720278)
		(width 0.15)
		(layer "F.Cu")
		(net 226)
	)
	(arc
		(start 154 75.341421)
		(mid 153.970711 75.412131)
		(end 154 75.482841)
		(width 0.15)
		(layer "F.Cu")
		(net 226)
	)
	(arc
		(start 156.757716 78.099137)
		(mid 156.728427 78.169848)
		(end 156.757716 78.240559)
		(width 0.15)
		(layer "F.Cu")
		(net 226)
	)
	(arc
		(start 157.818376 78.876954)
		(mid 157.789088 78.947665)
		(end 157.818376 79.018374)
		(width 0.15)
		(layer "F.Cu")
		(net 226)
	)
	(arc
		(start 154.919238 76.260659)
		(mid 154.889949 76.33137)
		(end 154.919238 76.402081)
		(width 0.15)
		(layer "F.Cu")
		(net 226)
	)
	(arc
		(start 155.979899 76.897056)
		(mid 156.009188 76.967767)
		(end 155.979898 77.038477)
		(width 0.15)
		(layer "F.Cu")
		(net 226)
	)
	(arc
		(start 155.520277 76.578856)
		(mid 155.59099 76.549569)
		(end 155.661701 76.578858)
		(width 0.15)
		(layer "F.Cu")
		(net 226)
	)
	(arc
		(start 155.838477 77.179898)
		(mid 155.809188 77.250609)
		(end 155.838477 77.32132)
		(width 0.15)
		(layer "F.Cu")
		(net 226)
	)
	(arc
		(start 156.156675 77.639518)
		(mid 156.227386 77.668807)
		(end 156.298096 77.639517)
		(width 0.15)
		(layer "F.Cu")
		(net 226)
	)
	(arc
		(start 154.601038 75.659617)
		(mid 154.671751 75.63033)
		(end 154.742462 75.659619)
		(width 0.15)
		(layer "F.Cu")
		(net 226)
	)
	(arc
		(start 157.075914 78.558757)
		(mid 157.146625 78.588046)
		(end 157.217335 78.558756)
		(width 0.15)
		(layer "F.Cu")
		(net 226)
	)
	(arc
		(start 154.318198 75.80104)
		(mid 154.388909 75.830329)
		(end 154.459619 75.801039)
		(width 0.15)
		(layer "F.Cu")
		(net 226)
	)
	(arc
		(start 157.358755 78.417334)
		(mid 157.429468 78.388047)
		(end 157.500179 78.417336)
		(width 0.15)
		(layer "F.Cu")
		(net 226)
	)
	(arc
		(start 156.439516 77.498095)
		(mid 156.510229 77.468808)
		(end 156.58094 77.498097)
		(width 0.15)
		(layer "F.Cu")
		(net 226)
	)
	(arc
		(start 155.06066 75.977817)
		(mid 155.089949 76.048528)
		(end 155.060659 76.119238)
		(width 0.15)
		(layer "F.Cu")
		(net 226)
	)
	(arc
		(start 154 75.2)
		(mid 154.029289 75.270711)
		(end 153.999999 75.341421)
		(width 0.15)
		(layer "F.Cu")
		(net 226)
	)
	(segment
		(start 165.95 92.746902)
		(end 165.903098 92.7)
		(width 0.15)
		(layer "B.Cu")
		(net 226)
	)
	(segment
		(start 165.95 93.35)
		(end 165.95 92.746902)
		(width 0.15)
		(layer "B.Cu")
		(net 226)
	)
	(segment
		(start 161.65 98.625)
		(end 161.65 96.660025)
		(width 0.15)
		(layer "B.Cu")
		(net 226)
	)
	(segment
		(start 161.65 96.660025)
		(end 161.542133 96.552158)
		(width 0.15)
		(layer "B.Cu")
		(net 226)
	)
	(segment
		(start 165.903098 92.7)
		(end 165.903098 93.096902)
		(width 0.15)
		(layer "In3.Cu")
		(net 226)
	)
	(segment
		(start 161.542133 96.457867)
		(end 161.542133 96.552158)
		(width 0.15)
		(layer "In3.Cu")
		(net 226)
	)
	(segment
		(start 165.903098 93.096902)
		(end 163.8 95.2)
		(width 0.15)
		(layer "In3.Cu")
		(net 226)
	)
	(segment
		(start 162.8 95.2)
		(end 161.542133 96.457867)
		(width 0.15)
		(layer "In3.Cu")
		(net 226)
	)
	(segment
		(start 163.8 95.2)
		(end 162.8 95.2)
		(width 0.15)
		(layer "In3.Cu")
		(net 226)
	)
	(segment
		(start 140.6 73.2)
		(end 154 73.2)
		(width 0.15)
		(layer "F.Cu")
		(net 227)
	)
	(segment
		(start 167 86.2)
		(end 167 92.7)
		(width 0.15)
		(layer "F.Cu")
		(net 227)
	)
	(segment
		(start 154 73.2)
		(end 167 86.2)
		(width 0.15)
		(layer "F.Cu")
		(net 227)
	)
	(segment
		(start 167.0875 92.7875)
		(end 167.0875 93.35)
		(width 0.15)
		(layer "F.Cu")
		(net 227)
	)
	(segment
		(start 139.675 74.125)
		(end 140.6 73.2)
		(width 0.15)
		(layer "F.Cu")
		(net 227)
	)
	(segment
		(start 139.675 74.4)
		(end 139.675 74.125)
		(width 0.15)
		(layer "F.Cu")
		(net 227)
	)
	(segment
		(start 167 92.7)
		(end 167.0875 92.7875)
		(width 0.15)
		(layer "F.Cu")
		(net 227)
	)
	(via
		(at 167 92.7)
		(size 0.4)
		(drill 0.2)
		(layers "F.Cu" "B.Cu")
		(net 227)
	)
	(via
		(at 162.55 96.545023)
		(size 0.4)
		(drill 0.2)
		(layers "F.Cu" "B.Cu")
		(net 227)
	)
	(segment
		(start 162.65 96.645023)
		(end 162.65 98.625)
		(width 0.15)
		(layer "B.Cu")
		(net 227)
	)
	(segment
		(start 167.0875 93.35)
		(end 167.0875 92.7875)
		(width 0.15)
		(layer "B.Cu")
		(net 227)
	)
	(segment
		(start 162.55 96.545023)
		(end 162.65 96.645023)
		(width 0.15)
		(layer "B.Cu")
		(net 227)
	)
	(segment
		(start 167.0875 92.7875)
		(end 167 92.7)
		(width 0.15)
		(layer "B.Cu")
		(net 227)
	)
	(segment
		(start 163.295023 95.8)
		(end 164.4 95.8)
		(width 0.15)
		(layer "In3.Cu")
		(net 227)
	)
	(segment
		(start 167 93.2)
		(end 167 92.7)
		(width 0.15)
		(layer "In3.Cu")
		(net 227)
	)
	(segment
		(start 162.55 96.545023)
		(end 163.295023 95.8)
		(width 0.15)
		(layer "In3.Cu")
		(net 227)
	)
	(segment
		(start 164.4 95.8)
		(end 167 93.2)
		(width 0.15)
		(layer "In3.Cu")
		(net 227)
	)
	(segment
		(start 105.6655 70.988)
		(end 105.6655 71.8655)
		(width 0.09)
		(layer "F.Cu")
		(net 228)
	)
	(segment
		(start 160.085 61.415)
		(end 160.05 61.45)
		(width 0.15)
		(layer "F.Cu")
		(net 228)
	)
	(segment
		(start 161.55 61.415)
		(end 160.085 61.415)
		(width 0.15)
		(layer "F.Cu")
		(net 228)
	)
	(segment
		(start 105.6655 71.8655)
		(end 105.7 71.9)
		(width 0.09)
		(layer "F.Cu")
		(net 228)
	)
	(via
		(at 160.05 61.45)
		(size 0.4)
		(drill 0.2)
		(layers "F.Cu" "B.Cu")
		(net 228)
	)
	(via
		(at 105.7 71.9)
		(size 0.4)
		(drill 0.15)
		(layers "F.Cu" "B.Cu")
		(net 228)
	)
	(segment
		(start 105.9 71.7)
		(end 106.25 71.7)
		(width 0.15)
		(layer "B.Cu")
		(net 228)
	)
	(segment
		(start 106.25 71.7)
		(end 106.55 72)
		(width 0.15)
		(layer "B.Cu")
		(net 228)
	)
	(segment
		(start 113.15 64.75)
		(end 113.15 63.65)
		(width 0.15)
		(layer "B.Cu")
		(net 228)
	)
	(segment
		(start 106.75 72.45)
		(end 107.25 72.45)
		(width 0.15)
		(layer "B.Cu")
		(net 228)
	)
	(segment
		(start 160 61.5)
		(end 160.05 61.45)
		(width 0.15)
		(layer "B.Cu")
		(net 228)
	)
	(segment
		(start 107.5 71)
		(end 109.05 69.45)
		(width 0.15)
		(layer "B.Cu")
		(net 228)
	)
	(segment
		(start 110.05 66.3)
		(end 111.6 66.3)
		(width 0.15)
		(layer "B.Cu")
		(net 228)
	)
	(segment
		(start 106.55 72)
		(end 106.55 72.25)
		(width 0.15)
		(layer "B.Cu")
		(net 228)
	)
	(segment
		(start 115 63.05)
		(end 115.3 63.35)
		(width 0.15)
		(layer "B.Cu")
		(net 228)
	)
	(segment
		(start 105.7 71.9)
		(end 105.9 71.7)
		(width 0.15)
		(layer "B.Cu")
		(net 228)
	)
	(segment
		(start 107.25 72.45)
		(end 107.5 72.2)
		(width 0.15)
		(layer "B.Cu")
		(net 228)
	)
	(segment
		(start 109.05 67.3)
		(end 110.05 66.3)
		(width 0.15)
		(layer "B.Cu")
		(net 228)
	)
	(segment
		(start 113.15 63.65)
		(end 113.75 63.05)
		(width 0.15)
		(layer "B.Cu")
		(net 228)
	)
	(segment
		(start 107.5 72.2)
		(end 107.5 71)
		(width 0.15)
		(layer "B.Cu")
		(net 228)
	)
	(segment
		(start 123.25 63.35)
		(end 125.1 61.5)
		(width 0.15)
		(layer "B.Cu")
		(net 228)
	)
	(segment
		(start 109.05 69.45)
		(end 109.05 67.3)
		(width 0.15)
		(layer "B.Cu")
		(net 228)
	)
	(segment
		(start 125.1 61.5)
		(end 160 61.5)
		(width 0.15)
		(layer "B.Cu")
		(net 228)
	)
	(segment
		(start 115.3 63.35)
		(end 123.25 63.35)
		(width 0.15)
		(layer "B.Cu")
		(net 228)
	)
	(segment
		(start 111.6 66.3)
		(end 113.15 64.75)
		(width 0.15)
		(layer "B.Cu")
		(net 228)
	)
	(segment
		(start 106.55 72.25)
		(end 106.75 72.45)
		(width 0.15)
		(layer "B.Cu")
		(net 228)
	)
	(segment
		(start 113.75 63.05)
		(end 115 63.05)
		(width 0.15)
		(layer "B.Cu")
		(net 228)
	)
	(zone
		(net 13)
		(net_name "+1V05")
		(layer "F.Cu")
		(hatch edge 0.508)
		(priority 2)
		(connect_pads yes
			(clearance 0.15)
		)
		(min_thickness 0.15)
		(filled_areas_thickness no)
		(fill yes
			(thermal_gap 0.508)
			(thermal_bridge_width 0.508)
		)
		(polygon
			(pts
				(xy 138.675 78.1) (xy 138.675 78.9) (xy 142.075 78.9) (xy 142.075 81.1) (xy 138.675 81.1) (xy 138.675 81.9)
				(xy 137.975 81.9) (xy 137.975 78.1)
			)
		)
	)
	(zone
		(net 10)
		(net_name "/Power supply/VOUT4")
		(layer "F.Cu")
		(hatch edge 0.508)
		(priority 1)
		(connect_pads yes
			(clearance 0.1)
		)
		(min_thickness 0.1)
		(filled_areas_thickness no)
		(fill yes
			(thermal_gap 0.508)
			(thermal_bridge_width 0.508)
		)
		(polygon
			(pts
				(xy 102.8125 69.825) (xy 100.6375 69.825) (xy 100.6375 72.025) (xy 104.1125 72.025) (xy 104.1125 69.225)
				(xy 102.8125 69.225)
			)
		)
	)
	(zone
		(net 1)
		(net_name "+1V1")
		(layer "F.Cu")
		(hatch edge 0.508)
		(priority 1)
		(connect_pads yes
			(clearance 0.1)
		)
		(min_thickness 0.254)
		(filled_areas_thickness no)
		(fill yes
			(thermal_gap 0.508)
			(thermal_bridge_width 0.508)
		)
		(polygon
			(pts
				(xy 102.3 76.2) (xy 110.2 76.2) (xy 110.2 77.9) (xy 100.7 77.9) (xy 100.7 72.6) (xy 102.3 72.6)
			)
		)
	)
	(zone
		(net 11)
		(net_name "/Power supply/VOUT")
		(layer "F.Cu")
		(hatch edge 0.508)
		(priority 2)
		(connect_pads yes
			(clearance 0.15)
		)
		(min_thickness 0.15)
		(filled_areas_thickness no)
		(fill yes
			(thermal_gap 0.508)
			(thermal_bridge_width 0.508)
		)
		(polygon
			(pts
				(xy 164.575 66.05) (xy 164.575 69.95) (xy 164.475 69.95) (xy 164.475 72.05) (xy 163.475 72.05) (xy 163.475 69.95)
				(xy 163.575 69.95) (xy 163.575 66.05)
			)
		)
	)
	(zone
		(net 13)
		(net_name "+1V05")
		(layer "F.Cu")
		(hatch edge 0.508)
		(priority 2)
		(connect_pads yes
			(clearance 0.15)
		)
		(min_thickness 0.15)
		(filled_areas_thickness no)
		(fill yes
			(thermal_gap 0.508)
			(thermal_bridge_width 0.508)
		)
		(polygon
			(pts
				(xy 133.775 82.1) (xy 133.775 81.3) (xy 134.475 81.3) (xy 134.475 78.7) (xy 133.775 78.7) (xy 133.775 77.9)
				(xy 133.075 77.9) (xy 133.075 77.3) (xy 133.775 77.3) (xy 133.8 71.85) (xy 135.8 71.85) (xy 135.775 77.3)
				(xy 136.475 77.3) (xy 136.475 77.9) (xy 135.775 77.9) (xy 135.775 78.8) (xy 135.075 78.8) (xy 135.075 81.2)
				(xy 135.775 81.2) (xy 135.775 82.1) (xy 136.475 82.1) (xy 136.475 82.7) (xy 135.775 82.7) (xy 135.775 88.625)
				(xy 133.775 88.625) (xy 133.775 82.7) (xy 133.075 82.7) (xy 133.075 82.1)
			)
		)
	)
	(zone
		(net 1)
		(net_name "+1V1")
		(layer "F.Cu")
		(hatch edge 0.508)
		(priority 1)
		(connect_pads yes
			(clearance 0.1)
		)
		(min_thickness 0.1)
		(filled_areas_thickness no)
		(fill yes
			(thermal_gap 0.508)
			(thermal_bridge_width 0.508)
		)
		(polygon
			(pts
				(xy 162.675 68.85) (xy 162.675 67.05) (xy 162.475 66.85) (xy 162.475 65.1) (xy 163.575 65.1) (xy 163.575 69.95)
				(xy 163.475 69.95) (xy 163.475 72.05) (xy 162.475 72.05) (xy 162.475 69.05)
			)
		)
	)
	(zone
		(net 13)
		(net_name "+1V05")
		(layer "F.Cu")
		(hatch edge 0.508)
		(priority 2)
		(connect_pads yes
			(clearance 0.15)
		)
		(min_thickness 0.15)
		(filled_areas_thickness no)
		(fill yes
			(thermal_gap 0.508)
			(thermal_bridge_width 0.508)
		)
		(polygon
			(pts
				(xy 130.875 81.9) (xy 130.875 81.1) (xy 127.475 81.1) (xy 127.475 78.9) (xy 130.875 78.9) (xy 130.875 78.1)
				(xy 131.575 78.1) (xy 131.575 81.9)
			)
		)
	)
	(zone
		(net 13)
		(net_name "+1V05")
		(layer "F.Cu")
		(hatch edge 0.508)
		(priority 4)
		(connect_pads yes
			(clearance 0.1)
		)
		(min_thickness 0.1)
		(filled_areas_thickness no)
		(fill yes
			(thermal_gap 0.508)
			(thermal_bridge_width 0.508)
		)
		(polygon
			(pts
				(xy 137.975 77.3) (xy 137.975 78.1) (xy 138.675 78.1) (xy 138.675 81.9) (xy 137.875 81.9) (xy 137.875 82.7)
				(xy 134.975 82.7) (xy 134.975 77.3)
			)
		)
	)
	(zone
		(net 9)
		(net_name "/Power supply/VOUT3")
		(layer "F.Cu")
		(hatch edge 0.508)
		(priority 1)
		(connect_pads yes
			(clearance 0.1)
		)
		(min_thickness 0.1)
		(filled_areas_thickness no)
		(fill yes
			(thermal_gap 0.508)
			(thermal_bridge_width 0.508)
		)
		(polygon
			(pts
				(xy 110.4875 69.825) (xy 113.9875 69.825) (xy 113.9875 72.025) (xy 109.1875 72.025) (xy 109.1875 69.225)
				(xy 110.4875 69.225)
			)
		)
	)
	(zone
		(net 13)
		(net_name "+1V05")
		(layer "F.Cu")
		(hatch edge 0.508)
		(priority 1)
		(connect_pads yes
			(clearance 0.1)
		)
		(min_thickness 0.1)
		(filled_areas_thickness no)
		(fill yes
			(thermal_gap 0.508)
			(thermal_bridge_width 0.508)
		)
		(polygon
			(pts
				(xy 135.8 70.9) (xy 135.8 72.3) (xy 133.925 72.3) (xy 133.4 71.775) (xy 130.375 71.775) (xy 130.15 72)
				(xy 114.5 72) (xy 114.5 69.85) (xy 114.725 69.65) (xy 134.55 69.65)
			)
		)
	)
	(zone
		(net 11)
		(net_name "/Power supply/VOUT")
		(layer "F.Cu")
		(hatch edge 0.508)
		(priority 2)
		(connect_pads yes
			(clearance 0.15)
		)
		(min_thickness 0.15)
		(filled_areas_thickness no)
		(fill yes
			(thermal_gap 0.508)
			(thermal_bridge_width 0.508)
		)
		(polygon
			(pts
				(xy 161.475 66.85) (xy 161.475 66.05) (xy 162.475 66.05) (xy 162.475 66.85) (xy 162.675 67.05) (xy 162.675 68.85)
				(xy 162.475 69.05) (xy 162.475 70.05) (xy 160.475 70.05) (xy 160.475 66.85)
			)
		)
	)
	(zone
		(net 5)
		(net_name "+5V")
		(layer "F.Cu")
		(hatch edge 0.508)
		(priority 1)
		(connect_pads yes
			(clearance 0.1)
		)
		(min_thickness 0.1)
		(filled_areas_thickness no)
		(fill yes
			(thermal_gap 0.508)
			(thermal_bridge_width 0.508)
		)
		(polygon
			(pts
				(xy 106.6875 72.5) (xy 106.6875 70.325) (xy 107.8875 70.325) (xy 107.8875 72.5) (xy 108.9875 72.5)
				(xy 108.9875 75.95) (xy 106.6875 75.95)
			)
		)
	)
	(zone
		(net 13)
		(net_name "+1V05")
		(layer "F.Cu")
		(hatch edge 0.508)
		(priority 4)
		(connect_pads yes
			(clearance 0.1)
		)
		(min_thickness 0.1)
		(filled_areas_thickness no)
		(fill yes
			(thermal_gap 0.508)
			(thermal_bridge_width 0.508)
		)
		(polygon
			(pts
				(xy 131.575 82.7) (xy 131.575 81.9) (xy 130.875 81.9) (xy 130.875 78.1) (xy 131.675 78.1) (xy 131.675 77.3)
				(xy 134.575 77.3) (xy 134.575 82.7)
			)
		)
	)
	(zone
		(net 5)
		(net_name "+5V")
		(layer "F.Cu")
		(hatch edge 0.508)
		(connect_pads yes
			(clearance 0.1)
		)
		(min_thickness 0.1)
		(filled_areas_thickness no)
		(fill yes
			(thermal_gap 0.508)
			(thermal_bridge_width 0.508)
		)
		(polygon
			(pts
				(xy 102.15 99.8) (xy 100.975 99.8) (xy 100.975 95.5) (xy 102.15 95.5)
			)
		)
	)
	(zone
		(net 4)
		(net_name "+0V5")
		(layer "F.Cu")
		(hatch edge 0.508)
		(priority 1)
		(connect_pads yes
			(clearance 0.1)
		)
		(min_thickness 0.1)
		(filled_areas_thickness no)
		(fill yes
			(thermal_gap 0.508)
			(thermal_bridge_width 0.508)
		)
		(polygon
			(pts
				(xy 160 66.7) (xy 160 69.9) (xy 157.5 69.9) (xy 157.5 66.7)
			)
		)
	)
	(zone
		(net 7)
		(net_name "/Power supply/VOUT1")
		(layer "F.Cu")
		(hatch edge 0.508)
		(priority 1)
		(connect_pads yes
			(clearance 0.1)
		)
		(min_thickness 0.1)
		(filled_areas_thickness no)
		(fill yes
			(thermal_gap 0.508)
			(thermal_bridge_width 0.508)
		)
		(polygon
			(pts
				(xy 104.05 63.425) (xy 103.05 63.425) (xy 103.05 60.3) (xy 105.35 60.3) (xy 105.35 65.325) (xy 104.05 65.325)
			)
		)
	)
	(zone
		(net 8)
		(net_name "/Power supply/VOUT2")
		(layer "F.Cu")
		(hatch edge 0.508)
		(priority 1)
		(connect_pads yes
			(clearance 0.1)
		)
		(min_thickness 0.1)
		(filled_areas_thickness no)
		(fill yes
			(thermal_gap 0.508)
			(thermal_bridge_width 0.508)
		)
		(polygon
			(pts
				(xy 109.25 63.425) (xy 110.25 63.425) (xy 110.25 60.3) (xy 107.95 60.3) (xy 107.95 65.325) (xy 109.25 65.325)
			)
		)
	)
	(zone
		(net 14)
		(net_name "GND")
		(layer "F.Cu")
		(hatch edge 0.508)
		(connect_pads yes
			(clearance 0.1)
		)
		(min_thickness 0.254)
		(filled_areas_thickness no)
		(fill yes
			(thermal_gap 0.508)
			(thermal_bridge_width 0.508)
		)
		(polygon
			(pts
				(xy 107.725 62.425) (xy 112.125 62.425) (xy 112.125 68.325) (xy 112.725 68.325) (xy 112.725 69.625)
				(xy 110.925 69.625) (xy 110.925 72.025) (xy 106.425 72.025) (xy 106.425 76.225) (xy 103.425 76.225)
				(xy 103.425 73.225) (xy 102.925 73.225) (xy 102.925 69.625) (xy 100.625 69.625) (xy 100.625 67.825)
				(xy 101.225 67.825) (xy 101.225 62.425) (xy 105.625 62.425) (xy 105.625 60.3) (xy 107.725 60.3)
			)
		)
	)
	(zone
		(net 14)
		(net_name "GND")
		(layers "F.Cu" "B.Cu")
		(hatch edge 0.508)
		(connect_pads yes
			(clearance 0.15)
		)
		(min_thickness 0.15)
		(filled_areas_thickness no)
		(fill yes
			(thermal_gap 0.508)
			(thermal_bridge_width 0.508)
		)
		(polygon
			(pts
				(xy 169.375 60.45) (xy 169.375 72.15) (xy 160.275 72.15) (xy 160.275 60.45)
			)
		)
	)
	(zone
		(net 4)
		(net_name "+0V5")
		(layer "B.Cu")
		(hatch edge 0.508)
		(priority 1)
		(connect_pads yes
			(clearance 0.1)
		)
		(min_thickness 0.1)
		(filled_areas_thickness no)
		(fill yes
			(thermal_gap 0.508)
			(thermal_bridge_width 0.508)
		)
		(polygon
			(pts
				(xy 160 71.4) (xy 137.8 71.4) (xy 137.2 72) (xy 132.4 72) (xy 132.4 69.8) (xy 136.35 66.6) (xy 160 66.6)
			)
		)
	)
	(zone
		(net 11)
		(net_name "/Power supply/VOUT")
		(layer "B.Cu")
		(hatch edge 0.508)
		(priority 1)
		(connect_pads yes
			(clearance 0.15)
		)
		(min_thickness 0.15)
		(filled_areas_thickness no)
		(fill yes
			(thermal_gap 0.508)
			(thermal_bridge_width 0.508)
		)
		(polygon
			(pts
				(xy 164.775 66.9) (xy 164.775 71.45) (xy 161.425 71.45) (xy 161.425 66.9)
			)
		)
	)
	(zone
		(net 4)
		(net_name "+0V5")
		(layer "B.Cu")
		(hatch edge 0.508)
		(connect_pads yes
			(clearance 0.1)
		)
		(min_thickness 0.1)
		(filled_areas_thickness no)
		(fill yes
			(thermal_gap 0.508)
			(thermal_bridge_width 0.508)
		)
		(polygon
			(pts
				(xy 128.475 73.6) (xy 128.475 75.080578) (xy 129.075 75.8) (xy 129.075 76.4) (xy 130.875 76.4) (xy 130.875 77)
				(xy 130.475 77.4) (xy 130.475 77.8) (xy 132.475 77.8) (xy 132.475 73.6)
			)
		)
	)
	(zone
		(net 4)
		(net_name "+0V5")
		(layer "B.Cu")
		(hatch edge 0.508)
		(connect_pads yes
			(clearance 0.1)
		)
		(min_thickness 0.1)
		(filled_areas_thickness no)
		(fill yes
			(thermal_gap 0.508)
			(thermal_bridge_width 0.508)
		)
		(polygon
			(pts
				(xy 137.2 86.4) (xy 132.4 86.4) (xy 132.4 72) (xy 137.2 72)
			)
		)
	)
	(zone
		(net 4)
		(net_name "+0V5")
		(layer "B.Cu")
		(hatch edge 0.508)
		(connect_pads yes
			(clearance 0.1)
		)
		(min_thickness 0.1)
		(filled_areas_thickness no)
		(fill yes
			(thermal_gap 0.508)
			(thermal_bridge_width 0.508)
		)
		(polygon
			(pts
				(xy 141.275 73.6) (xy 141.275 75.080578) (xy 140.224048 76.440289) (xy 138.675 76.4) (xy 138.675 77)
				(xy 139.275 77.4) (xy 139.275 77.8) (xy 137.075 77.8) (xy 137.075 73.6)
			)
		)
	)
	(zone
		(net 4)
		(net_name "+0V5")
		(layer "B.Cu")
		(hatch edge 0.508)
		(connect_pads yes
			(clearance 0.1)
		)
		(min_thickness 0.1)
		(filled_areas_thickness no)
		(fill yes
			(thermal_gap 0.508)
			(thermal_bridge_width 0.508)
		)
		(polygon
			(pts
				(xy 128.275 86.4) (xy 128.275 84.919422) (xy 129.325952 83.559711) (xy 130.875 83.6) (xy 130.875 83)
				(xy 130.275 82.6) (xy 130.275 82.2) (xy 132.475 82.2) (xy 132.475 86.4)
			)
		)
	)
	(zone
		(net 4)
		(net_name "+0V5")
		(layer "B.Cu")
		(hatch edge 0.508)
		(connect_pads yes
			(clearance 0.1)
		)
		(min_thickness 0.1)
		(filled_areas_thickness no)
		(fill yes
			(thermal_gap 0.508)
			(thermal_bridge_width 0.508)
		)
		(polygon
			(pts
				(xy 141.075 86.4) (xy 141.075 84.919422) (xy 140.475 84.2) (xy 140.475 83.6) (xy 138.675 83.6) (xy 138.675 83)
				(xy 139.075 82.6) (xy 139.075 82.2) (xy 137.075 82.2) (xy 137.075 86.4)
			)
		)
	)
	(zone
		(net 14)
		(net_name "GND")
		(layers "In1.Cu" "In2.Cu" "In4.Cu")
		(hatch edge 0.508)
		(connect_pads
			(clearance 0.15)
		)
		(min_thickness 0.15)
		(filled_areas_thickness no)
		(fill yes
			(thermal_gap 0.508)
			(thermal_bridge_width 0.508)
		)
		(polygon
			(pts
				(xy 169.575 99.95) (xy 99.975 99.95) (xy 99.975 59.95) (xy 169.575 59.95)
			)
		)
	)
	(zone
		(net 0)
		(net_name "")
		(layer "In2.Cu")
		(hatch edge 0.508)
		(connect_pads yes
			(clearance 0)
		)
		(min_thickness 0.254)
		(filled_areas_thickness no)
		(keepout
			(tracks allowed)
			(vias allowed)
			(pads allowed)
			(copperpour not_allowed)
			(footprints allowed)
		)
		(placement
			(enabled no)
			(sheetname "")
		)
		(fill
			(thermal_gap 0.508)
			(thermal_bridge_width 0.508)
		)
		(polygon
			(pts
				(xy 161.4 72.275) (xy 160.45 72.275) (xy 160.45 70.15) (xy 161.4 70.15)
			)
		)
	)
	(zone
		(net 1)
		(net_name "+1V1")
		(layer "In2.Cu")
		(hatch edge 0.508)
		(priority 1)
		(connect_pads yes
			(clearance 0.15)
		)
		(min_thickness 0.254)
		(filled_areas_thickness no)
		(fill yes
			(thermal_gap 0.508)
			(thermal_bridge_width 0.508)
		)
		(polygon
			(pts
				(xy 164.503245 72.135202) (xy 116.601301 72.22158) (xy 110.2 77.9) (xy 109.1 77.9) (xy 109.1 75.2)
				(xy 117.3 67) (xy 164.5 67)
			)
		)
	)
	(zone
		(net 12)
		(net_name "+0V9")
		(layer "In3.Cu")
		(hatch edge 0.508)
		(connect_pads yes
			(clearance 0.1)
		)
		(min_thickness 0.1)
		(filled_areas_thickness no)
		(fill yes
			(thermal_gap 0.508)
			(thermal_bridge_width 0.508)
		)
		(polygon
			(pts
				(xy 137.225 75.55) (xy 136.475 75.55) (xy 136.475 84.4) (xy 136.475 84.45) (xy 136.475 85.2) (xy 133.075 85.2)
				(xy 133.075 84.45) (xy 133.075 84.35) (xy 133.075 75.55) (xy 132.325 75.55) (xy 132.325 71.95) (xy 137.225 71.95)
			)
		)
	)
	(zone
		(net 5)
		(net_name "+5V")
		(layer "In3.Cu")
		(hatch edge 0.508)
		(connect_pads yes
			(clearance 0.1)
		)
		(min_thickness 0.1)
		(filled_areas_thickness no)
		(fill yes
			(thermal_gap 0.508)
			(thermal_bridge_width 0.508)
		)
		(polygon
			(pts
				(xy 109.025 77.95) (xy 103.875 77.95) (xy 103.875 97.275) (xy 100.975 97.275) (xy 100.975 95.45)
				(xy 100.975 93.95) (xy 100.975 76.2) (xy 107.3 76.2) (xy 107.3 73.7) (xy 109.025 73.7)
			)
		)
	)
	(zone
		(net 12)
		(net_name "+0V9")
		(layer "In4.Cu")
		(hatch edge 0.508)
		(priority 8)
		(connect_pads
			(clearance 0.1)
		)
		(min_thickness 0.1)
		(filled_areas_thickness no)
		(fill yes
			(thermal_gap 0.508)
			(thermal_bridge_width 0.508)
		)
		(polygon
			(pts
				(xy 128.8 79.2) (xy 132.4 79.2) (xy 132.4 77.6) (xy 134 77.6) (xy 134 75.6) (xy 132.4 75.6) (xy 132.4 74.8)
				(xy 137.2 74.8) (xy 137.2 75.6) (xy 135.6 75.6) (xy 135.6 77.6) (xy 137.2 77.6) (xy 137.2 79.2)
				(xy 140.6 79.2) (xy 140.6 78.175) (xy 141.125 78.175) (xy 141.575 78.625) (xy 144.525 78.625) (xy 144.525 81.775)
				(xy 144.15 81.775) (xy 143.775 81.4) (xy 141.575 81.4) (xy 141.175 81.8) (xy 141.05 81.8) (xy 140.6 81.35)
				(xy 140.6 80.8) (xy 138.2 80.8) (xy 137.2 80.8) (xy 137.2 82.4) (xy 135.6 82.4) (xy 135.6 84.4)
				(xy 136.6 84.4) (xy 136.6 85.2) (xy 133 85.2) (xy 133 84.4) (xy 134 84.4) (xy 134 82.4) (xy 132.4 82.4)
				(xy 132.4 80.8) (xy 128.8 80.8) (xy 128.8 81.6) (xy 128.725 81.675) (xy 128.3 81.675) (xy 128.25 81.5375)
				(xy 128.25 81.4) (xy 128.05 81.2) (xy 126.1 81.2) (xy 125.675 81.625) (xy 125.475 81.625) (xy 125.4 81.55)
				(xy 125.4 79.05) (xy 125.675 78.775) (xy 127.825 78.775) (xy 128.35 78.25) (xy 128.5 78.25) (xy 128.8 78.55)
			)
		)
	)
	(zone
		(net 12)
		(net_name "+0V9")
		(layer "In4.Cu")
		(hatch edge 0.508)
		(priority 2)
		(connect_pads yes
			(clearance 0.15)
		)
		(min_thickness 0.15)
		(filled_areas_thickness no)
		(fill yes
			(thermal_gap 0.508)
			(thermal_bridge_width 0.508)
		)
		(polygon
			(pts
				(xy 135.6 65.2) (xy 135.6 74.8) (xy 134 74.8) (xy 134 66) (xy 130 62) (xy 111.8 62) (xy 111.8 60)
				(xy 130.4 60)
			)
		)
	)
)
